G04 ================== begin FILE IDENTIFICATION RECORD ==================*
G04 Layout Name:  15126-1b.brd*
G04 Film Name:    L9GND*
G04 File Format:  Gerber RS274X*
G04 File Origin:  Cadence Allegro 16.6-2015-S079*
G04 Origin Date:  Fri Feb 10 17:22:46 2017*
G04 *
G04 Layer:  VIA CLASS/L9GND*
G04 Layer:  PIN/L9GND*
G04 Layer:  ETCH/L9GND*
G04 Layer:  DRAWING FORMAT/LAYER_PCB_STORY*
G04 Layer:  DRAWING FORMAT/LAYER_L9GND*
G04 *
G04 Offset:    (0.00 0.00)*
G04 Mirror:    No*
G04 Mode:      Positive*
G04 Rotation:  0*
G04 FullContactRelief:  No*
G04 UndefLineWidth:     6.00*
G04 ================== end FILE IDENTIFICATION RECORD ====================*
%FSLAX35Y35*MOIN*%
%IR0*IPPOS*OFA0.00000B0.00000*MIA0B0*SFA1.00000B1.00000*%
%ADD12C,.02*%
%ADD34C,.03*%
%ADD26C,.04*%
%ADD25C,.031*%
%ADD10C,.022*%
%ADD21C,.05*%
%ADD28C,.052*%
%ADD13C,.034*%
%ADD17C,.071*%
%ADD16C,.044*%
%ADD23C,.054*%
%ADD20C,.018*%
%ADD19C,.028*%
%ADD14C,.046*%
%ADD22C,.056*%
%ADD18C,.057*%
%ADD30O,.041X.06*%
%AMMACRO32*
4,1,48,.0225,.036,
.026668,.035635,
.030708,.034553,
.0345,.032785,
.037927,.030385,
.040885,.027427,
.043285,.024,
.045053,.020208,
.046135,.016168,
.0465,.012,
.046135,.007832,
.045053,.003792,
.043285,0.0,
.040885,-.003427,
.037927,-.006385,
.0345,-.008785,
.030708,-.010553,
.026668,-.011635,
.0225,-.012,
.0015,-.012,
.001135,-.016168,
.000053,-.020208,
-.001715,-.024,
-.004115,-.027427,
-.007073,-.030385,
-.0105,-.032785,
-.014292,-.034553,
-.018332,-.035635,
-.0225,-.036,
-.026668,-.035635,
-.030708,-.034553,
-.0345,-.032785,
-.037927,-.030385,
-.040885,-.027427,
-.043285,-.024,
-.045053,-.020208,
-.046135,-.016168,
-.0465,-.012,
-.0465,.012,
-.046135,.016168,
-.045053,.020208,
-.043285,.024,
-.040885,.027427,
-.037927,.030385,
-.0345,.032785,
-.030708,.034553,
-.026668,.035635,
-.0225,.036,
.0225,.036,
0.0*
%
%ADD32MACRO32*%
%ADD27O,.032X.036*%
%ADD15C,.14*%
%ADD33O,.094X.048*%
%ADD11C,.238*%
%ADD24C,.276*%
%ADD29O,.099X.048*%
%ADD35C,.01*%
%ADD36C,.006*%
%ADD79R,.05948X.06858*%
%ADD42O,.07202X.12102*%
%ADD54C,.03004*%
%ADD72C,.04004*%
%ADD63C,.03204*%
%ADD81C,.06104*%
%ADD58C,.07004*%
%ADD74C,.08004*%
%ADD66C,.06204*%
%ADD55C,.04404*%
%ADD68C,.07204*%
%ADD78C,.05504*%
%ADD69C,.06404*%
%ADD39C,.02804*%
%ADD77C,.06504*%
%ADD71C,.04704*%
%ADD60C,.07404*%
%ADD38C,.05604*%
%ADD80C,.05506*%
%ADD75C,.05704*%
%ADD73C,.09304*%
%ADD65C,.07504*%
%ADD57C,.08404*%
%ADD51C,.04804*%
%ADD43C,.0709*%
%ADD59C,.07604*%
%ADD76C,.06804*%
%ADD62C,.05904*%
%ADD53C,.08604*%
%ADD67C,.07804*%
%ADD49C,.07518*%
%ADD46C,.06943*%
%ADD48C,.11211*%
%ADD61C,.12104*%
%ADD52C,.11204*%
%ADD50C,.261*%
%ADD56C,.15004*%
%ADD41O,.15402X.21902*%
%ADD37C,.11404*%
%ADD47C,.11209*%
%ADD40O,.15404X.21904*%
%ADD44C,.15504*%
%ADD45C,.15506*%
%ADD70C,.28404*%
%ADD64C,.17804*%
G75*
%LPD*%
G75*
G36*
G01X1973300Y-60000D02*
X-19810D01*
Y-34500D01*
X1973300D01*
Y-60000D01*
G37*
G36*
G01X1972441Y434402D02*
X1922315D01*
G02X1921957Y434979I1J400D01*
G03X1919533Y436377I-1257J621D01*
G02X1918867I-333J222D01*
G03X1916533I-1167J-777D01*
G02X1915867I-333J222D01*
G03X1913443Y434979I-1167J-777D01*
G02X1913085Y434402I-359J-177D01*
G01X1703700D01*
Y434399D01*
X1685866D01*
G03X1680128Y428661I0J-5738D01*
G01Y428595D01*
X1680127Y428584D01*
G03X1680088Y427908I6448J-711D01*
G01Y306403D01*
G02X1679558Y306025I-400J0D01*
G03X1678129Y303689I-458J-1325D01*
G02Y303111I-277J-289D01*
G03Y301089I971J-1011D01*
G02Y300511I-277J-289D01*
G03X1678090Y298527I971J-1011D01*
G02Y297973I-288J-277D01*
G03Y296027I1010J-973D01*
G02Y295473I-288J-277D01*
G03Y293527I1010J-973D01*
G02Y292973I-288J-277D01*
G03Y291027I1010J-973D01*
G02Y290473I-288J-277D01*
G03X1678271Y288369I1010J-973D01*
G02Y287724I-236J-323D01*
G03X1678090Y285620I829J-1131D01*
G02Y285066I-288J-277D01*
G03Y283120I1010J-973D01*
G02Y282566I-288J-277D01*
G03X1678158Y280555I1010J-972D01*
G02Y279962I-269J-297D01*
G03X1678099Y277942I942J-1038D01*
G02Y277382I-285J-280D01*
G03X1678090Y275427I1001J-982D01*
G02Y274873I-288J-277D01*
G03X1678129Y272889I1010J-973D01*
G02Y272311I-277J-289D01*
G03X1679729Y270047I971J-1011D01*
G02X1680297Y269787I180J-357D01*
G03X1685866Y265440I5569J1394D01*
G01X1686519D01*
G03X1686577Y265438I253J6483D01*
G01X1846588D01*
Y265440D01*
X1870747D01*
G02X1871097Y264846I0J-400D01*
G03X1873549I1226J-679D01*
G02X1873899Y265440I350J194D01*
G01X1883780D01*
G02X1885913Y263307I0J-2133D01*
G01Y250709D01*
G03X1891654Y244968I5741J0D01*
G01X1912260D01*
G02X1912615Y244384I0J-400D01*
G03X1915459I1422J-738D01*
G02X1915814Y244968I355J184D01*
G01X1946598D01*
Y236102D01*
X1954390D01*
G03X1959543Y236615I2500J1024D01*
G02X1960225Y236815I393J-76D01*
G03X1959666Y239000I1665J1590D01*
G02X1958972Y238849I-386J104D01*
G03X1957693Y239706I-2081J-1723D01*
G01X1957552Y239750D01*
Y244968D01*
X1965840D01*
Y239440D01*
X1974574D01*
Y210008D01*
X1965840D01*
Y204006D01*
X1974574D01*
Y148894D01*
G02X1973986Y148541I-400J0D01*
G03Y146065I-658J-1238D01*
G02X1974574Y145712I188J-353D01*
G01Y144490D01*
G02X1973914Y144186I-400J0D01*
G03Y142054I-910J-1066D01*
G02X1974574Y141750I260J-304D01*
G01Y59055D01*
G02X1972441Y56922I-2133J0D01*
G01X1906889D01*
G03X1903117Y53150I1J-3773D01*
G01Y52762D01*
G02X1902520Y52414I-400J0D01*
G03X1897805Y48998I-1575J-2788D01*
G02X1897250Y48554I-392J-79D01*
G03Y42706I-1305J-2924D01*
G02X1897805Y42262I163J-365D01*
G03Y41006I3140J-628D01*
G02X1897250Y40562I-392J-79D01*
G03Y34714I-1305J-2924D01*
G02X1897805Y34270I163J-365D01*
G03Y33014I3140J-628D01*
G02X1897250Y32570I-392J-79D01*
G03Y26722I-1305J-2924D01*
G02X1897805Y26278I163J-365D01*
G03X1897829Y24913I3140J-628D01*
G02X1897269Y24459I-389J-92D01*
G03Y18849I-1324J-2805D01*
G02X1897829Y18395I171J-362D01*
G03X1897805Y17030I3116J-737D01*
G02X1897250Y16586I-392J-79D01*
G03Y10738I-1305J-2924D01*
G02X1897805Y10294I163J-365D01*
G03Y9038I3140J-628D01*
G02X1897250Y8594I-392J-79D01*
G03Y2746I-1305J-2924D01*
G02X1897805Y2302I163J-365D01*
G03Y1046I3140J-628D01*
G02X1897250Y602I-392J-79D01*
G03Y-5246I-1305J-2924D01*
G02X1897805Y-5690I163J-365D01*
G03X1902520Y-9106I3140J-628D01*
G02X1903117Y-9454I197J-348D01*
G01Y-9843D01*
G03X1906889Y-13615I3773J1D01*
G01X1972441D01*
G02X1974574Y-15748I0J-2133D01*
G01Y-19685D01*
G02X1972441Y-21818I-2133J0D01*
G01X1894747D01*
G02X1894378Y-21266I1J400D01*
G03X1891784I-1297J531D01*
G02X1891415Y-21818I-370J-152D01*
G01X658438D01*
G02X658076Y-21248I0J400D01*
G03X655538I-1269J596D01*
G02X655176Y-21818I-362J-170D01*
G01X69236D01*
G02X68865Y-21269I0J400D01*
G03X67065Y-19435I-1301J524D01*
G02X66532Y-19149I-143J374D01*
G03X64216Y-18423I-1368J-307D01*
G02X63622Y-18362I-270J295D01*
G03X63434Y-20217I-1136J-822D01*
G02X64028Y-20278I270J-295D01*
G03X65663Y-20766I1136J822D01*
G02X66196Y-21052I143J-374D01*
G03X66263Y-21269I1369J304D01*
G02X65892Y-21818I-371J-149D01*
G01X52233D01*
G02X51867Y-21256I0J400D01*
G03X49305I-1281J569D01*
G02X48939Y-21818I-366J-162D01*
G01X39768D01*
G02X39426Y-21211I0J400D01*
G03X37028I-1199J726D01*
G02X36686Y-21818I-342J-207D01*
G01X-19685D01*
G02X-21818Y-19685I0J2133D01*
G01Y622441D01*
G02X-19685Y624574I2133J0D01*
G01X385284D01*
G02X385658Y624033I0J-400D01*
G03X388282I1312J-494D01*
G02X388656Y624574I374J141D01*
G01X451663D01*
G02X452015Y623984I0J-400D01*
G03X454485I1235J-664D01*
G02X454837Y624574I352J190D01*
G01X455323D01*
G02X455675Y623984I0J-400D01*
G03X458145I1235J-664D01*
G02X458497Y624574I352J190D01*
G01X726329D01*
G02X726700Y624024I0J-400D01*
G03X729300I1300J-524D01*
G02X729671Y624574I371J150D01*
G01X1044829D01*
G02X1045200Y624024I0J-400D01*
G03X1047800I1300J-524D01*
G02X1048171Y624574I371J150D01*
G01X1550535D01*
G02X1550904Y624020I0J-400D01*
G03X1553492I1294J-541D01*
G02X1553861Y624574I369J154D01*
G01X1555881D01*
G02X1556257Y624038I0J-400D01*
G03X1558813Y622900I1318J-479D01*
G02X1559517Y622904I353J-188D01*
G03X1562070Y624041I1230J672D01*
G02X1562447Y624574I377J133D01*
G01X1564902D01*
G02X1565261Y623998I0J-400D01*
G03X1567673Y622584I1259J-616D01*
G02X1568333Y622580I329J-228D01*
G03X1570748Y623994I1162J784D01*
G02X1571105Y624574I357J180D01*
G01X1972441D01*
G02X1974574Y622441I0J-2133D01*
G01Y598567D01*
G02X1973913Y598264I-400J0D01*
G03Y596136I-913J-1064D01*
G02X1974574Y595833I261J-303D01*
G01Y566366D01*
G02X1973869Y566107I-400J0D01*
G03Y564293I-1069J-907D01*
G02X1974574Y564034I305J-259D01*
G01Y537966D01*
G02X1973869Y537707I-400J0D01*
G03Y535893I-1069J-907D01*
G02X1974574Y535634I305J-259D01*
G01Y436535D01*
G02X1972441Y434402I-2133J0D01*
G37*
G36*
G01X-20621Y661811D02*
G02X-19685Y662747I936J0D01*
G01X1972600D01*
Y637600D01*
X-20412D01*
G02X-20621Y638189I726J589D01*
G01Y661811D01*
G37*
%LPC*%
G75*
G36*
G01X1603820Y433694D02*
G02X1602241Y433668I-770J-1171D01*
G03X1602230Y434329I-231J327D01*
G02X1603809Y434355I770J1171D01*
G03X1603820Y433694I231J-327D01*
G37*
G36*
G01X1685017Y192029D02*
G02X1685249Y190205I1166J-778D01*
G03X1684650Y190129I-266J-298D01*
G02X1684418Y191953I-1166J778D01*
G03X1685017Y192029I266J298D01*
G37*
G36*
G01X1675832Y195852D02*
G03X1675197Y195838I-312J-250D01*
G02X1675158Y197545I-1131J828D01*
G03X1675793Y197559I312J250D01*
G02X1675832Y195852I1131J-828D01*
G37*
G36*
G01X1606022Y557644D02*
Y561645D01*
G02X1607233Y563125I1511J-1D01*
G03X1607452Y563785I-79J393D01*
G02X1616289Y570393I3831J4090D01*
G02X1611415Y562272I-5004J-2520D01*
G02X1609474Y562570I-133J5602D01*
G03X1608983Y562072I-108J-385D01*
G02X1609044Y561654I-1450J-425D01*
G01Y557559D01*
X1609035Y557475D01*
G02X1606022Y557644I-1502J169D01*
G37*
G36*
G01X1514847Y92931D02*
X1514848D01*
Y92928D01*
X1514846D01*
Y92924D01*
X1514847D01*
G02X1514846Y92853I-1512J-14D01*
G01Y92836D01*
X1514844Y92817D01*
G02X1511844Y92664I-1509J102D01*
G01X1511820Y92780D01*
Y92784D01*
X1511819D01*
X1511496Y96414D01*
X1511497D01*
Y96415D01*
X1511501Y96542D01*
G02X1512516Y97974I1512J4D01*
G02X1513224Y98044I499J-1427D01*
G02X1514519Y96682I-211J-1498D01*
G01X1514529Y96683D01*
X1514541Y96554D01*
X1514534D01*
X1514535Y96548D01*
X1514541D01*
X1514852Y93055D01*
X1514849Y93053D01*
X1514848D01*
X1514843Y93048D01*
X1514844Y93026D01*
G02X1514847Y92931I-1509J-95D01*
G37*
G36*
G01X1756912Y37661D02*
Y37615D01*
X1756908Y37577D01*
G02X1754912Y36269I-1507J123D01*
G01X1754909Y36259D01*
X1751506Y37425D01*
Y37430D01*
X1751440Y37460D01*
G02X1751250Y37551I557J1406D01*
G03X1751065Y37198I-78J-184D01*
G02X1751762Y35935I-815J-1273D01*
G01Y35840D01*
X1751752Y35756D01*
G02X1750250Y34414I-1502J170D01*
G01X1746550D01*
G02X1745673Y37156I0J1511D01*
G03X1745687Y37796I-233J325D01*
G02X1747684Y38073I865J1104D01*
G03X1748006Y37436I323J-237D01*
G01X1750251D01*
G02X1750363Y37432I2J-1511D01*
G03X1750741Y38027I29J399D01*
G02X1752488Y40296I1260J837D01*
G01X1752491Y40306D01*
X1755896Y39140D01*
Y39138D01*
X1756013Y39082D01*
G02X1756350Y38877I-611J-1383D01*
G01Y38876D01*
G02X1756360Y38868I-939J-1184D01*
G01X1756362D01*
G02X1756912Y37710I-963J-1167D01*
G01Y37702D01*
G02Y37661I-1512J-20D01*
G37*
G36*
G01X1379160Y237101D02*
G02Y237065I-2100J-18D01*
G02X1378760Y237069I-200J2D01*
G03Y237097I-1700J14D01*
G02X1379160Y237101I200J2D01*
G37*
G36*
G01X1335573Y235364D02*
G02Y235328I-2100J-18D01*
G02X1335173Y235332I-200J2D01*
G03Y235360I-1700J14D01*
G02X1335573Y235364I200J2D01*
G37*
G36*
G01X1357825Y233739D02*
G02Y233703I-2100J-18D01*
G02X1357425Y233707I-200J2D01*
G03Y233735I-1700J14D01*
G02X1357825Y233739I200J2D01*
G37*
G36*
G01X46800Y261036D02*
X57864Y272100D01*
X74936D01*
X80000Y267036D01*
Y222564D01*
X75736Y218300D01*
X50964D01*
X46800Y222464D01*
Y261036D01*
G37*
G36*
G01X1951554Y127860D02*
X1958054D01*
G02Y112456I0J-7702D01*
G01X1951554D01*
G02Y127860I0J7702D01*
G37*
G36*
G01X1833443D02*
X1839943D01*
G02Y112456I0J-7702D01*
G01X1833443D01*
G02Y127860I0J7702D01*
G37*
G36*
G01X1857035Y602728D02*
X1854331D01*
G02Y618532I1J7902D01*
G01X1857044D01*
G03X1860510Y619640I-2J5982D01*
G02X1860511Y601620I7622J-9010D01*
G03X1857035Y602728I-3476J-4898D01*
G37*
G36*
G01Y-15776D02*
X1854331D01*
G02Y28I1J7902D01*
G01X1857044D01*
G03X1860510Y1136I-2J5982D01*
G02X1860511Y-16884I7622J-9010D01*
G03X1857035Y-15776I-3476J-4898D01*
G37*
G36*
G01X1684261Y616623D02*
X1687214Y611111D01*
G02X1683070Y608889I-2072J-1111D01*
G01X1680117Y614401D01*
G02X1684261Y616623I2072J1111D01*
G37*
G36*
G01Y601662D02*
X1687214Y596150D01*
G02X1683070Y593928I-2072J-1111D01*
G01X1680117Y599440D01*
G02X1684261Y601662I2072J1111D01*
G37*
G36*
G01X1675404Y616622D02*
X1678356Y611110D01*
G02X1674210Y608890I-2073J-1110D01*
G01X1671258Y614402D01*
G02X1675404Y616622I2073J1110D01*
G37*
G36*
G01Y601661D02*
X1678356Y596149D01*
G02X1674210Y593929I-2073J-1110D01*
G01X1671258Y599441D01*
G02X1675404Y601661I2073J1110D01*
G37*
G36*
G01X1408216Y602728D02*
X1405512D01*
G02Y618532I1J7902D01*
G01X1408225D01*
G03X1411691Y619640I-2J5982D01*
G02X1411692Y601620I7622J-9010D01*
G03X1408216Y602728I-3476J-4898D01*
G37*
G36*
G01Y-15776D02*
X1405512D01*
G02Y28I1J7902D01*
G01X1408225D01*
G03X1411691Y1136I-2J5982D01*
G02X1411692Y-16884I7622J-9010D01*
G03X1408216Y-15776I-3476J-4898D01*
G37*
G36*
G01X679869Y602728D02*
X677165D01*
G02Y618532I1J7902D01*
G01X679878D01*
G03X683344Y619640I-2J5982D01*
G02X683345Y601620I7622J-9010D01*
G03X679869Y602728I-3476J-4898D01*
G37*
G36*
G01Y-15776D02*
X677165D01*
G02Y28I1J7902D01*
G01X679878D01*
G03X683344Y1136I-2J5982D01*
G02X683345Y-16884I7622J-9010D01*
G03X679869Y-15776I-3476J-4898D01*
G37*
G36*
G01X2704Y602728D02*
X0D01*
G02Y618532I1J7902D01*
G01X2713D01*
G03X6179Y619640I-2J5982D01*
G02X6180Y601620I7622J-9010D01*
G03X2704Y602728I-3476J-4898D01*
G37*
G36*
G01X1313465Y618530D02*
G03X1312887I-289J-277D01*
G02Y620472I-1011J971D01*
G03X1313465I289J277D01*
G02Y618530I1011J-971D01*
G37*
G36*
G01X1591926Y619723D02*
G03X1592512Y619711I299J266D01*
G02X1592474Y617801I1007J-975D01*
G03X1591888Y617813I-299J-266D01*
G02X1591926Y619723I-1007J975D01*
G37*
G36*
G01X1602539Y617279D02*
G03X1601961I-289J-277D01*
G02Y619221I-1011J971D01*
G03X1602539I289J277D01*
G02Y617279I1011J-971D01*
G37*
G36*
G01X1962583Y618411D02*
G03Y617789I252J-311D01*
G02X1960817I-883J-1089D01*
G03Y618411I-252J311D01*
G02X1962583I883J1089D01*
G37*
G36*
G01X713345Y616607D02*
G03X712901Y616223I-44J-398D01*
G02X711655Y617667I-1401J51D01*
G03X712099Y618051I44J398D01*
G02X713345Y616607I1401J-51D01*
G37*
G36*
G01X1931383Y617811D02*
G03Y617189I252J-311D01*
G02X1929617I-883J-1089D01*
G03Y617811I-252J311D01*
G02X1931383I883J1089D01*
G37*
G36*
G01X1372904Y615115D02*
G03X1372297Y615025I-266J-298D01*
G02X1372034Y616802I-1197J731D01*
G03X1372641Y616892I266J298D01*
G02X1372904Y615115I1197J-731D01*
G37*
G36*
G01X629517Y611700D02*
G03X629012Y611466I-132J-378D01*
G02X628165Y613297I-1307J507D01*
G03X628670Y613531I132J378D01*
G02X629517Y611700I1307J-507D01*
G37*
G36*
G01X1015360Y612989D02*
G03X1015938Y612881I339J213D01*
G02X1015591Y611012I840J-1123D01*
G03X1015013Y611120I-339J-213D01*
G02X1015360Y612989I-840J1123D01*
G37*
G36*
G01X365752D02*
G03X366330Y612881I339J213D01*
G02X365983Y611012I840J-1123D01*
G03X365405Y611120I-339J-213D01*
G02X365752Y612989I-840J1123D01*
G37*
G36*
G01X656071Y613089D02*
G03Y612511I277J-289D01*
G02X654129I-971J-1011D01*
G03Y613089I-277J289D01*
G02X656071I971J1011D01*
G37*
G36*
G01X1533154Y612419D02*
G03X1533178Y611832I283J-282D01*
G02X1531276Y611753I-908J-1068D01*
G03X1531252Y612340I-283J282D01*
G02X1531212Y612375I903J1072D01*
G03X1530665Y612370I-271J-294D01*
G02X1528864Y612257I-968J1014D01*
G03X1528294Y612159I-238J-322D01*
G02X1528149Y614024I-1244J841D01*
G03X1528470Y614063I146J136D01*
G02X1528563Y614209I1227J-679D01*
G03X1528485Y614509I-161J118D01*
G02X1530296Y615109I582J1275D01*
G03X1530435Y614576I350J-193D01*
G02X1530645Y614417I-738J-1192D01*
G03X1531192Y614422I271J294D01*
G02X1533154Y612419I969J-1014D01*
G37*
G36*
G01X1383607Y611122D02*
G03X1383603Y610567I286J-280D01*
G02X1381584Y610582I-1017J-965D01*
G03X1381588Y611137I-286J280D01*
G02X1383607Y611122I1017J965D01*
G37*
G36*
G01X1652380Y614210D02*
Y609115D01*
X1652371Y609031D01*
G02X1649358Y609200I-1502J169D01*
G01Y614201D01*
G02X1652380Y614210I1511J-1D01*
G37*
G36*
G01X1637045Y616571D02*
X1637046Y616569D01*
X1639942Y611164D01*
X1639943Y611162D01*
G02X1635798Y608941I-2045J-1162D01*
G01X1635797Y608943D01*
X1632901Y614348D01*
X1632900Y614350D01*
G02X1637045Y616571I2045J1162D01*
G37*
G36*
G01X1628179Y616586D02*
X1628180Y616585D01*
X1631092Y611148D01*
X1631093Y611146D01*
G02X1626947Y608926I-2054J-1146D01*
G01X1626946Y608927D01*
X1624034Y614364D01*
X1624033Y614366D01*
G02X1628179Y616586I2054J1146D01*
G37*
G36*
G01X1505671Y610089D02*
G03Y609511I277J-289D01*
G02X1503729I-971J-1011D01*
G03Y610089I-277J289D01*
G02X1505671I971J1011D01*
G37*
G36*
G01X1307614Y609031D02*
G03X1307604Y608489I289J-276D01*
G02X1305542Y608527I-1049J-931D01*
G03X1305552Y609069I-289J276D01*
G02X1307614Y609031I1049J931D01*
G37*
G36*
G01X1225735Y608978D02*
G03X1225740Y608390I274J-292D01*
G02X1223839Y608371I-940J-1040D01*
G03X1223834Y608959I-274J292D01*
G02X1225735Y608978I940J1040D01*
G37*
G36*
G01X1188924D02*
G03X1188929Y608390I274J-292D01*
G02X1187028Y608371I-940J-1040D01*
G03X1187023Y608959I-274J292D01*
G02X1188924Y608978I940J1040D01*
G37*
G36*
G01X1152113D02*
G03X1152118Y608390I274J-292D01*
G02X1150217Y608371I-940J-1040D01*
G03X1150212Y608959I-274J292D01*
G02X1152113Y608978I940J1040D01*
G37*
G36*
G01X1115301D02*
G03X1115306Y608390I274J-292D01*
G02X1113405Y608371I-940J-1040D01*
G03X1113400Y608959I-274J292D01*
G02X1115301Y608978I940J1040D01*
G37*
G36*
G01X934593D02*
G03X934598Y608390I274J-292D01*
G02X932697Y608371I-940J-1040D01*
G03X932692Y608959I-274J292D01*
G02X934593Y608978I940J1040D01*
G37*
G36*
G01X897782D02*
G03X897787Y608390I274J-292D01*
G02X895886Y608371I-940J-1040D01*
G03X895881Y608959I-274J292D01*
G02X897782Y608978I940J1040D01*
G37*
G36*
G01X860971D02*
G03X860976Y608390I274J-292D01*
G02X859075Y608371I-940J-1040D01*
G03X859070Y608959I-274J292D01*
G02X860971Y608978I940J1040D01*
G37*
G36*
G01X824160D02*
G03X824165Y608390I274J-292D01*
G02X822264Y608371I-940J-1040D01*
G03X822259Y608959I-274J292D01*
G02X824160Y608978I940J1040D01*
G37*
G36*
G01X785453Y608371D02*
G03X785448Y608959I-274J292D01*
G02X787349Y608978I940J1040D01*
G03X787354Y608390I274J-292D01*
G02X785453Y608371I-940J-1040D01*
G37*
G36*
G01X576127Y608978D02*
G03X576132Y608390I274J-292D01*
G02X574231Y608371I-940J-1040D01*
G03X574226Y608959I-274J292D01*
G02X576127Y608978I940J1040D01*
G37*
G36*
G01X539316D02*
G03X539321Y608390I274J-292D01*
G02X537420Y608371I-940J-1040D01*
G03X537415Y608959I-274J292D01*
G02X539316Y608978I940J1040D01*
G37*
G36*
G01X502505D02*
G03X502510Y608390I274J-292D01*
G02X500609Y608371I-940J-1040D01*
G03X500604Y608959I-274J292D01*
G02X502505Y608978I940J1040D01*
G37*
G36*
G01X465693D02*
G03X465698Y608390I274J-292D01*
G02X463797Y608371I-940J-1040D01*
G03X463792Y608959I-274J292D01*
G02X465693Y608978I940J1040D01*
G37*
G36*
G01X284985D02*
G03X284990Y608390I274J-292D01*
G02X283089Y608371I-940J-1040D01*
G03X283084Y608959I-274J292D01*
G02X284985Y608978I940J1040D01*
G37*
G36*
G01X248174D02*
G03X248179Y608390I274J-292D01*
G02X246278Y608371I-940J-1040D01*
G03X246273Y608959I-274J292D01*
G02X248174Y608978I940J1040D01*
G37*
G36*
G01X211363D02*
G03X211368Y608390I274J-292D01*
G02X209467Y608371I-940J-1040D01*
G03X209462Y608959I-274J292D01*
G02X211363Y608978I940J1040D01*
G37*
G36*
G01X174552D02*
G03X174557Y608390I274J-292D01*
G02X172656Y608371I-940J-1040D01*
G03X172651Y608959I-274J292D01*
G02X174552Y608978I940J1040D01*
G37*
G36*
G01X135845Y608371D02*
G03X135840Y608959I-274J292D01*
G02X137741Y608978I940J1040D01*
G03X137746Y608390I274J-292D01*
G02X135845Y608371I-940J-1040D01*
G37*
G36*
G01X1230841Y608734D02*
G03Y608155I276J-290D01*
G02X1228907I-967J-1015D01*
G03Y608734I-276J289D01*
G02X1230841I967J1015D01*
G37*
G36*
G01X1194030D02*
G03Y608155I276J-290D01*
G02X1192096I-967J-1015D01*
G03Y608734I-276J289D01*
G02X1194030I967J1015D01*
G37*
G36*
G01X1157219D02*
G03Y608155I276J-290D01*
G02X1155285I-967J-1015D01*
G03Y608734I-276J289D01*
G02X1157219I967J1015D01*
G37*
G36*
G01X1120407D02*
G03Y608155I276J-290D01*
G02X1118473I-967J-1015D01*
G03Y608734I-276J289D01*
G02X1120407I967J1015D01*
G37*
G36*
G01X939699D02*
G03Y608155I276J-290D01*
G02X937765I-967J-1015D01*
G03Y608734I-276J289D01*
G02X939699I967J1015D01*
G37*
G36*
G01X902888D02*
G03Y608155I276J-290D01*
G02X900954I-967J-1015D01*
G03Y608734I-276J289D01*
G02X902888I967J1015D01*
G37*
G36*
G01X866077D02*
G03Y608155I276J-290D01*
G02X864143I-967J-1015D01*
G03Y608734I-276J289D01*
G02X866077I967J1015D01*
G37*
G36*
G01X829266D02*
G03Y608155I276J-290D01*
G02X827332I-967J-1015D01*
G03Y608734I-276J289D01*
G02X829266I967J1015D01*
G37*
G36*
G01X792455D02*
G03Y608155I276J-290D01*
G02X790521I-967J-1015D01*
G03Y608734I-276J289D01*
G02X792455I967J1015D01*
G37*
G36*
G01X581233D02*
G03Y608155I276J-290D01*
G02X579299I-967J-1015D01*
G03Y608734I-276J289D01*
G02X581233I967J1015D01*
G37*
G36*
G01X544422D02*
G03Y608155I276J-290D01*
G02X542488I-967J-1015D01*
G03Y608734I-276J289D01*
G02X544422I967J1015D01*
G37*
G36*
G01X507611D02*
G03Y608155I276J-290D01*
G02X505677I-967J-1015D01*
G03Y608734I-276J289D01*
G02X507611I967J1015D01*
G37*
G36*
G01X470800D02*
G03Y608155I276J-290D01*
G02X468865I-968J-1015D01*
G03Y608734I-276J289D01*
G02X470800I967J1015D01*
G37*
G36*
G01X290091D02*
G03Y608155I276J-290D01*
G02X288157I-967J-1015D01*
G03Y608734I-276J289D01*
G02X290091I967J1015D01*
G37*
G36*
G01X253280D02*
G03Y608155I276J-290D01*
G02X251346I-967J-1015D01*
G03Y608734I-276J289D01*
G02X253280I967J1015D01*
G37*
G36*
G01X216469D02*
G03Y608155I276J-290D01*
G02X214535I-967J-1015D01*
G03Y608734I-276J289D01*
G02X216469I967J1015D01*
G37*
G36*
G01X179658D02*
G03Y608155I276J-290D01*
G02X177724I-967J-1015D01*
G03Y608734I-276J289D01*
G02X179658I967J1015D01*
G37*
G36*
G01X142847D02*
G03Y608155I276J-290D01*
G02X140913I-967J-1015D01*
G03Y608734I-276J289D01*
G02X142847I967J1015D01*
G37*
G36*
G01X1545090Y606559D02*
G03X1545469Y606114I397J-46D01*
G02X1544014Y604873I-62J-1401D01*
G03X1543635Y605318I-397J46D01*
G02X1542337Y606379I62J1401D01*
G03X1541774Y606642I-388J-97D01*
G02X1542522Y608243I-612J1261D01*
G03X1543085Y607980I388J97D01*
G02X1545090Y606559I612J-1261D01*
G37*
G36*
G01X1605380Y608460D02*
Y604365D01*
X1605371Y604281D01*
G02X1602358Y604450I-1502J169D01*
G01Y608451D01*
G02X1605380Y608460I1511J-1D01*
G37*
G36*
G01X1659880Y606260D02*
Y602165D01*
X1659871Y602081D01*
G02X1656858Y602250I-1502J169D01*
G01Y606251D01*
G02X1659880Y606260I1511J-1D01*
G37*
G36*
G01X1572237Y600367D02*
G03X1571718Y600360I-255J-308D01*
G02X1571683Y602796I-1058J1203D01*
G03X1572202Y602803I255J308D01*
G02X1572237Y600367I1058J-1203D01*
G37*
G36*
G01X1804772Y601902D02*
G03X1804178Y601662I-207J-342D01*
G02X1803850Y604145I-3193J841D01*
G03X1804486Y604068I347J199D01*
G02X1804772Y601902I1014J-968D01*
G37*
G36*
G01X1614860Y603260D02*
Y599165D01*
X1614851Y599081D01*
G02X1611838Y599250I-1502J169D01*
G01Y603251D01*
G02X1614860Y603260I1511J-1D01*
G37*
G36*
G01X1325210Y599127D02*
G03Y598573I288J-277D01*
G02X1323190I-1010J-973D01*
G03Y599127I-288J277D01*
G02X1323229Y601111I1010J973D01*
G03Y601689I-277J289D01*
G02X1323154Y603634I971J1011D01*
G03Y604166I-298J266D01*
G02Y606034I1046J934D01*
G03Y606566I-298J266D01*
G02X1323229Y608511I1046J934D01*
G03Y609089I-277J289D01*
G02X1325171I971J1011D01*
G03Y608511I277J-289D01*
G02X1325246Y606566I-971J-1011D01*
G03Y606034I298J-266D01*
G02Y604166I-1046J-934D01*
G03Y603634I298J-266D01*
G02X1325171Y601689I-1046J-934D01*
G03Y601111I277J-289D01*
G02X1325210Y599127I-971J-1011D01*
G37*
G36*
G01X713010Y598527D02*
G03Y597973I288J-277D01*
G02X710990I-1010J-973D01*
G03Y598527I-288J277D01*
G02X713010I1010J973D01*
G37*
G36*
G01X1589293Y595924D02*
G03X1588711Y595918I-288J-277D01*
G02X1586692Y595871I-1032J949D01*
G03X1586137Y595879I-282J-284D01*
G02X1586166Y597898I-958J1023D01*
G03X1586721Y597890I282J284D01*
G02X1588690Y597839I959J-1023D01*
G03X1589272Y597845I288J277D01*
G02X1589293Y595924I1032J-949D01*
G37*
G36*
G01X709771Y598289D02*
G03Y597711I277J-289D01*
G02X707829I-971J-1011D01*
G03Y598289I-277J289D01*
G02X709771I971J1011D01*
G37*
G36*
G01X1637045Y601610D02*
X1637046Y601608D01*
X1639942Y596203D01*
X1639943Y596201D01*
G02X1635798Y593980I-2045J-1162D01*
G01X1635797Y593982D01*
X1632901Y599387D01*
X1632900Y599389D01*
G02X1637045Y601610I2045J1162D01*
G37*
G36*
G01X1628179Y601625D02*
X1628180Y601624D01*
X1631092Y596187D01*
X1631093Y596185D01*
G02X1626947Y593965I-2054J-1146D01*
G01X1626946Y593966D01*
X1624034Y599403D01*
X1624033Y599405D01*
G02X1628179Y601625I2054J1146D01*
G37*
G36*
G01X1654010Y597960D02*
Y593865D01*
X1654001Y593781D01*
G02X1650988Y593950I-1502J169D01*
G01Y597951D01*
G02X1654010Y597960I1511J-1D01*
G37*
G36*
G01X1016508Y592671D02*
G03X1015930I-289J-277D01*
G02Y594613I-1011J971D01*
G03X1016508I289J277D01*
G02X1018582Y594556I1011J-971D01*
G03X1019200Y594569I304J260D01*
G02X1019237Y592786I1100J-869D01*
G03X1018619Y592773I-304J-260D01*
G02X1016508Y592671I-1100J869D01*
G37*
G36*
G01X1005113Y594661D02*
G03X1005668Y594658I279J286D01*
G02X1005655Y592638I966J-1016D01*
G03X1005100Y592641I-279J-286D01*
G02X1005113Y594661I-966J1016D01*
G37*
G36*
G01X366900Y592671D02*
G03X366322I-289J-277D01*
G02Y594613I-1011J971D01*
G03X366900I289J277D01*
G02X368964Y594568I1011J-971D01*
G03X369574Y594579I300J264D01*
G02X369606Y592765I1085J-888D01*
G03X368996Y592754I-300J-264D01*
G02X366900Y592671I-1085J888D01*
G37*
G36*
G01X355505Y594661D02*
G03X356060Y594658I279J286D01*
G02X356047Y592638I966J-1016D01*
G03X355492Y592641I-279J-286D01*
G02X355505Y594661I-966J1016D01*
G37*
G36*
G01X754907Y592660D02*
G03X754330Y592649I-283J-282D01*
G02X754293Y594590I-1030J951D01*
G03X754870Y594601I283J282D01*
G02X754907Y592660I1030J-951D01*
G37*
G36*
G01X1801343Y595110D02*
G03X1801349Y594538I283J-283D01*
G02X1799387Y594518I-971J-1011D01*
G03X1799381Y595090I-283J283D01*
G02X1801343Y595110I971J1011D01*
G37*
G36*
G01X1710951Y594470D02*
G03X1710940Y593893I271J-294D01*
G02X1708999Y593930I-990J-993D01*
G03X1709010Y594507I-271J294D01*
G02X1710951Y594470I990J993D01*
G37*
G36*
G01X1605430Y596760D02*
Y592665D01*
X1605421Y592581D01*
G02X1602408Y592750I-1502J169D01*
G01Y596751D01*
G02X1605430Y596760I1511J-1D01*
G37*
G36*
G01X1718962Y593631D02*
G03X1718956Y593035I264J-301D01*
G02X1717083Y593055I-948J-1033D01*
G03X1717089Y593651I-264J301D01*
G02X1717027Y595657I948J1033D01*
G03Y596211I-288J277D01*
G02X1719047I1010J973D01*
G03Y595657I288J-277D01*
G02X1718962Y593631I-1010J-972D01*
G37*
G36*
G01X1554589Y590129D02*
G03X1554011I-289J-277D01*
G02Y592071I-1011J971D01*
G03X1554589I289J277D01*
G02Y590129I1011J-971D01*
G37*
G36*
G01X648104Y592592D02*
G03X648419Y592084I383J-114D01*
G02X646836Y591102I-239J-1382D01*
G03X646521Y591610I-383J114D01*
G02X645381Y592738I239J1382D01*
G03X644880Y593050I-393J-73D01*
G02X645879Y594654I-380J1350D01*
G03X646380Y594342I393J73D01*
G02X648104Y592592I380J-1350D01*
G37*
G36*
G01X2515Y591438D02*
G03X2495Y590851I262J-303D01*
G02X516Y590968I-1056J-1068D01*
G03X566Y591554I-245J316D01*
G02X506Y591623I1027J954D01*
G03X194I-156J-125D01*
G02X73Y593510I-1094J877D01*
G03X627I277J288D01*
G02X2515Y591438I973J-1010D01*
G37*
G36*
G01X1763216Y590944D02*
G03Y590666I144J-139D01*
G02X1760908I-1154J-1111D01*
G03Y590944I-144J139D01*
G02X1763216I1154J1111D01*
G37*
G36*
G01X1230845Y590103D02*
G03Y589525I277J-289D01*
G02X1228903I-971J-1011D01*
G03Y590103I-277J289D01*
G02X1230845I971J1011D01*
G37*
G36*
G01X1194034D02*
G03Y589525I277J-289D01*
G02X1192092I-971J-1011D01*
G03Y590103I-277J289D01*
G02X1194034I971J1011D01*
G37*
G36*
G01X1157223D02*
G03Y589525I277J-289D01*
G02X1155281I-971J-1011D01*
G03Y590103I-277J289D01*
G02X1157223I971J1011D01*
G37*
G36*
G01X1120411D02*
G03Y589525I277J-289D01*
G02X1118469I-971J-1011D01*
G03Y590103I-277J289D01*
G02X1120411I971J1011D01*
G37*
G36*
G01X939703D02*
G03Y589525I277J-289D01*
G02X937761I-971J-1011D01*
G03Y590103I-277J289D01*
G02X939703I971J1011D01*
G37*
G36*
G01X902892D02*
G03Y589525I277J-289D01*
G02X900950I-971J-1011D01*
G03Y590103I-277J289D01*
G02X902892I971J1011D01*
G37*
G36*
G01X866081D02*
G03Y589525I277J-289D01*
G02X864139I-971J-1011D01*
G03Y590103I-277J289D01*
G02X866081I971J1011D01*
G37*
G36*
G01X829270D02*
G03Y589525I277J-289D01*
G02X827328I-971J-1011D01*
G03Y590103I-277J289D01*
G02X829270I971J1011D01*
G37*
G36*
G01X792459D02*
G03Y589525I277J-289D01*
G02X790517I-971J-1011D01*
G03Y590103I-277J289D01*
G02X792459I971J1011D01*
G37*
G36*
G01X581237D02*
G03Y589525I277J-289D01*
G02X579295I-971J-1011D01*
G03Y590103I-277J289D01*
G02X581237I971J1011D01*
G37*
G36*
G01X544426D02*
G03Y589525I277J-289D01*
G02X542484I-971J-1011D01*
G03Y590103I-277J289D01*
G02X544426I971J1011D01*
G37*
G36*
G01X507615D02*
G03Y589525I277J-289D01*
G02X505673I-971J-1011D01*
G03Y590103I-277J289D01*
G02X507615I971J1011D01*
G37*
G36*
G01X470803D02*
G03Y589525I277J-289D01*
G02X468861I-971J-1011D01*
G03Y590103I-277J289D01*
G02X470803I971J1011D01*
G37*
G36*
G01X290095D02*
G03Y589525I277J-289D01*
G02X288153I-971J-1011D01*
G03Y590103I-277J289D01*
G02X290095I971J1011D01*
G37*
G36*
G01X253284D02*
G03Y589525I277J-289D01*
G02X251342I-971J-1011D01*
G03Y590103I-277J289D01*
G02X253284I971J1011D01*
G37*
G36*
G01X216473D02*
G03Y589525I277J-289D01*
G02X214531I-971J-1011D01*
G03Y590103I-277J289D01*
G02X216473I971J1011D01*
G37*
G36*
G01X179662D02*
G03Y589525I277J-289D01*
G02X177720I-971J-1011D01*
G03Y590103I-277J289D01*
G02X179662I971J1011D01*
G37*
G36*
G01X142851D02*
G03Y589525I277J-289D01*
G02X140909I-971J-1011D01*
G03Y590103I-277J289D01*
G02X142851I971J1011D01*
G37*
G36*
G01X1225745Y589889D02*
G03Y589311I277J-289D01*
G02X1223803I-971J-1011D01*
G03Y589889I-277J289D01*
G02X1225745I971J1011D01*
G37*
G36*
G01X1188934D02*
G03Y589311I277J-289D01*
G02X1186992I-971J-1011D01*
G03Y589889I-277J289D01*
G02X1188934I971J1011D01*
G37*
G36*
G01X1152123D02*
G03Y589311I277J-289D01*
G02X1150181I-971J-1011D01*
G03Y589889I-277J289D01*
G02X1152123I971J1011D01*
G37*
G36*
G01X1115311D02*
G03Y589311I277J-289D01*
G02X1113369I-971J-1011D01*
G03Y589889I-277J289D01*
G02X1115311I971J1011D01*
G37*
G36*
G01X934603D02*
G03Y589311I277J-289D01*
G02X932661I-971J-1011D01*
G03Y589889I-277J289D01*
G02X934603I971J1011D01*
G37*
G36*
G01X897792D02*
G03Y589311I277J-289D01*
G02X895850I-971J-1011D01*
G03Y589889I-277J289D01*
G02X897792I971J1011D01*
G37*
G36*
G01X860981D02*
G03Y589311I277J-289D01*
G02X859039I-971J-1011D01*
G03Y589889I-277J289D01*
G02X860981I971J1011D01*
G37*
G36*
G01X824170D02*
G03Y589311I277J-289D01*
G02X822228I-971J-1011D01*
G03Y589889I-277J289D01*
G02X824170I971J1011D01*
G37*
G36*
G01X787359D02*
G03Y589311I277J-289D01*
G02X785417I-971J-1011D01*
G03Y589889I-277J289D01*
G02X787359I971J1011D01*
G37*
G36*
G01X576137D02*
G03Y589311I277J-289D01*
G02X574195I-971J-1011D01*
G03Y589889I-277J289D01*
G02X576137I971J1011D01*
G37*
G36*
G01X539326D02*
G03Y589311I277J-289D01*
G02X537384I-971J-1011D01*
G03Y589889I-277J289D01*
G02X539326I971J1011D01*
G37*
G36*
G01X502515D02*
G03Y589311I277J-289D01*
G02X500573I-971J-1011D01*
G03Y589889I-277J289D01*
G02X502515I971J1011D01*
G37*
G36*
G01X465703D02*
G03Y589311I277J-289D01*
G02X463761I-971J-1011D01*
G03Y589889I-277J289D01*
G02X465703I971J1011D01*
G37*
G36*
G01X284995D02*
G03Y589311I277J-289D01*
G02X283053I-971J-1011D01*
G03Y589889I-277J289D01*
G02X284995I971J1011D01*
G37*
G36*
G01X248184D02*
G03Y589311I277J-289D01*
G02X246242I-971J-1011D01*
G03Y589889I-277J289D01*
G02X248184I971J1011D01*
G37*
G36*
G01X211373D02*
G03Y589311I277J-289D01*
G02X209431I-971J-1011D01*
G03Y589889I-277J289D01*
G02X211373I971J1011D01*
G37*
G36*
G01X174562D02*
G03Y589311I277J-289D01*
G02X172620I-971J-1011D01*
G03Y589889I-277J289D01*
G02X174562I971J1011D01*
G37*
G36*
G01X137751D02*
G03Y589311I277J-289D01*
G02X135809I-971J-1011D01*
G03Y589889I-277J289D01*
G02X137751I971J1011D01*
G37*
G36*
G01X1662192Y590760D02*
Y586665D01*
X1662182Y586581D01*
G02X1659168Y586750I-1502J169D01*
G01Y590751D01*
G02X1662192Y590760I1512J-1D01*
G37*
G36*
G01X1419447Y585240D02*
G03X1418893I-277J-288D01*
G02X1416824Y585375I-973J1010D01*
G03X1416215Y585394I-313J-249D01*
G02X1414200Y585322I-1042J938D01*
G03X1413646I-277J-288D01*
G02Y587342I-973J1010D01*
G03X1414200I277J288D01*
G02X1416269Y587207I973J-1010D01*
G03X1416878Y587188I313J249D01*
G02X1418893Y587260I1042J-938D01*
G03X1419447I277J288D01*
G02X1421393I973J-1010D01*
G03X1421947I277J288D01*
G02Y585240I973J-1010D01*
G03X1421393I-277J-288D01*
G02X1419447I-973J1010D01*
G37*
G36*
G01X1611008Y590005D02*
G02X1614030Y590014I1511J-1D01*
G01Y586004D01*
X1614031D01*
Y585919D01*
X1614021Y585835D01*
G02X1611008Y586004I-1502J169D01*
G01Y590005D01*
G37*
G36*
G01X1544189Y584753D02*
G03X1543611I-289J-277D01*
G02Y586695I-1011J971D01*
G03X1544189I289J277D01*
G02Y584753I1011J-971D01*
G37*
G36*
G01X1012804Y584806D02*
G03X1012195I-305J-258D01*
G02Y586622I-1069J908D01*
G03X1012804I304J258D01*
G02Y584806I1069J-908D01*
G37*
G36*
G01X1005109Y586729D02*
G03X1005664Y586727I279J287D01*
G02X1005657Y584707I969J-1013D01*
G03X1005102Y584709I-279J-287D01*
G02X1005109Y586729I-969J1013D01*
G37*
G36*
G01X363196Y584806D02*
G03X362587I-305J-258D01*
G02Y586622I-1069J908D01*
G03X363196I305J258D01*
G02X365183Y586774I1069J-908D01*
G03X365765Y586837I262J302D01*
G02X365972Y584940I1125J-837D01*
G03X365390Y584877I-262J-302D01*
G02X363196Y584806I-1125J837D01*
G37*
G36*
G01X355501Y586729D02*
G03X356056Y586727I279J287D01*
G02X356049Y584707I969J-1013D01*
G03X355494Y584709I-279J-287D01*
G02X355501Y586729I-969J1013D01*
G37*
G36*
G01X1372689Y583685D02*
G03X1372111I-289J-277D01*
G02Y585627I-1011J971D01*
G03X1372689I289J277D01*
G02Y583685I1011J-971D01*
G37*
G36*
G01X1815255Y582948D02*
G03X1814679Y582814I-227J-329D01*
G02X1814253Y584653I-1223J686D01*
G03X1814829Y584787I227J329D01*
G02X1815255Y582948I1223J-686D01*
G37*
G36*
G01X1731818Y580896D02*
G03X1732393Y580876I297J267D01*
G02X1732324Y578932I975J-1008D01*
G03X1731749Y578952I-297J-267D01*
G02X1731818Y580896I-975J1008D01*
G37*
G36*
G01X1294692Y581162D02*
G03X1295092Y580762I400J0D01*
G02X1293688Y579358I-2J-1402D01*
G03X1293288Y579758I-400J0D01*
G02X1294692Y581162I2J1402D01*
G37*
G36*
G01X1684289Y586650D02*
X1684290Y586648D01*
X1687186Y581243D01*
X1687187Y581241D01*
G02X1683042Y579020I-2045J-1162D01*
G01X1683041Y579022D01*
X1680145Y584427D01*
X1680144Y584429D01*
G02X1684289Y586650I2045J1162D01*
G37*
G36*
G01X1675423Y586665D02*
X1675424Y586664D01*
X1678336Y581227D01*
X1678337Y581225D01*
G02X1674191Y579005I-2054J-1146D01*
G01X1674190Y579006D01*
X1671278Y584443D01*
X1671277Y584445D01*
G02X1675423Y586665I2054J1146D01*
G37*
G36*
G01X1637045Y586650D02*
X1637046Y586648D01*
X1639942Y581243D01*
X1639943Y581241D01*
G02X1635798Y579020I-2045J-1162D01*
G01X1635797Y579022D01*
X1632901Y584427D01*
X1632900Y584429D01*
G02X1637045Y586650I2045J1162D01*
G37*
G36*
G01X1628179Y586665D02*
X1628180Y586664D01*
X1631092Y581227D01*
X1631093Y581225D01*
G02X1626947Y579005I-2054J-1146D01*
G01X1626946Y579006D01*
X1624034Y584443D01*
X1624033Y584445D01*
G02X1628179Y586665I2054J1146D01*
G37*
G36*
G01X1607506Y582510D02*
Y578415D01*
X1607496Y578331D01*
G02X1604482Y578500I-1502J169D01*
G01Y582501D01*
G02X1607506Y582510I1512J-1D01*
G37*
G36*
G01X1654180Y582360D02*
Y578265D01*
X1654171Y578181D01*
G02X1651158Y578350I-1502J169D01*
G01Y582351D01*
G02X1654180Y582360I1511J-1D01*
G37*
G36*
G01X1015778Y573782D02*
G03X1015195I-292J-274D01*
G02Y575702I-1022J960D01*
G03X1015778I291J274D01*
G02Y573782I1022J-960D01*
G37*
G36*
G01X366170D02*
G03X365587I-291J-274D01*
G02Y575702I-1022J960D01*
G03X366170I291J274D01*
G02Y573782I1022J-960D01*
G37*
G36*
G01X651238Y573438D02*
G03X650696Y573413I-257J-306D01*
G02X648729Y575411I-996J987D01*
G03Y575989I-277J289D01*
G02X650645Y578036I971J1011D01*
G03X651186Y578039I269J296D01*
G02X653150Y576038I954J-1028D01*
G03Y575484I288J-277D01*
G02X651238Y573438I-1009J-973D01*
G37*
G36*
G01X664689Y573229D02*
G03X664111I-289J-277D01*
G02Y575171I-1011J971D01*
G03X664689I289J277D01*
G02Y573229I1011J-971D01*
G37*
G36*
G01X1772522Y574592D02*
G03X1772110Y574142I-15J-400D01*
G02X1770775Y575365I-1391J-178D01*
G03X1771187Y575815I15J400D01*
G02X1772522Y574592I1391J178D01*
G37*
G36*
G01X660489Y568829D02*
G03X659911I-289J-277D01*
G02Y570771I-1011J971D01*
G03X660489I289J277D01*
G02Y568829I1011J-971D01*
G37*
G36*
G01X1225735Y571178D02*
G03X1225740Y570590I274J-292D01*
G02X1223839Y570571I-940J-1040D01*
G03X1223834Y571159I-274J292D01*
G02X1225735Y571178I940J1040D01*
G37*
G36*
G01X1188924D02*
G03X1188929Y570590I274J-292D01*
G02X1187028Y570571I-940J-1040D01*
G03X1187023Y571159I-274J292D01*
G02X1188924Y571178I940J1040D01*
G37*
G36*
G01X1152113D02*
G03X1152118Y570590I274J-292D01*
G02X1150217Y570571I-940J-1040D01*
G03X1150212Y571159I-274J292D01*
G02X1152113Y571178I940J1040D01*
G37*
G36*
G01X1115301D02*
G03X1115306Y570590I274J-292D01*
G02X1113405Y570571I-940J-1040D01*
G03X1113400Y571159I-274J292D01*
G02X1115301Y571178I940J1040D01*
G37*
G36*
G01X934593D02*
G03X934598Y570590I274J-292D01*
G02X932697Y570571I-940J-1040D01*
G03X932692Y571159I-274J292D01*
G02X934593Y571178I940J1040D01*
G37*
G36*
G01X897782D02*
G03X897787Y570590I274J-292D01*
G02X895886Y570571I-940J-1040D01*
G03X895881Y571159I-274J292D01*
G02X897782Y571178I940J1040D01*
G37*
G36*
G01X860971D02*
G03X860976Y570590I274J-292D01*
G02X859075Y570571I-940J-1040D01*
G03X859070Y571159I-274J292D01*
G02X860971Y571178I940J1040D01*
G37*
G36*
G01X824160D02*
G03X824165Y570590I274J-292D01*
G02X822264Y570571I-940J-1040D01*
G03X822259Y571159I-274J292D01*
G02X824160Y571178I940J1040D01*
G37*
G36*
G01X787349D02*
G03X787354Y570590I274J-292D01*
G02X785453Y570571I-940J-1040D01*
G03X785448Y571159I-274J292D01*
G02X787349Y571178I940J1040D01*
G37*
G36*
G01X576127D02*
G03X576132Y570590I274J-292D01*
G02X574231Y570571I-940J-1040D01*
G03X574226Y571159I-274J292D01*
G02X576127Y571178I940J1040D01*
G37*
G36*
G01X539316D02*
G03X539321Y570590I274J-292D01*
G02X537420Y570571I-940J-1040D01*
G03X537415Y571159I-274J292D01*
G02X539316Y571178I940J1040D01*
G37*
G36*
G01X502505D02*
G03X502510Y570590I274J-292D01*
G02X500609Y570571I-940J-1040D01*
G03X500604Y571159I-274J292D01*
G02X502505Y571178I940J1040D01*
G37*
G36*
G01X465693D02*
G03X465698Y570590I274J-292D01*
G02X463797Y570571I-940J-1040D01*
G03X463792Y571159I-274J292D01*
G02X465693Y571178I940J1040D01*
G37*
G36*
G01X284985D02*
G03X284990Y570590I274J-292D01*
G02X283089Y570571I-940J-1040D01*
G03X283084Y571159I-274J292D01*
G02X284985Y571178I940J1040D01*
G37*
G36*
G01X248174D02*
G03X248179Y570590I274J-292D01*
G02X246278Y570571I-940J-1040D01*
G03X246273Y571159I-274J292D01*
G02X248174Y571178I940J1040D01*
G37*
G36*
G01X211363D02*
G03X211368Y570590I274J-292D01*
G02X209467Y570571I-940J-1040D01*
G03X209462Y571159I-274J292D01*
G02X211363Y571178I940J1040D01*
G37*
G36*
G01X174552D02*
G03X174557Y570590I274J-292D01*
G02X172656Y570571I-940J-1040D01*
G03X172651Y571159I-274J292D01*
G02X174552Y571178I940J1040D01*
G37*
G36*
G01X135845Y570571D02*
G03X135840Y571159I-274J292D01*
G02X137741Y571178I940J1040D01*
G03X137746Y570590I274J-292D01*
G02X135845Y570571I-940J-1040D01*
G37*
G36*
G01X1230841Y570934D02*
G03Y570355I276J-290D01*
G02X1228907I-967J-1015D01*
G03Y570934I-276J289D01*
G02X1230841I967J1015D01*
G37*
G36*
G01X1194030D02*
G03Y570355I276J-290D01*
G02X1192096I-967J-1015D01*
G03Y570934I-276J289D01*
G02X1194030I967J1015D01*
G37*
G36*
G01X1157219D02*
G03Y570355I276J-290D01*
G02X1155285I-967J-1015D01*
G03Y570934I-276J289D01*
G02X1157219I967J1015D01*
G37*
G36*
G01X1120407D02*
G03Y570355I276J-290D01*
G02X1118473I-967J-1015D01*
G03Y570934I-276J289D01*
G02X1120407I967J1015D01*
G37*
G36*
G01X939699D02*
G03Y570355I276J-290D01*
G02X937765I-967J-1015D01*
G03Y570934I-276J289D01*
G02X939699I967J1015D01*
G37*
G36*
G01X902888D02*
G03Y570355I276J-290D01*
G02X900954I-967J-1015D01*
G03Y570934I-276J289D01*
G02X902888I967J1015D01*
G37*
G36*
G01X866077D02*
G03Y570355I276J-290D01*
G02X864143I-967J-1015D01*
G03Y570934I-276J289D01*
G02X866077I967J1015D01*
G37*
G36*
G01X829266D02*
G03Y570355I276J-290D01*
G02X827332I-967J-1015D01*
G03Y570934I-276J289D01*
G02X829266I967J1015D01*
G37*
G36*
G01X792455D02*
G03Y570355I276J-290D01*
G02X790521I-967J-1015D01*
G03Y570934I-276J289D01*
G02X792455I967J1015D01*
G37*
G36*
G01X581233D02*
G03Y570355I276J-290D01*
G02X579299I-967J-1015D01*
G03Y570934I-276J289D01*
G02X581233I967J1015D01*
G37*
G36*
G01X544422D02*
G03Y570355I276J-290D01*
G02X542488I-967J-1015D01*
G03Y570934I-276J289D01*
G02X544422I967J1015D01*
G37*
G36*
G01X507611D02*
G03Y570355I276J-290D01*
G02X505677I-967J-1015D01*
G03Y570934I-276J289D01*
G02X507611I967J1015D01*
G37*
G36*
G01X470799D02*
G03Y570355I276J-290D01*
G02X468865I-967J-1015D01*
G03Y570934I-276J289D01*
G02X470799I967J1015D01*
G37*
G36*
G01X290091D02*
G03Y570355I276J-290D01*
G02X288157I-967J-1015D01*
G03Y570934I-276J289D01*
G02X290091I967J1015D01*
G37*
G36*
G01X253280D02*
G03Y570355I276J-290D01*
G02X251346I-967J-1015D01*
G03Y570934I-276J289D01*
G02X253280I967J1015D01*
G37*
G36*
G01X216469D02*
G03Y570355I276J-290D01*
G02X214535I-967J-1015D01*
G03Y570934I-276J289D01*
G02X216469I967J1015D01*
G37*
G36*
G01X179658D02*
G03Y570355I276J-290D01*
G02X177724I-967J-1015D01*
G03Y570934I-276J289D01*
G02X179658I967J1015D01*
G37*
G36*
G01X142847D02*
G03Y570355I276J-290D01*
G02X140913I-967J-1015D01*
G03Y570934I-276J289D01*
G02X142847I967J1015D01*
G37*
G36*
G01X703008Y570426D02*
G03X703030Y569849I288J-278D01*
G02X701092Y569774I-930J-1049D01*
G03X701070Y570351I-288J278D01*
G02X703008Y570426I930J1049D01*
G37*
G36*
G01X649000Y567694D02*
G03X648400I-300J-265D01*
G02Y569552I-1050J929D01*
G03X649000I300J265D01*
G02Y567694I1050J-929D01*
G37*
G36*
G01X1603336Y572335D02*
Y568240D01*
X1603327Y568156D01*
G02X1600314Y568325I-1502J169D01*
G01Y572326D01*
G02X1603336Y572335I1511J-1D01*
G37*
G36*
G01X4611Y568271D02*
G03X5189I289J277D01*
G02Y566329I1011J-971D01*
G03X4611I-289J-277D01*
G02Y568271I-1011J971D01*
G37*
G36*
G01X1015778Y565854D02*
G03X1015195I-292J-274D01*
G02Y567774I-1022J960D01*
G03X1015778I291J274D01*
G02Y565854I1022J-960D01*
G37*
G36*
G01X366170D02*
G03X365587I-291J-274D01*
G02Y567774I-1022J960D01*
G03X366170I291J274D01*
G02Y565854I1022J-960D01*
G37*
G36*
G01X1684289Y571689D02*
X1684290Y571687D01*
X1687186Y566282D01*
X1687187Y566280D01*
G02X1683042Y564059I-2045J-1162D01*
G01X1683041Y564061D01*
X1680145Y569466D01*
X1680144Y569468D01*
G02X1684289Y571689I2045J1162D01*
G37*
G36*
G01X1675423Y571704D02*
X1675424Y571703D01*
X1678336Y566266D01*
X1678337Y566264D01*
G02X1674191Y564044I-2054J-1146D01*
G01X1674190Y564045D01*
X1671278Y569482D01*
X1671277Y569484D01*
G02X1675423Y571704I2054J1146D01*
G37*
G36*
G01X1637045Y571689D02*
X1637046Y571687D01*
X1639942Y566282D01*
X1639943Y566280D01*
G02X1635798Y564059I-2045J-1162D01*
G01X1635797Y564061D01*
X1632901Y569466D01*
X1632900Y569468D01*
G02X1637045Y571689I2045J1162D01*
G37*
G36*
G01X1628179Y571704D02*
X1628180Y571703D01*
X1631092Y566266D01*
X1631093Y566264D01*
G02X1626947Y564044I-2054J-1146D01*
G01X1626946Y564045D01*
X1624034Y569482D01*
X1624033Y569484D01*
G02X1628179Y571704I2054J1146D01*
G37*
G36*
G01X1448220Y562717D02*
G03X1447680I-270J-295D01*
G02Y565083I-1080J1183D01*
G03X1448220I270J295D01*
G02X1450340Y565118I1080J-1183D01*
G03X1450860I260J304D01*
G02X1452980Y565083I1040J-1218D01*
G03X1453520I270J295D01*
G02X1455680I1080J-1183D01*
G03X1456220I270J295D01*
G02Y562717I1080J-1183D01*
G03X1455680I-270J-295D01*
G02X1453520I-1080J1183D01*
G03X1452980I-270J-295D01*
G02X1450860Y562682I-1080J1183D01*
G03X1450340I-260J-304D01*
G02X1448220Y562717I-1040J1218D01*
G37*
G36*
G01X1655911Y562918D02*
G03X1655333Y562646I-187J-354D01*
G02X1653568Y564276I-1373J284D01*
G03X1653794Y564874I-112J384D01*
G02X1655911Y562918I4734J3000D01*
G37*
G36*
G01X1598097Y561256D02*
G03X1597543I-277J-288D01*
G02X1595579Y563258I-973J1010D01*
G03X1595590Y563812I-283J283D01*
G02X1595597Y565723I1030J952D01*
G03X1595593Y566275I-292J274D01*
G02X1597623Y566291I1007J975D01*
G03X1597627Y565739I292J-274D01*
G02X1597714Y565641I-1004J-979D01*
G03X1598026I156J125D01*
G02X1600111Y563772I1093J-878D01*
G03X1600100Y563218I283J-283D01*
G02X1598097Y561256I-1030J-952D01*
G37*
G36*
G01X1469286Y560694D02*
G03X1468767Y560689I-257J-307D01*
G02X1468742Y563125I-1053J1207D01*
G03X1469261Y563130I257J307D01*
G02X1471361Y563136I1053J-1207D01*
G03X1471901Y563152I261J302D01*
G02X1471971Y560790I1117J-1149D01*
G03X1471431Y560774I-261J-302D01*
G02X1469286Y560694I-1117J1149D01*
G37*
G36*
G01X1491077Y560687D02*
G03X1490504Y560667I-277J-289D01*
G02X1490426Y562897I-1188J1075D01*
G03X1490999Y562917I277J289D01*
G02X1493387Y562903I1188J-1075D01*
G03X1493987I300J265D01*
G02X1496267Y563025I1200J-1061D01*
G03X1496812Y563031I269J296D01*
G02X1498963Y563086I1106J-1159D01*
G03X1499485I261J303D01*
G02Y560658I1045J-1214D01*
G03X1498963I-261J-303D01*
G02X1496838Y560689I-1045J1214D01*
G03X1496293Y560683I-269J-296D01*
G02X1493987Y560781I-1106J1159D01*
G03X1493387I-300J-265D01*
G02X1491077Y560687I-1200J1061D01*
G37*
G36*
G01X1383118Y561641D02*
G03X1383081Y561073I262J-302D01*
G02X1381114Y561202I-1049J-930D01*
G03X1381151Y561770I-262J302D01*
G02X1383118Y561641I1049J930D01*
G37*
G36*
G01X1850561Y558233D02*
X1850537Y558238D01*
X1848488D01*
Y560287D01*
X1848483Y560311D01*
G02Y561689I2767J689D01*
G01X1848488Y561713D01*
Y563762D01*
X1850537D01*
X1850561Y563767D01*
G02X1851939I689J-2767D01*
G01X1851963Y563762D01*
X1854012D01*
Y561713D01*
X1854017Y561689D01*
G02Y560311I-2767J-689D01*
G01X1854012Y560287D01*
Y558238D01*
X1851963D01*
X1851939Y558233D01*
G02X1850561I-689J2767D01*
G37*
G36*
G01X1739133Y559735D02*
G03X1739297Y559155I335J-218D01*
G02X1737522Y558653I-600J-1267D01*
G03X1737358Y559233I-335J218D01*
G02X1739133Y559735I600J1267D01*
G37*
G36*
G01X1626606Y559210D02*
Y555115D01*
X1626596Y555031D01*
G02X1623582Y555200I-1502J169D01*
G01Y559200D01*
G02X1626606Y559210I1512J0D01*
G37*
G36*
G01X2393Y555510D02*
G03X2416Y554924I283J-282D01*
G02X430Y554895I-977J-1141D01*
G03X436Y555482I-269J296D01*
G02X389Y555529I968J1015D01*
G03X-189I-289J-277D01*
G02Y557471I-1011J971D01*
G03X389I289J277D01*
G02X2393Y555510I1012J-971D01*
G37*
G36*
G01X652611Y551617D02*
G03X651989I-311J-252D01*
G02Y553383I-1089J883D01*
G03X652611I311J252D01*
G02Y551617I1089J-883D01*
G37*
G36*
G01X1663754Y549588D02*
X1658753D01*
G02X1658754Y552412I1J1412D01*
G01X1663754D01*
G02X1665166Y551010I0J-1412D01*
G01Y550916D01*
X1665155Y550832D01*
G02X1663754Y549588I-1401J167D01*
G37*
G36*
G01X1230845Y552303D02*
G03Y551725I277J-289D01*
G02X1228903I-971J-1011D01*
G03Y552303I-277J289D01*
G02X1230845I971J1011D01*
G37*
G36*
G01X1194034D02*
G03Y551725I277J-289D01*
G02X1192092I-971J-1011D01*
G03Y552303I-277J289D01*
G02X1194034I971J1011D01*
G37*
G36*
G01X1157223D02*
G03Y551725I277J-289D01*
G02X1155281I-971J-1011D01*
G03Y552303I-277J289D01*
G02X1157223I971J1011D01*
G37*
G36*
G01X1120411D02*
G03Y551725I277J-289D01*
G02X1118469I-971J-1011D01*
G03Y552303I-277J289D01*
G02X1120411I971J1011D01*
G37*
G36*
G01X939703D02*
G03Y551725I277J-289D01*
G02X937761I-971J-1011D01*
G03Y552303I-277J289D01*
G02X939703I971J1011D01*
G37*
G36*
G01X902892D02*
G03Y551725I277J-289D01*
G02X900950I-971J-1011D01*
G03Y552303I-277J289D01*
G02X902892I971J1011D01*
G37*
G36*
G01X866081D02*
G03Y551725I277J-289D01*
G02X864139I-971J-1011D01*
G03Y552303I-277J289D01*
G02X866081I971J1011D01*
G37*
G36*
G01X829270D02*
G03Y551725I277J-289D01*
G02X827328I-971J-1011D01*
G03Y552303I-277J289D01*
G02X829270I971J1011D01*
G37*
G36*
G01X792459D02*
G03Y551725I277J-289D01*
G02X790517I-971J-1011D01*
G03Y552303I-277J289D01*
G02X792459I971J1011D01*
G37*
G36*
G01X581237D02*
G03Y551725I277J-289D01*
G02X579295I-971J-1011D01*
G03Y552303I-277J289D01*
G02X581237I971J1011D01*
G37*
G36*
G01X544426D02*
G03Y551725I277J-289D01*
G02X542484I-971J-1011D01*
G03Y552303I-277J289D01*
G02X544426I971J1011D01*
G37*
G36*
G01X507615D02*
G03Y551725I277J-289D01*
G02X505673I-971J-1011D01*
G03Y552303I-277J289D01*
G02X507615I971J1011D01*
G37*
G36*
G01X470803D02*
G03Y551725I277J-289D01*
G02X468861I-971J-1011D01*
G03Y552303I-277J289D01*
G02X470803I971J1011D01*
G37*
G36*
G01X290095D02*
G03Y551725I277J-289D01*
G02X288153I-971J-1011D01*
G03Y552303I-277J289D01*
G02X290095I971J1011D01*
G37*
G36*
G01X253284D02*
G03Y551725I277J-289D01*
G02X251342I-971J-1011D01*
G03Y552303I-277J289D01*
G02X253284I971J1011D01*
G37*
G36*
G01X216473D02*
G03Y551725I277J-289D01*
G02X214531I-971J-1011D01*
G03Y552303I-277J289D01*
G02X216473I971J1011D01*
G37*
G36*
G01X179662D02*
G03Y551725I277J-289D01*
G02X177720I-971J-1011D01*
G03Y552303I-277J289D01*
G02X179662I971J1011D01*
G37*
G36*
G01X142851D02*
G03Y551725I277J-289D01*
G02X140909I-971J-1011D01*
G03Y552303I-277J289D01*
G02X142851I971J1011D01*
G37*
G36*
G01X1225745Y552089D02*
G03Y551511I277J-289D01*
G02X1223803I-971J-1011D01*
G03Y552089I-277J289D01*
G02X1225745I971J1011D01*
G37*
G36*
G01X1188934D02*
G03Y551511I277J-289D01*
G02X1186992I-971J-1011D01*
G03Y552089I-277J289D01*
G02X1188934I971J1011D01*
G37*
G36*
G01X1152123D02*
G03Y551511I277J-289D01*
G02X1150181I-971J-1011D01*
G03Y552089I-277J289D01*
G02X1152123I971J1011D01*
G37*
G36*
G01X1115311D02*
G03Y551511I277J-289D01*
G02X1113369I-971J-1011D01*
G03Y552089I-277J289D01*
G02X1115311I971J1011D01*
G37*
G36*
G01X934603D02*
G03Y551511I277J-289D01*
G02X932661I-971J-1011D01*
G03Y552089I-277J289D01*
G02X934603I971J1011D01*
G37*
G36*
G01X897792D02*
G03Y551511I277J-289D01*
G02X895850I-971J-1011D01*
G03Y552089I-277J289D01*
G02X897792I971J1011D01*
G37*
G36*
G01X860981D02*
G03Y551511I277J-289D01*
G02X859039I-971J-1011D01*
G03Y552089I-277J289D01*
G02X860981I971J1011D01*
G37*
G36*
G01X824170D02*
G03Y551511I277J-289D01*
G02X822228I-971J-1011D01*
G03Y552089I-277J289D01*
G02X824170I971J1011D01*
G37*
G36*
G01X787359D02*
G03Y551511I277J-289D01*
G02X785417I-971J-1011D01*
G03Y552089I-277J289D01*
G02X787359I971J1011D01*
G37*
G36*
G01X576137D02*
G03Y551511I277J-289D01*
G02X574195I-971J-1011D01*
G03Y552089I-277J289D01*
G02X576137I971J1011D01*
G37*
G36*
G01X539326D02*
G03Y551511I277J-289D01*
G02X537384I-971J-1011D01*
G03Y552089I-277J289D01*
G02X539326I971J1011D01*
G37*
G36*
G01X502515D02*
G03Y551511I277J-289D01*
G02X500573I-971J-1011D01*
G03Y552089I-277J289D01*
G02X502515I971J1011D01*
G37*
G36*
G01X465703D02*
G03Y551511I277J-289D01*
G02X463761I-971J-1011D01*
G03Y552089I-277J289D01*
G02X465703I971J1011D01*
G37*
G36*
G01X284995D02*
G03Y551511I277J-289D01*
G02X283053I-971J-1011D01*
G03Y552089I-277J289D01*
G02X284995I971J1011D01*
G37*
G36*
G01X248184D02*
G03Y551511I277J-289D01*
G02X246242I-971J-1011D01*
G03Y552089I-277J289D01*
G02X248184I971J1011D01*
G37*
G36*
G01X211373D02*
G03Y551511I277J-289D01*
G02X209431I-971J-1011D01*
G03Y552089I-277J289D01*
G02X211373I971J1011D01*
G37*
G36*
G01X174562D02*
G03Y551511I277J-289D01*
G02X172620I-971J-1011D01*
G03Y552089I-277J289D01*
G02X174562I971J1011D01*
G37*
G36*
G01X137751D02*
G03Y551511I277J-289D01*
G02X135809I-971J-1011D01*
G03Y552089I-277J289D01*
G02X137751I971J1011D01*
G37*
G36*
G01X1685000Y549032D02*
X1679999D01*
G02X1680000Y552056I1J1512D01*
G01X1685000D01*
G02X1686512Y550554I0J-1512D01*
G01Y550459D01*
X1686502Y550375D01*
G02X1685000Y549032I-1502J168D01*
G37*
G36*
G01X1794888Y551715D02*
G03X1794866Y551116I254J-309D01*
G02X1793012Y551185I-966J-1016D01*
G03X1793034Y551784I-254J309D01*
G02X1794888Y551715I966J1016D01*
G37*
G36*
G01X1936731Y551240D02*
G03X1937264Y550995I380J125D01*
G02X1936469Y549260I536J-1295D01*
G03X1935936Y549505I-380J-125D01*
G02X1936731Y551240I-536J1295D01*
G37*
G36*
G01X1739037Y549968D02*
G03X1739065Y549355I270J-295D01*
G02X1737267Y549271I-849J-1116D01*
G03X1737239Y549884I-270J295D01*
G02X1739037Y549968I849J1116D01*
G37*
G36*
G01X1364055Y546944D02*
G03X1363501I-277J-288D01*
G02Y548964I-973J1010D01*
G03X1364055I277J288D01*
G02Y546944I973J-1010D01*
G37*
G36*
G01X1012804Y547006D02*
G03X1012195I-305J-258D01*
G02Y548822I-1069J908D01*
G03X1012804I304J258D01*
G02Y547006I1069J-908D01*
G37*
G36*
G01X363196D02*
G03X362587I-305J-258D01*
G02Y548822I-1069J908D01*
G03X363196I305J258D01*
G02Y547006I1069J-908D01*
G37*
G36*
G01X1705348Y545122D02*
X1700348D01*
G02Y548144I0J1511D01*
G01X1705348D01*
G02X1706860Y546643I0J-1512D01*
G01Y546548D01*
X1706850Y546464D01*
G02X1705348Y545122I-1502J169D01*
G37*
G36*
G01X1496273Y547033D02*
G03X1496820Y547010I286J280D01*
G02X1496723Y544674I1046J-1213D01*
G03X1496176Y544697I-286J-280D01*
G02X1493930Y544849I-1046J1213D01*
G03X1493330I-300J-265D01*
G02X1490874Y544916I-1200J1061D01*
G03X1490298Y544970I-314J-248D01*
G02X1490387Y547006I-918J1060D01*
G03X1490965Y547010I287J278D01*
G02X1493330Y546971I1165J-1100D01*
G03X1493930I300J265D01*
G02X1496273Y547033I1200J-1061D01*
G37*
G36*
G01X1439987Y544190D02*
G03X1439915Y543633I247J-315D01*
G02X1437935Y543889I-1116J-848D01*
G03X1438007Y544446I-247J315D01*
G02X1439987Y544190I1116J848D01*
G37*
G36*
G01X1676020Y550027D02*
G03X1676280Y549508I376J-136D01*
G02X1671633Y548350I-1359J-4449D01*
G03X1671350Y549032I-283J282D01*
G01X1669599D01*
G02X1669600Y552056I1J1512D01*
G01X1674600D01*
G02X1676112Y550554I0J-1512D01*
G01Y550459D01*
X1676102Y550375D01*
G02X1676020Y550027I-1502J170D01*
G37*
G36*
G01X1391434Y540655D02*
G03X1391428Y540051I259J-305D01*
G02X1389543Y540025I-928J-1051D01*
G03X1389521Y540629I-273J292D01*
G02X1391434Y540655I941J1171D01*
G37*
G36*
G01X1743894Y534951D02*
G03X1743351I-271J-294D01*
G02Y538631I-1697J1840D01*
G03X1743894I272J294D01*
G02X1747288I1697J-1840D01*
G03X1747831I272J294D01*
G02X1751225I1697J-1840D01*
G03X1751768I271J294D01*
G02X1755162I1697J-1840D01*
G03X1755705I271J294D01*
G02X1759099I1697J-1840D01*
G03X1759642I272J294D01*
G02Y534951I1697J-1840D01*
G03X1759099I-271J-294D01*
G02X1755705I-1697J1840D01*
G03X1755162I-272J-294D01*
G02X1751768I-1697J1840D01*
G03X1751225I-272J-294D01*
G02X1747831I-1697J1840D01*
G03X1747288I-271J-294D01*
G02X1743894I-1697J1840D01*
G37*
G36*
G01X735027Y534190D02*
G03X734473I-277J-288D01*
G02X732490Y536173I-973J1010D01*
G03Y536727I-288J277D01*
G02X734473Y538710I1010J973D01*
G03X735027I277J288D01*
G02X737010Y536727I973J-1010D01*
G03Y536173I288J-277D01*
G02X735027Y534190I-1010J-973D01*
G37*
G36*
G01X1712206Y533780D02*
X1707204D01*
G02X1704820Y534952I0J3011D01*
G03X1704207Y534977I-317J-244D01*
G02X1700203Y534976I-2002J1814D01*
G03X1699590Y534952I-296J-268D01*
G02X1697206Y533780I-2384J1839D01*
G01X1692204D01*
G02X1689820Y534952I0J3011D01*
G03X1689207Y534977I-317J-244D01*
G02Y538605I-2002J1814D01*
G03X1689820Y538630I296J269D01*
G02X1692204Y539802I2384J-1839D01*
G01X1697206D01*
G02X1699590Y538630I0J-3011D01*
G03X1700203Y538606I317J244D01*
G02X1704207Y538605I2002J-1815D01*
G03X1704820Y538630I296J269D01*
G02X1707204Y539802I2384J-1839D01*
G01X1712206D01*
G02X1714590Y538630I0J-3011D01*
G03X1715203Y538606I317J244D01*
G02Y534976I2002J-1815D01*
G03X1714590Y534952I-296J-268D01*
G02X1712206Y533780I-2384J1839D01*
G37*
G36*
G01X1225735Y533378D02*
G03X1225740Y532790I274J-292D01*
G02X1223839Y532771I-940J-1040D01*
G03X1223834Y533359I-274J292D01*
G02X1225735Y533378I940J1040D01*
G37*
G36*
G01X1188924D02*
G03X1188929Y532790I274J-292D01*
G02X1187028Y532771I-940J-1040D01*
G03X1187023Y533359I-274J292D01*
G02X1188924Y533378I940J1040D01*
G37*
G36*
G01X1152113D02*
G03X1152118Y532790I274J-292D01*
G02X1150217Y532771I-940J-1040D01*
G03X1150212Y533359I-274J292D01*
G02X1152113Y533378I940J1040D01*
G37*
G36*
G01X1115301D02*
G03X1115306Y532790I274J-292D01*
G02X1113405Y532771I-940J-1040D01*
G03X1113400Y533359I-274J292D01*
G02X1115301Y533378I940J1040D01*
G37*
G36*
G01X934593D02*
G03X934598Y532790I274J-292D01*
G02X932697Y532771I-940J-1040D01*
G03X932692Y533359I-274J292D01*
G02X934593Y533378I940J1040D01*
G37*
G36*
G01X897782D02*
G03X897787Y532790I274J-292D01*
G02X895886Y532771I-940J-1040D01*
G03X895881Y533359I-274J292D01*
G02X897782Y533378I940J1040D01*
G37*
G36*
G01X860971D02*
G03X860976Y532790I274J-292D01*
G02X859075Y532771I-940J-1040D01*
G03X859070Y533359I-274J292D01*
G02X860971Y533378I940J1040D01*
G37*
G36*
G01X824160D02*
G03X824165Y532790I274J-292D01*
G02X822264Y532771I-940J-1040D01*
G03X822259Y533359I-274J292D01*
G02X824160Y533378I940J1040D01*
G37*
G36*
G01X785453Y532771D02*
G03X785448Y533359I-274J292D01*
G02X787349Y533378I940J1040D01*
G03X787354Y532790I274J-292D01*
G02X785453Y532771I-940J-1040D01*
G37*
G36*
G01X576127Y533378D02*
G03X576132Y532790I274J-292D01*
G02X574231Y532771I-940J-1040D01*
G03X574226Y533359I-274J292D01*
G02X576127Y533378I940J1040D01*
G37*
G36*
G01X539316D02*
G03X539321Y532790I274J-292D01*
G02X537420Y532771I-940J-1040D01*
G03X537415Y533359I-274J292D01*
G02X539316Y533378I940J1040D01*
G37*
G36*
G01X502505D02*
G03X502510Y532790I274J-292D01*
G02X500609Y532771I-940J-1040D01*
G03X500604Y533359I-274J292D01*
G02X502505Y533378I940J1040D01*
G37*
G36*
G01X463797Y532771D02*
G03X463792Y533359I-274J292D01*
G02X465693Y533378I940J1040D01*
G03X465698Y532790I274J-292D01*
G02X463797Y532771I-940J-1040D01*
G37*
G36*
G01X284985Y533378D02*
G03X284990Y532790I274J-292D01*
G02X283089Y532771I-940J-1040D01*
G03X283084Y533359I-274J292D01*
G02X284985Y533378I940J1040D01*
G37*
G36*
G01X248174D02*
G03X248179Y532790I274J-292D01*
G02X246278Y532771I-940J-1040D01*
G03X246273Y533359I-274J292D01*
G02X248174Y533378I940J1040D01*
G37*
G36*
G01X211363D02*
G03X211368Y532790I274J-292D01*
G02X209467Y532771I-940J-1040D01*
G03X209462Y533359I-274J292D01*
G02X211363Y533378I940J1040D01*
G37*
G36*
G01X174552D02*
G03X174557Y532790I274J-292D01*
G02X172656Y532771I-940J-1040D01*
G03X172651Y533359I-274J292D01*
G02X174552Y533378I940J1040D01*
G37*
G36*
G01X135845Y532771D02*
G03X135840Y533359I-274J292D01*
G02X137741Y533378I940J1040D01*
G03X137746Y532790I274J-292D01*
G02X135845Y532771I-940J-1040D01*
G37*
G36*
G01X1230841Y533134D02*
G03Y532555I276J-290D01*
G02X1228907I-967J-1015D01*
G03Y533134I-276J289D01*
G02X1230841I967J1015D01*
G37*
G36*
G01X1194030D02*
G03Y532555I276J-290D01*
G02X1192096I-967J-1015D01*
G03Y533134I-276J289D01*
G02X1194030I967J1015D01*
G37*
G36*
G01X1157219D02*
G03Y532555I276J-290D01*
G02X1155285I-967J-1015D01*
G03Y533134I-276J289D01*
G02X1157219I967J1015D01*
G37*
G36*
G01X1120407D02*
G03Y532555I276J-290D01*
G02X1118473I-967J-1015D01*
G03Y533134I-276J289D01*
G02X1120407I967J1015D01*
G37*
G36*
G01X939699D02*
G03Y532555I276J-290D01*
G02X937765I-967J-1015D01*
G03Y533134I-276J289D01*
G02X939699I967J1015D01*
G37*
G36*
G01X902888D02*
G03Y532555I276J-290D01*
G02X900954I-967J-1015D01*
G03Y533134I-276J289D01*
G02X902888I967J1015D01*
G37*
G36*
G01X866077D02*
G03Y532555I276J-290D01*
G02X864143I-967J-1015D01*
G03Y533134I-276J289D01*
G02X866077I967J1015D01*
G37*
G36*
G01X829266D02*
G03Y532555I276J-290D01*
G02X827332I-967J-1015D01*
G03Y533134I-276J289D01*
G02X829266I967J1015D01*
G37*
G36*
G01X792455D02*
G03Y532555I276J-290D01*
G02X790521I-967J-1015D01*
G03Y533134I-276J289D01*
G02X792455I967J1015D01*
G37*
G36*
G01X581233D02*
G03Y532555I276J-290D01*
G02X579299I-967J-1015D01*
G03Y533134I-276J289D01*
G02X581233I967J1015D01*
G37*
G36*
G01X544422D02*
G03Y532555I276J-290D01*
G02X542488I-967J-1015D01*
G03Y533134I-276J289D01*
G02X544422I967J1015D01*
G37*
G36*
G01X507611D02*
G03Y532555I276J-290D01*
G02X505677I-967J-1015D01*
G03Y533134I-276J289D01*
G02X507611I967J1015D01*
G37*
G36*
G01X470799D02*
G03Y532555I276J-290D01*
G02X468865I-967J-1015D01*
G03Y533134I-276J289D01*
G02X470799I967J1015D01*
G37*
G36*
G01X290091D02*
G03Y532555I276J-290D01*
G02X288157I-967J-1015D01*
G03Y533134I-276J289D01*
G02X290091I967J1015D01*
G37*
G36*
G01X253280D02*
G03Y532555I276J-290D01*
G02X251346I-967J-1015D01*
G03Y533134I-276J289D01*
G02X253280I967J1015D01*
G37*
G36*
G01X216469D02*
G03Y532555I276J-290D01*
G02X214535I-967J-1015D01*
G03Y533134I-276J289D01*
G02X216469I967J1015D01*
G37*
G36*
G01X179658D02*
G03Y532555I276J-290D01*
G02X177724I-967J-1015D01*
G03Y533134I-276J289D01*
G02X179658I967J1015D01*
G37*
G36*
G01X142847D02*
G03Y532555I276J-290D01*
G02X140913I-967J-1015D01*
G03Y533134I-276J289D01*
G02X142847I967J1015D01*
G37*
G36*
G01X4611Y532271D02*
G03X5189I289J277D01*
G02Y530329I1011J-971D01*
G03X4611I-289J-277D01*
G02Y532271I-1011J971D01*
G37*
G36*
G01X1930653Y529830D02*
X1928253D01*
G02Y535252I0J2711D01*
G01X1930653D01*
G02X1933364Y532551I0J-2711D01*
G01Y532452D01*
X1933359Y532363D01*
G02X1930653Y529830I-2706J179D01*
G37*
G36*
G01X1889927D02*
X1884727D01*
G02Y535252I0J2711D01*
G01X1889927D01*
G02X1892638Y532551I0J-2711D01*
G01Y532452D01*
X1892633Y532363D01*
G02X1889927Y529830I-2706J179D01*
G37*
G36*
G01X1482727Y530190D02*
G03X1482173I-277J-288D01*
G02Y532210I-973J1010D01*
G03X1482727I277J288D01*
G02Y530190I973J-1010D01*
G37*
G36*
G01X115539Y527414D02*
G03X115435Y526832I214J-338D01*
G02X113575Y527166I-1113J-852D01*
G03X113679Y527748I-214J338D01*
G02X115539Y527414I1113J852D01*
G37*
G36*
G01X1818548Y526492D02*
G03X1818168Y526005I11J-400D01*
G02X1816761Y527101I-1368J-305D01*
G03X1817141Y527588I-11J400D01*
G02X1818548Y526492I1368J305D01*
G37*
G36*
G01X1638728Y528723D02*
G03X1638940Y528154I350J-194D01*
G02X1636593Y527726I-810J-2208D01*
G03X1636591Y528333I-261J303D01*
G02X1638728Y528723I909J1067D01*
G37*
G36*
G01X1785026Y521592D02*
G03X1784449Y521570I-278J-288D01*
G02X1782379Y521539I-1049J930D01*
G03X1781811Y521552I-290J-275D01*
G02X1781859Y523523I-973J1010D01*
G03X1782427Y523510I290J275D01*
G02X1784374Y523508I972J-1010D01*
G03X1784951Y523530I278J288D01*
G02X1785026Y521592I1049J-930D01*
G37*
G36*
G01X702144Y523214D02*
G03X702156Y522612I270J-296D01*
G02X700311Y522574I-901J-1074D01*
G03X700299Y523176I-270J296D01*
G02X702144Y523214I901J1074D01*
G37*
G36*
G01X1629183Y519602D02*
G03X1628572Y519538I-279J-287D01*
G02X1628383Y521324I-1165J780D01*
G03X1628994Y521388I279J287D01*
G02X1629183Y519602I1165J-780D01*
G37*
G36*
G01X1698850Y519221D02*
G03X1698272I-289J-277D01*
G02Y521163I-1011J971D01*
G03X1698850I289J277D01*
G02Y519221I1011J-971D01*
G37*
G36*
G01X1790804Y521062D02*
G03X1790594Y520541I159J-367D01*
G02X1788746Y521288I-1294J-541D01*
G03X1788956Y521809I-159J367D01*
G02X1790804Y521062I1294J541D01*
G37*
G36*
G01X1377636Y518921D02*
G03X1377082I-277J-288D01*
G02X1375031Y519035I-973J1010D01*
G03X1374417Y519037I-308J-256D01*
G02X1374423Y520836I-1072J903D01*
G03X1375037Y520834I308J256D01*
G02X1377082Y520941I1073J-903D01*
G03X1377636I277J288D01*
G02X1379572Y520950I973J-1010D01*
G03X1380124Y520952I275J290D01*
G02X1382173Y520836I970J-1012D01*
G03X1382787Y520834I308J256D01*
G02X1384832Y520941I1073J-903D01*
G03X1385386I277J288D01*
G02Y518921I973J-1010D01*
G03X1384832I-277J-288D01*
G02X1382781Y519035I-973J1010D01*
G03X1382167Y519037I-308J-256D01*
G02X1380132Y518921I-1072J903D01*
G03X1379580Y518919I-275J-290D01*
G02X1377636Y518921I-971J1012D01*
G37*
G36*
G01X1492664Y518498D02*
X1490099D01*
G02X1490037Y518500I17J1501D01*
G01X1489579D01*
X1489416Y518663D01*
X1489390Y518677D01*
G02X1488777Y519290I710J1323D01*
G01X1488763Y519316D01*
X1488700Y519379D01*
Y519456D01*
X1488688Y519489D01*
G02Y520511I1412J511D01*
G01X1488700Y520544D01*
Y520621D01*
X1488763Y520684D01*
X1488777Y520710D01*
G02X1489390Y521323I1323J-710D01*
G01X1489416Y521337D01*
X1489579Y521500D01*
X1490037D01*
G02X1490100Y521502I79J-1499D01*
G01X1492664D01*
G02X1492773Y521500I27J-1502D01*
G01X1493421D01*
X1494300Y520621D01*
Y519379D01*
X1493421Y518500D01*
X1492773D01*
G02X1492664Y518498I-82J1500D01*
G37*
G36*
G01X753910Y520148D02*
G03Y519594I288J-277D01*
G02X751890I-1010J-973D01*
G03Y520148I-288J277D01*
G02X753910I1010J973D01*
G37*
G36*
G01X1506500Y519354D02*
X1506511Y519362D01*
X1506714Y519565D01*
X1506886D01*
X1506918Y519576D01*
G02X1507441Y519657I488J-1421D01*
G01X1507444Y519656D01*
X1510005D01*
G02X1510491Y519576I2J-1501D01*
G01X1510522Y519565D01*
X1510556D01*
X1510577Y519544D01*
X1510612Y519529D01*
G02X1511379Y518762I-607J-1374D01*
G01X1511394Y518727D01*
X1511435Y518686D01*
Y518614D01*
X1511443Y518586D01*
G02X1511506Y518165I-1438J-430D01*
G01Y518070D01*
X1511497Y517986D01*
G02X1511443Y517724I-1492J171D01*
G01X1511435Y517696D01*
Y517444D01*
X1510556Y516565D01*
X1506714D01*
X1505835Y517444D01*
Y518686D01*
X1506198Y519049D01*
X1506206Y519060D01*
G02X1506500Y519354I1199J-905D01*
G37*
G36*
G01X53987Y525432D02*
G03X54513I263J302D01*
G02X56487I987J-1132D01*
G03X57013I263J302D01*
G02X59132Y523313I987J-1132D01*
G03Y522787I302J-263D01*
G02X59075Y520751I-1132J-987D01*
G03X59061Y520207I286J-280D01*
G02X56933Y518094I-1125J-995D01*
G03X56420Y518113I-268J-297D01*
G02X54397Y518281I-920J1187D01*
G03X54103I-147J-136D01*
G02X54037Y518214I-1102J1020D01*
G03X54036Y517925I138J-145D01*
G02X51848Y517819I-1044J-1079D01*
G03X51849Y518335I-305J259D01*
G02X51868Y520287I1151J965D01*
G03Y520813I-302J263D01*
G02Y522787I1132J987D01*
G03Y523313I-302J263D01*
G02X53987Y525432I1132J987D01*
G37*
G36*
G01X1025810Y517883D02*
G03Y517329I288J-277D01*
G02X1023790I-1010J-973D01*
G03Y517883I-288J277D01*
G02X1025810I1010J973D01*
G37*
G36*
G01X376202D02*
G03Y517329I288J-277D01*
G02X374182I-1010J-973D01*
G03Y517883I-288J277D01*
G02X376202I1010J973D01*
G37*
G36*
G01X1496555Y516195D02*
Y516643D01*
X1496718Y516806D01*
G02X1497346Y517446I1337J-684D01*
G01X1497372Y517460D01*
X1497434Y517522D01*
X1497510D01*
X1497543Y517534D01*
G02X1498091Y517624I513J-1412D01*
G01X1500655D01*
G02X1501166Y517534I-1J-1502D01*
G01X1501199Y517522D01*
X1501276D01*
X1501339Y517459D01*
X1501365Y517445D01*
G02X1501991Y516807I-710J-1323D01*
G01X1502155Y516643D01*
Y516186D01*
G02X1502156Y516132I-1500J-55D01*
G01Y516130D01*
X1502155D01*
Y515401D01*
X1501276Y514522D01*
X1497434D01*
X1496555Y515401D01*
Y516049D01*
G02Y516195I1500J73D01*
G37*
G36*
G01X1483227Y514690D02*
G03X1482673I-277J-288D01*
G02Y516710I-973J1010D01*
G03X1483227I277J288D01*
G02Y514690I973J-1010D01*
G37*
G36*
G01X63468Y516587D02*
G03Y517113I-302J263D01*
G02X63617Y519235I1132J987D01*
G03X63596Y519857I-262J303D01*
G02X63343Y522008I907J1197D01*
G03X63317Y522545I-309J254D01*
G02X63282Y524631I1063J1061D01*
G03Y525177I-292J273D01*
G02X65087Y527527I1098J1025D01*
G03X65604Y527653I188J353D01*
G02X67972Y525813I1237J-852D01*
G03Y525287I302J-263D01*
G02X67864Y523201I-1132J-987D01*
G03X67853Y522919I136J-147D01*
G02X67882Y520913I-1103J-1019D01*
G03Y520387I302J-263D01*
G02Y518413I-1132J-987D01*
G03Y517887I302J-263D01*
G02X66485Y515422I-1132J-987D01*
G03X66032Y515148I-71J-394D01*
G02X63468Y516587I-1432J452D01*
G37*
G36*
G01X1314671Y516789D02*
G03Y516211I277J-289D01*
G02X1312729I-971J-1011D01*
G03Y516789I-277J289D01*
G02X1314671I971J1011D01*
G37*
G36*
G01X1230845Y514503D02*
G03Y513925I277J-289D01*
G02X1228903I-971J-1011D01*
G03Y514503I-277J289D01*
G02X1230845I971J1011D01*
G37*
G36*
G01X1194034D02*
G03Y513925I277J-289D01*
G02X1192092I-971J-1011D01*
G03Y514503I-277J289D01*
G02X1194034I971J1011D01*
G37*
G36*
G01X1157223D02*
G03Y513925I277J-289D01*
G02X1155281I-971J-1011D01*
G03Y514503I-277J289D01*
G02X1157223I971J1011D01*
G37*
G36*
G01X1120411D02*
G03Y513925I277J-289D01*
G02X1118469I-971J-1011D01*
G03Y514503I-277J289D01*
G02X1120411I971J1011D01*
G37*
G36*
G01X939703D02*
G03Y513925I277J-289D01*
G02X937761I-971J-1011D01*
G03Y514503I-277J289D01*
G02X939703I971J1011D01*
G37*
G36*
G01X902892D02*
G03Y513925I277J-289D01*
G02X900950I-971J-1011D01*
G03Y514503I-277J289D01*
G02X902892I971J1011D01*
G37*
G36*
G01X866081D02*
G03Y513925I277J-289D01*
G02X864139I-971J-1011D01*
G03Y514503I-277J289D01*
G02X866081I971J1011D01*
G37*
G36*
G01X829270D02*
G03Y513925I277J-289D01*
G02X827328I-971J-1011D01*
G03Y514503I-277J289D01*
G02X829270I971J1011D01*
G37*
G36*
G01X792459D02*
G03Y513925I277J-289D01*
G02X790517I-971J-1011D01*
G03Y514503I-277J289D01*
G02X792459I971J1011D01*
G37*
G36*
G01X581237D02*
G03Y513925I277J-289D01*
G02X579295I-971J-1011D01*
G03Y514503I-277J289D01*
G02X581237I971J1011D01*
G37*
G36*
G01X544426D02*
G03Y513925I277J-289D01*
G02X542484I-971J-1011D01*
G03Y514503I-277J289D01*
G02X544426I971J1011D01*
G37*
G36*
G01X507615D02*
G03Y513925I277J-289D01*
G02X505673I-971J-1011D01*
G03Y514503I-277J289D01*
G02X507615I971J1011D01*
G37*
G36*
G01X470803D02*
G03Y513925I277J-289D01*
G02X468861I-971J-1011D01*
G03Y514503I-277J289D01*
G02X470803I971J1011D01*
G37*
G36*
G01X290095D02*
G03Y513925I277J-289D01*
G02X288153I-971J-1011D01*
G03Y514503I-277J289D01*
G02X290095I971J1011D01*
G37*
G36*
G01X253284D02*
G03Y513925I277J-289D01*
G02X251342I-971J-1011D01*
G03Y514503I-277J289D01*
G02X253284I971J1011D01*
G37*
G36*
G01X216473D02*
G03Y513925I277J-289D01*
G02X214531I-971J-1011D01*
G03Y514503I-277J289D01*
G02X216473I971J1011D01*
G37*
G36*
G01X179662D02*
G03Y513925I277J-289D01*
G02X177720I-971J-1011D01*
G03Y514503I-277J289D01*
G02X179662I971J1011D01*
G37*
G36*
G01X142851D02*
G03Y513925I277J-289D01*
G02X140909I-971J-1011D01*
G03Y514503I-277J289D01*
G02X142851I971J1011D01*
G37*
G36*
G01X1225745Y514289D02*
G03Y513711I277J-289D01*
G02X1223803I-971J-1011D01*
G03Y514289I-277J289D01*
G02X1225745I971J1011D01*
G37*
G36*
G01X1188934D02*
G03Y513711I277J-289D01*
G02X1186992I-971J-1011D01*
G03Y514289I-277J289D01*
G02X1188934I971J1011D01*
G37*
G36*
G01X1152123D02*
G03Y513711I277J-289D01*
G02X1150181I-971J-1011D01*
G03Y514289I-277J289D01*
G02X1152123I971J1011D01*
G37*
G36*
G01X1115311D02*
G03Y513711I277J-289D01*
G02X1113369I-971J-1011D01*
G03Y514289I-277J289D01*
G02X1115311I971J1011D01*
G37*
G36*
G01X934603D02*
G03Y513711I277J-289D01*
G02X932661I-971J-1011D01*
G03Y514289I-277J289D01*
G02X934603I971J1011D01*
G37*
G36*
G01X897792D02*
G03Y513711I277J-289D01*
G02X895850I-971J-1011D01*
G03Y514289I-277J289D01*
G02X897792I971J1011D01*
G37*
G36*
G01X860981D02*
G03Y513711I277J-289D01*
G02X859039I-971J-1011D01*
G03Y514289I-277J289D01*
G02X860981I971J1011D01*
G37*
G36*
G01X824170D02*
G03Y513711I277J-289D01*
G02X822228I-971J-1011D01*
G03Y514289I-277J289D01*
G02X824170I971J1011D01*
G37*
G36*
G01X787359D02*
G03Y513711I277J-289D01*
G02X785417I-971J-1011D01*
G03Y514289I-277J289D01*
G02X787359I971J1011D01*
G37*
G36*
G01X576137D02*
G03Y513711I277J-289D01*
G02X574195I-971J-1011D01*
G03Y514289I-277J289D01*
G02X576137I971J1011D01*
G37*
G36*
G01X539326D02*
G03Y513711I277J-289D01*
G02X537384I-971J-1011D01*
G03Y514289I-277J289D01*
G02X539326I971J1011D01*
G37*
G36*
G01X502515D02*
G03Y513711I277J-289D01*
G02X500573I-971J-1011D01*
G03Y514289I-277J289D01*
G02X502515I971J1011D01*
G37*
G36*
G01X465703D02*
G03Y513711I277J-289D01*
G02X463761I-971J-1011D01*
G03Y514289I-277J289D01*
G02X465703I971J1011D01*
G37*
G36*
G01X284995D02*
G03Y513711I277J-289D01*
G02X283053I-971J-1011D01*
G03Y514289I-277J289D01*
G02X284995I971J1011D01*
G37*
G36*
G01X248184D02*
G03Y513711I277J-289D01*
G02X246242I-971J-1011D01*
G03Y514289I-277J289D01*
G02X248184I971J1011D01*
G37*
G36*
G01X211373D02*
G03Y513711I277J-289D01*
G02X209431I-971J-1011D01*
G03Y514289I-277J289D01*
G02X211373I971J1011D01*
G37*
G36*
G01X174562D02*
G03Y513711I277J-289D01*
G02X172620I-971J-1011D01*
G03Y514289I-277J289D01*
G02X174562I971J1011D01*
G37*
G36*
G01X137751D02*
G03Y513711I277J-289D01*
G02X135809I-971J-1011D01*
G03Y514289I-277J289D01*
G02X137751I971J1011D01*
G37*
G36*
G01X1775235Y513745D02*
G03X1775789Y513710I295J270D01*
G02X1775660Y511695I906J-1070D01*
G03X1775106Y511730I-295J-270D01*
G02X1775235Y513745I-906J1070D01*
G37*
G36*
G01X1460011Y514043D02*
G03X1459949Y513438I227J-329D01*
G02X1458137Y513623I-1014J-968D01*
G03X1458199Y514228I-227J329D01*
G02X1460186Y516206I1014J968D01*
G03X1460740I277J288D01*
G02Y514186I973J-1010D01*
G03X1460186I-277J-288D01*
G02X1460011Y514043I-972J1011D01*
G37*
G36*
G01X730626Y510592D02*
G03X730049Y510570I-278J-288D01*
G02X729974Y512508I-1049J930D01*
G03X730551Y512530I278J288D01*
G02X730626Y510592I1049J-930D01*
G37*
G36*
G01X1510700Y509639D02*
G02X1510591Y509530I-1115J1006D01*
G01X1510206Y509145D01*
X1509658D01*
G02X1509549Y509143I-82J1500D01*
G01X1509546Y509144D01*
X1506984D01*
G02X1506922Y509145I-7J1501D01*
G01X1506364D01*
X1505976Y509533D01*
X1505972Y509536D01*
G02X1505876Y509632I1013J1109D01*
G01X1505873Y509636D01*
X1505485Y510024D01*
Y510582D01*
G02Y510708I1500J63D01*
G01Y511266D01*
X1505874Y511655D01*
G02X1505972Y511754I1115J-1006D01*
G01X1505976Y511757D01*
X1506379Y512160D01*
X1510200D01*
X1511080Y511280D01*
Y511271D01*
X1511085Y511266D01*
Y510718D01*
G02Y510572I-1500J-73D01*
G01Y510024D01*
X1510700Y509639D01*
G37*
G36*
G01X1614027Y509290D02*
G03X1613473I-277J-288D01*
G02Y511310I-973J1010D01*
G03X1614027I277J288D01*
G02Y509290I973J-1010D01*
G37*
G36*
G01X1932053Y508490D02*
X1926853D01*
G02Y513914I0J2712D01*
G01X1932053D01*
G02X1934764Y511212I0J-2711D01*
G01Y511113D01*
X1934759Y511024D01*
G02X1932053Y508490I-2706J178D01*
G37*
G36*
G01X1888527D02*
X1886127D01*
G02Y513914I0J2712D01*
G01X1888527D01*
G02X1891238Y511212I0J-2711D01*
G01Y511113D01*
X1891233Y511024D01*
G02X1888527Y508490I-2706J178D01*
G37*
G36*
G01X1549341Y510717D02*
G03X1549325Y510156I277J-289D01*
G02X1547275I-1025J-956D01*
G03X1547259Y510717I-293J272D01*
G02X1549341I1041J1083D01*
G37*
G36*
G01X721845Y510766D02*
G03X722033Y510244I365J-163D01*
G02X720134Y509558I-619J-1258D01*
G03X719946Y510080I-365J163D01*
G02X721845Y510766I619J1258D01*
G37*
G36*
G01X361434Y511711D02*
G03X361620Y511512I200J1D01*
G02X362587Y511022I-101J-1398D01*
G03X363196I305J258D01*
G02X365276Y511085I1068J-908D01*
G03X365854I289J277D01*
G02Y509143I1011J-971D01*
G03X365276I-289J-277D01*
G02X363196Y509206I-1012J971D01*
G03X362587I-305J-258D01*
G02X361157Y508759I-1069J908D01*
G01X361045Y508789D01*
X359439Y507183D01*
G02X358846Y506936I-558J504D01*
G01X321818D01*
X319439Y509316D01*
G03X318836Y509273I-283J-283D01*
G02X316873Y511236I-1122J841D01*
G03X316916Y511839I-240J320D01*
G01X316331Y512424D01*
G03X315675Y512285I-283J-283D01*
G02X314802Y514125I-1307J507D01*
G03X315326Y514505I124J380D01*
G01Y516344D01*
G03X314802Y516724I-400J0D01*
G02Y519390I-434J1333D01*
G03X315326Y519770I124J380D01*
G01Y534212D01*
X316623Y535508D01*
G03X316645Y536050I-283J283D01*
G02X318621Y538026I1069J907D01*
G03X319163Y538048I259J305D01*
G01X321695Y540580D01*
G02X322225Y540800I531J-530D01*
G01X357851D01*
X361214Y537436D01*
G02X361434Y536906I-530J-531D01*
G01Y516802D01*
G03X361635Y516602I200J0D01*
G02X362680Y516142I7J-1402D01*
G03X363262Y516132I296J269D01*
G02X365276Y516123I1003J-980D01*
G03X365854I289J277D01*
G02Y514181I1011J-971D01*
G03X365276I-289J-277D01*
G02X363227Y514210I-1011J971D01*
G03X362645Y514220I-296J-269D01*
G02X361635Y513798I-1003J980D01*
G03X361434Y513598I-1J-200D01*
G01Y511711D01*
G37*
G36*
G01X1502377Y508166D02*
Y507818D01*
X1502292Y507733D01*
X1502276Y507694D01*
G02X1500841Y506737I-1400J545D01*
G01X1500838Y506738D01*
X1498276D01*
G02X1496878Y507693I0J1501D01*
G01X1496863Y507732D01*
X1496777Y507818D01*
Y508176D01*
G02Y508302I1500J63D01*
G01Y509060D01*
X1497656Y509939D01*
X1501498D01*
X1502377Y509060D01*
Y508312D01*
G02Y508166I-1500J-73D01*
G37*
G36*
G01X1484265Y508465D02*
X1484275Y508495D01*
Y508621D01*
X1484377Y508723D01*
G02X1484947Y509303I1316J-723D01*
G01X1484971Y509317D01*
X1485154Y509500D01*
X1485630D01*
G02X1485693Y509502I79J-1499D01*
G01X1488293D01*
G02X1488356Y509500I-16J-1502D01*
G01X1488996D01*
X1489875Y508621D01*
Y507379D01*
X1488996Y506500D01*
X1488356D01*
G02X1488293Y506498I-79J1499D01*
G01X1485692D01*
G02X1485630Y506500I17J1501D01*
G01X1485154D01*
X1484971Y506683D01*
X1484947Y506697D01*
G02X1484390Y507254I746J1303D01*
G01X1484376Y507278D01*
X1484275Y507379D01*
Y507505D01*
X1484265Y507535D01*
G02Y508465I1428J465D01*
G37*
G36*
G01X1478362Y506867D02*
G02X1478267Y506962I1013J1108D01*
G01X1477875Y507354D01*
Y507912D01*
G02Y508038I1500J63D01*
G01Y508596D01*
X1478267Y508988D01*
G02X1478362Y509083I1108J-1013D01*
G01X1478754Y509475D01*
X1479312D01*
G02X1479375Y509476I55J-1500D01*
G01X1481975D01*
G02X1482038Y509475I8J-1501D01*
G01X1482596D01*
X1482984Y509087D01*
X1482988Y509084D01*
G02X1483084Y508988I-1013J-1109D01*
G01X1483087Y508984D01*
X1483475Y508596D01*
Y508039D01*
G02X1483476Y507985I-1500J-55D01*
G01Y507984D01*
X1483475D01*
Y507354D01*
X1483083Y506962D01*
G02X1482988Y506867I-1108J1013D01*
G01X1482596Y506475D01*
X1482038D01*
G02X1481975Y506474I-55J1500D01*
G01X1479374D01*
G02X1479312Y506475I-7J1501D01*
G01X1478754D01*
X1478362Y506867D01*
G37*
G36*
G01X115452Y509327D02*
G03Y508773I288J-277D01*
G02X113432I-1010J-973D01*
G03Y509327I-288J277D01*
G02X115452I1010J973D01*
G37*
G36*
G01X1844304Y507840D02*
G03X1843851Y507461I-54J-396D01*
G02X1842636Y508910I-1401J59D01*
G03X1843089Y509289I54J396D01*
G02X1844304Y507840I1401J-59D01*
G37*
G36*
G01X34223Y509289D02*
G03X34058Y509518I-197J32D01*
G02X33490Y509735I241J1482D01*
G03X32964Y509651I-216J-337D01*
G02X32610Y511865I-1164J949D01*
G03X33136Y511949I216J337D01*
G02X35288Y512131I1164J-949D01*
G03X35856Y512173I263J301D01*
G02X38495Y511340I1144J-973D01*
G03X38958Y510982I399J37D01*
G02X39428Y508015I241J-1483D01*
G03X39092Y507574I61J-395D01*
G02X36111Y507205I-1492J-174D01*
G03X35713Y507553I-397J-52D01*
G02X34223Y509289I-6J1502D01*
G37*
G36*
G01X1556448Y508744D02*
G03Y508190I288J-277D01*
G02X1554428I-1010J-973D01*
G03Y508744I-288J277D01*
G02X1556448I1010J973D01*
G37*
G36*
G01X1543516Y508517D02*
G03X1543500Y507956I277J-289D01*
G02X1541450I-1025J-956D01*
G03X1541434Y508517I-293J272D01*
G02X1543516I1041J1083D01*
G37*
G36*
G01X764960Y507567D02*
G03Y507013I288J-277D01*
G02X762940I-1010J-973D01*
G03Y507567I-288J277D01*
G02Y509513I1010J973D01*
G03Y510067I-288J277D01*
G02X764960I1010J973D01*
G03Y509513I288J-277D01*
G02Y507567I-1010J-973D01*
G37*
G36*
G01X703409Y505754D02*
G03X702898Y505399I-112J-384D01*
G02X701891Y506846I-1398J101D01*
G03X702402Y507201I112J384D01*
G02X703409Y505754I1398J-101D01*
G37*
G36*
G01X712207Y504510D02*
G03X711639I-284J-282D01*
G02X709492Y504695I-997J986D01*
G03X708872Y504741I-329J-228D01*
G02X709001Y506501I-1022J960D01*
G03X709621Y506455I329J228D01*
G02X711636Y506486I1022J-959D01*
G03X712204I284J282D01*
G02X714199Y506484I997J-986D01*
G03X714798Y506517I285J280D01*
G02X714901Y504666I1102J-867D01*
G03X714302Y504633I-285J-280D01*
G02X712207Y504510I-1102J867D01*
G37*
G36*
G01X1650037Y503846D02*
G03X1649482Y503744I-226J-330D01*
G02X1648998Y505777I-1152J800D01*
G03X1649539Y505936I191J351D01*
G02X1650037Y503846I1405J-770D01*
G37*
G36*
G01X1568662Y504677D02*
G03X1569135Y505096I74J393D01*
G02X1570261Y502751I3463J220D01*
G03X1569638Y502643I-270J-296D01*
G02X1568662Y504677I-1238J657D01*
G37*
G36*
G01X1512234Y502025D02*
G02X1512139Y501930I-1108J1013D01*
G01X1511747Y501538D01*
X1511189D01*
G02X1511126Y501536I-79J1499D01*
G01X1508625D01*
G02X1508563Y501538I17J1501D01*
G01X1508005D01*
X1507617Y501926D01*
X1507613Y501929D01*
G02X1507517Y502025I1013J1109D01*
G01X1507514Y502029D01*
X1507126Y502417D01*
Y502975D01*
G02Y503101I1500J63D01*
G01Y503659D01*
X1507514Y504047D01*
X1507517Y504051D01*
G02X1507613Y504147I1109J-1013D01*
G01X1507617Y504150D01*
X1508005Y504538D01*
X1508563D01*
G02X1508626Y504540I79J-1499D01*
G01X1511126D01*
G02X1511189Y504538I-16J-1502D01*
G01X1511747D01*
X1512135Y504150D01*
G02X1512235Y504051I-1005J-1116D01*
G01X1512238Y504047D01*
X1512626Y503659D01*
Y503102D01*
G02X1512628Y503048I-1499J-83D01*
G01Y503038D01*
G02X1512626Y502975I-1501J16D01*
G01Y502417D01*
X1512234Y502025D01*
G37*
G36*
G01X1549310Y503027D02*
G03Y502473I288J-277D01*
G02X1547290I-1010J-973D01*
G03Y503027I-288J277D01*
G02X1549310I1010J973D01*
G37*
G36*
G01X1525487Y500192D02*
G02X1525392Y500287I1013J1108D01*
G01X1525000Y500679D01*
Y501237D01*
G02X1524998Y501300I1499J79D01*
G01Y503801D01*
G02X1525000Y503863I1501J-17D01*
G01Y504421D01*
X1525388Y504809D01*
X1525391Y504813D01*
G02X1525487Y504909I1109J-1013D01*
G01X1525491Y504912D01*
X1525879Y505300D01*
X1526437D01*
G02X1526563I63J-1500D01*
G01X1527121D01*
X1527512Y504909D01*
G02X1527612Y504809I-1010J-1110D01*
G01X1528000Y504421D01*
Y503864D01*
G02X1528002Y503810I-1499J-83D01*
G01Y501300D01*
G02X1528000Y501237I-1501J16D01*
G01Y500679D01*
X1527608Y500287D01*
G02X1527513Y500192I-1108J1013D01*
G01X1527121Y499800D01*
X1526563D01*
G02X1526437I-63J1500D01*
G01X1525879D01*
X1525487Y500192D01*
G37*
G36*
G01X675626Y500292D02*
G03X675049Y500270I-278J-288D01*
G02X672987Y500231I-1049J930D01*
G03X672432Y500253I-289J-277D01*
G02X672513Y502269I-932J1047D01*
G03X673068Y502247I289J277D01*
G02X674974Y502208I932J-1047D01*
G03X675551Y502230I278J288D01*
G02X675626Y500292I1049J-930D01*
G37*
G36*
G01X1738703Y502186D02*
G03X1738508Y501612I149J-371D01*
G02X1736777Y502201I-1208J-712D01*
G03X1736972Y502775I-149J371D01*
G02X1738703Y502186I1208J712D01*
G37*
G36*
G01X1874950Y501383D02*
G03X1875469Y501146I376J136D01*
G02X1874655Y499359I504J-1308D01*
G03X1874136Y499596I-376J-136D01*
G02X1874950Y501383I-504J1308D01*
G37*
G36*
G01X648006Y500173D02*
G03X647601Y499757I-5J-400D01*
G02X646219Y501102I-1401J-57D01*
G03X646624Y501518I5J400D01*
G02X648006Y500173I1401J57D01*
G37*
G36*
G01X1269329Y500380D02*
G03X1268968Y499918I34J-398D01*
G02X1267464Y501091I-1384J-224D01*
G03X1267825Y501553I-34J398D01*
G02X1269329Y500380I1384J224D01*
G37*
G36*
G01X745051Y498664D02*
G03X744497I-277J-288D01*
G02X742514Y500647I-973J1010D01*
G03Y501201I-288J277D01*
G02X744497Y503184I1010J973D01*
G03X745051I277J288D01*
G02X746997I973J-1010D01*
G03X747551I277J288D01*
G02X749401Y501080I973J-1010D01*
G03Y500768I125J-156D01*
G02X749485Y500695I-877J-1094D01*
G03X749786Y500725I138J145D01*
G02X750099Y498788I1145J-809D01*
G03X749564Y498734I-238J-322D01*
G02X747551Y498664I-1040J940D01*
G03X746997I-277J-288D01*
G02X745051I-973J1010D01*
G37*
G36*
G01X1532695Y501067D02*
G03Y500513I288J-277D01*
G02X1530675I-1010J-973D01*
G03Y501067I-288J277D01*
G02X1532695I1010J973D01*
G37*
G36*
G01X1556520Y501002D02*
G03Y500448I288J-277D01*
G02X1554500I-1010J-973D01*
G03Y501002I-288J277D01*
G02X1556520I1010J973D01*
G37*
G36*
G01X1543485Y500927D02*
G03Y500373I288J-277D01*
G02X1541465I-1010J-973D01*
G03Y500927I-288J277D01*
G02X1543485I1010J973D01*
G37*
G36*
G01X710341Y498494D02*
G03X709755Y498476I-285J-281D01*
G02X709698Y500384I-1055J923D01*
G03X710284Y500402I285J281D01*
G02X710341Y498494I1055J-923D01*
G37*
G36*
G01X1336011Y498417D02*
G03X1335389I-311J-252D01*
G02Y500183I-1089J883D01*
G03X1336011I311J252D01*
G02Y498417I1089J-883D01*
G37*
G36*
G01X1705728Y500548D02*
G03X1705739Y499999I296J-269D01*
G02X1703425Y497782I-1143J-1123D01*
G03X1702908Y497840I-292J-273D01*
G02X1700748Y500156I-903J1323D01*
G03X1700722Y500682I-314J248D01*
G02X1703017Y502917I1152J1113D01*
G03X1703551Y502884I285J280D01*
G02X1705728Y500548I993J-1257D01*
G37*
G36*
G01X-17651Y498430D02*
G03X-17666Y499031I-271J294D01*
G02X-15815Y499076I900J1075D01*
G03X-15800Y498475I271J-294D01*
G02X-17651Y498430I-900J-1075D01*
G37*
G36*
G01X1673481Y498725D02*
G03X1673416Y498165I250J-313D01*
G02X1671438Y498395I-1103J-865D01*
G03X1671503Y498955I-250J313D01*
G02X1673481Y498725I1103J865D01*
G37*
G36*
G01X113060Y499007D02*
G03X113164Y498418I314J-248D01*
G02X111328Y498095I-737J-1193D01*
G03X111224Y498684I-314J248D01*
G02X113060Y499007I737J1193D01*
G37*
G36*
G01X977433Y498798D02*
G03X977457Y498221I289J-277D01*
G02X975518Y498140I-927J-1051D01*
G03X975494Y498717I-289J277D01*
G02X977433Y498798I927J1051D01*
G37*
G36*
G01X327815Y498803D02*
G03X327843Y498227I291J-275D01*
G02X325904Y498134I-921J-1057D01*
G03X325876Y498710I-291J275D01*
G02X327815Y498803I921J1057D01*
G37*
G36*
G01X1084089Y495260D02*
X1081006D01*
X1080785Y495480D01*
X1069752Y506500D01*
X1042566D01*
X1041909Y507156D01*
X1041013Y508050D01*
G02X1040793Y508581I531J531D01*
G01Y508584D01*
G03X1040134Y508888I-400J0D01*
G02X1034196Y511629I-2336J2741D01*
G01Y516529D01*
G02X1040134Y519270I3602J0D01*
G03X1040793Y519574I259J304D01*
G01Y527460D01*
G03X1040134Y527764I-400J0D01*
G02X1034196Y530505I-2336J2741D01*
G01Y535405D01*
G02X1040347Y537949I3602J0D01*
G03X1040947Y537988I283J282D01*
G02X1041013Y538063I595J-457D01*
G01X1042622Y539673D01*
X1042625Y539676D01*
G02X1043215Y539920I555J-507D01*
G01X1095324D01*
G02X1095854Y539701I0J-751D01*
G01X1096716Y538840D01*
X1096719Y538837D01*
G02X1096761Y538795I-510J-552D01*
G01X1096764Y538792D01*
X1097210Y538347D01*
G02X1097430Y537816I-531J-531D01*
G01Y514203D01*
X1097594Y514173D01*
G02Y511415I-251J-1379D01*
G01X1097430Y511385D01*
Y508306D01*
X1084620Y495480D01*
G02X1084089Y495260I-531J531D01*
G37*
G36*
G01X434479D02*
X431396D01*
X420142Y506500D01*
X392956D01*
X391403Y508050D01*
G02X391183Y508581I531J531D01*
G01Y508584D01*
G03X390524Y508888I-400J0D01*
G02X384586Y511629I-2336J2741D01*
G01Y516529D01*
G02X390524Y519270I3602J0D01*
G03X391183Y519574I259J304D01*
G01Y527460D01*
G03X390524Y527764I-400J0D01*
G02X384586Y530505I-2336J2741D01*
G01Y535405D01*
G02X390524Y538146I3602J0D01*
G03X391183Y538450I259J304D01*
G01Y538494D01*
X392880Y540190D01*
G02X393410Y540410I531J-530D01*
G01X446594D01*
X447572Y539433D01*
X447575Y539430D01*
G02X447820Y538840I-506J-556D01*
G01Y514203D01*
X447984Y514174D01*
G02Y511414I-249J-1380D01*
G01X447820Y511385D01*
Y508306D01*
X435010Y495480D01*
G02X434479Y495260I-531J531D01*
G37*
G36*
G01X1758575Y494894D02*
X1753575D01*
G02Y497918I0J1512D01*
G01X1758575D01*
G02X1760086Y496416I-1J-1512D01*
G01Y496321D01*
X1760077Y496237D01*
G02X1758575Y494894I-1502J169D01*
G37*
G36*
G01X1748125Y494888D02*
X1743124D01*
G02X1743125Y497912I1J1512D01*
G01X1748125D01*
G02X1749636Y496410I-1J-1512D01*
G01Y496315D01*
X1749627Y496231D01*
G02X1748125Y494888I-1502J168D01*
G37*
G36*
G01X1157223Y495156D02*
G03Y494578I277J-289D01*
G02X1155281I-971J-1011D01*
G03Y495156I-277J289D01*
G02X1157223I971J1011D01*
G37*
G36*
G01X507615D02*
G03Y494578I277J-289D01*
G02X505673I-971J-1011D01*
G03Y495156I-277J289D01*
G02X507615I971J1011D01*
G37*
G36*
G01X1193992Y495159D02*
G03Y494559I265J-300D01*
G02X1192134I-929J-1050D01*
G03Y495159I-265J300D01*
G02X1193992I929J1050D01*
G37*
G36*
G01X544384D02*
G03Y494559I265J-300D01*
G02X542526I-929J-1050D01*
G03Y495159I-265J300D01*
G02X544384I929J1050D01*
G37*
G36*
G01X1152097Y495117D02*
G03Y494517I265J-300D01*
G02X1150239I-929J-1050D01*
G03Y495117I-265J300D01*
G02X1152097I929J1050D01*
G37*
G36*
G01X502489D02*
G03Y494517I265J-300D01*
G02X500631I-929J-1050D01*
G03Y495117I-265J300D01*
G02X502489I929J1050D01*
G37*
G36*
G01X939703Y494933D02*
G03Y494355I277J-289D01*
G02X937761I-971J-1011D01*
G03Y494933I-277J289D01*
G02X939703I971J1011D01*
G37*
G36*
G01X934618D02*
G03Y494355I277J-289D01*
G02X932676I-971J-1011D01*
G03Y494933I-277J289D01*
G02X934618I971J1011D01*
G37*
G36*
G01X290095D02*
G03Y494355I277J-289D01*
G02X288153I-971J-1011D01*
G03Y494933I-277J289D01*
G02X290095I971J1011D01*
G37*
G36*
G01X285010D02*
G03Y494355I277J-289D01*
G02X283068I-971J-1011D01*
G03Y494933I-277J289D01*
G02X285010I971J1011D01*
G37*
G36*
G01X902892Y494803D02*
G03Y494225I277J-289D01*
G02X900950I-971J-1011D01*
G03Y494803I-277J289D01*
G02X902892I971J1011D01*
G37*
G36*
G01X253284D02*
G03Y494225I277J-289D01*
G02X251342I-971J-1011D01*
G03Y494803I-277J289D01*
G02X253284I971J1011D01*
G37*
G36*
G01X1188907Y494859D02*
G03Y494259I265J-300D01*
G02X1187049I-929J-1050D01*
G03Y494859I-265J300D01*
G02X1188907I929J1050D01*
G37*
G36*
G01X897765D02*
G03Y494259I265J-300D01*
G02X895907I-929J-1050D01*
G03Y494859I-265J300D01*
G02X897765I929J1050D01*
G37*
G36*
G01X539299D02*
G03Y494259I265J-300D01*
G02X537441I-929J-1050D01*
G03Y494859I-265J300D01*
G02X539299I929J1050D01*
G37*
G36*
G01X248157D02*
G03Y494259I265J-300D01*
G02X246299I-929J-1050D01*
G03Y494859I-265J300D01*
G02X248157I929J1050D01*
G37*
G36*
G01X1296341Y494226D02*
G03X1296927Y494180I314J248D01*
G02X1296777Y492283I951J-1030D01*
G03X1296191Y492329I-314J-248D01*
G02X1296341Y494226I-951J1030D01*
G37*
G36*
G01X694614Y493330D02*
G03Y492776I288J-277D01*
G02X692594I-1010J-973D01*
G03Y493330I-288J277D01*
G02X694614I1010J973D01*
G37*
G36*
G01X690835Y493282D02*
G03Y492728I288J-277D01*
G02X688815I-1010J-973D01*
G03Y493282I-288J277D01*
G02X690835I1010J973D01*
G37*
G36*
G01X1842089Y490529D02*
G03X1841511I-289J-277D01*
G02X1839529Y492511I-1011J971D01*
G03Y493089I-277J289D01*
G02X1841511Y495071I971J1011D01*
G03X1842089I289J277D01*
G02X1844071Y493089I1011J-971D01*
G03Y492511I277J-289D01*
G02X1842089Y490529I-971J-1011D01*
G37*
G36*
G01X89350Y490392D02*
G03X88830I-260J-304D01*
G02X86572Y492650I-1040J1218D01*
G03Y493170I-304J260D01*
G02X86592Y495274I1218J1041D01*
G03X86602Y495793I-299J265D01*
G02X86622Y497850I1238J1017D01*
G03Y498370I-304J260D01*
G02X88880Y500628I1218J1040D01*
G03X89400I260J304D01*
G02X91480I1040J-1218D01*
G03X92000I260J304D01*
G02X94080I1040J-1218D01*
G03X94600I260J304D01*
G02X96680I1040J-1218D01*
G03X97200I260J304D01*
G02X99458Y498370I1040J-1218D01*
G03Y497850I304J-260D01*
G02X97776Y495277I-1218J-1040D01*
G03X97283Y494758I-117J-383D01*
G02X94663Y493062I-1506J-545D01*
G03X94106Y493061I-278J-288D01*
G02X91834Y493101I-1116J1149D01*
G03X91546I-144J-139D01*
G02X91499Y493054I-1156J1109D01*
G03Y492766I139J-144D01*
G02X89350Y490392I-1109J-1156D01*
G37*
G36*
G01X1249880Y490086D02*
G03X1249721Y489554I196J-348D01*
G02X1247787Y490135I-1247J-641D01*
G03X1247946Y490667I-196J348D01*
G02X1249880Y490086I1247J641D01*
G37*
G36*
G01X1819124Y490442D02*
X1824125D01*
G02X1825636Y488940I-1J-1512D01*
G01Y488845D01*
X1825627Y488761D01*
G02X1824125Y487418I-1502J169D01*
G01X1819124D01*
G02Y490442I0J1512D01*
G37*
G36*
G01X1796124D02*
X1801125D01*
G02X1802636Y488940I-1J-1512D01*
G01Y488845D01*
X1802627Y488761D01*
G02X1801125Y487418I-1502J169D01*
G01X1796124D01*
G02Y490442I0J1512D01*
G37*
G36*
G01X1784524D02*
X1789525D01*
G02X1791036Y488940I-1J-1512D01*
G01Y488845D01*
X1791027Y488761D01*
G02X1789525Y487418I-1502J169D01*
G01X1784524D01*
G02Y490442I0J1512D01*
G37*
G36*
G01X1811975Y487218D02*
X1806975D01*
G02Y490242I0J1512D01*
G01X1811975D01*
G02X1813486Y488740I-1J-1512D01*
G01Y488645D01*
X1813477Y488561D01*
G02X1811975Y487218I-1502J169D01*
G37*
G36*
G01X1754300Y486344D02*
X1749299D01*
G02X1749300Y489366I1J1511D01*
G01X1754300D01*
G02X1755812Y487865I0J-1512D01*
G01Y487770D01*
X1755802Y487686D01*
G02X1754300Y486344I-1502J170D01*
G37*
G36*
G01X1741900Y486244D02*
X1736899D01*
G02X1736900Y489266I1J1511D01*
G01X1741900D01*
G02X1743412Y487765I0J-1512D01*
G01Y487670D01*
X1743402Y487586D01*
G02X1741900Y486244I-1502J170D01*
G37*
G36*
G01X1770325Y485844D02*
X1765324D01*
G02X1765325Y488866I1J1511D01*
G01X1770325D01*
G02X1771836Y487365I0J-1511D01*
G01Y487270D01*
X1771827Y487186D01*
G02X1770325Y485844I-1502J169D01*
G37*
G36*
G01X1450607Y488218D02*
G03X1451188Y488206I296J268D01*
G02X1451149Y486281I1000J-983D01*
G03X1450568Y486293I-296J-268D01*
G02X1450607Y488218I-1000J983D01*
G37*
G36*
G01X721807Y486893D02*
G03X721585Y486360I145J-373D01*
G02X719794Y487107I-1285J-560D01*
G03X720016Y487640I-145J373D01*
G02X721934Y489451I1285J560D01*
G03X722487Y489661I181J357D01*
G02X723159Y487897I1305J-513D01*
G03X722606Y487687I-181J-357D01*
G02X721807Y486893I-1304J514D01*
G37*
G36*
G01X676752Y484669D02*
G03X676148Y484662I-299J-266D01*
G02X676128Y486501I-1068J908D01*
G03X676732Y486508I299J266D01*
G02X678732Y486647I1068J-908D01*
G03X679287Y486669I266J299D01*
G02X679368Y484653I1013J-969D01*
G03X678813Y484631I-266J-299D01*
G02X676752Y484669I-1013J969D01*
G37*
G36*
G01X1841471Y486239D02*
G03Y485661I277J-289D01*
G02X1839529I-971J-1011D01*
G03Y486239I-277J289D01*
G02X1841471I971J1011D01*
G37*
G36*
G01X610478Y485035D02*
G03X611039Y485021I288J278D01*
G02X610992Y483025I961J-1021D01*
G03X610431Y483039I-288J-278D01*
G02X610478Y485035I-961J1021D01*
G37*
G36*
G01X709168Y482570D02*
G03X708585Y482538I-277J-289D01*
G02X708480Y484452I-1074J901D01*
G03X709063Y484484I277J289D01*
G02X709168Y482570I1074J-901D01*
G37*
G36*
G01X1652882Y483774D02*
G03X1652896Y483210I290J-275D01*
G02X1650911Y483164I-970J-1013D01*
G03X1650897Y483728I-290J275D01*
G02X1652882Y483774I970J1013D01*
G37*
G36*
G01X1616627Y480390D02*
G03X1616073I-277J-288D01*
G02Y482410I-973J1010D01*
G03X1616627I277J288D01*
G02Y480390I973J-1010D01*
G37*
G36*
G01X1672021Y482589D02*
G03Y482011I277J-289D01*
G02X1670079I-971J-1011D01*
G03Y482589I-277J289D01*
G02X1672021I971J1011D01*
G37*
G36*
G01X606268Y482376D02*
G03X606278Y481843I303J-261D01*
G02X604187Y481806I-1029J-952D01*
G03X604177Y482339I-303J261D01*
G02X606268Y482376I1029J952D01*
G37*
G36*
G01X1291510Y481727D02*
G03Y481173I288J-277D01*
G02X1289490I-1010J-973D01*
G03Y481727I-288J277D01*
G02X1291510I1010J973D01*
G37*
G36*
G01X1794975Y477788D02*
X1789974D01*
G02X1789975Y480812I1J1512D01*
G01X1794975D01*
G02X1796486Y479310I-1J-1512D01*
G01Y479215D01*
X1796477Y479131D01*
G02X1794975Y477788I-1502J168D01*
G37*
G36*
G01X658794Y478143D02*
G03X658229Y478136I-279J-287D01*
G02X658203Y480122I-1002J980D01*
G03X658768Y480129I279J287D01*
G02X660708Y480191I1002J-980D01*
G03X661243I267J297D01*
G02Y478107I938J-1042D01*
G03X660708I-268J-297D01*
G02X658794Y478143I-938J1042D01*
G37*
G36*
G01X1817375Y476808D02*
X1812375D01*
G02Y479832I0J1512D01*
G01X1817375D01*
G02X1818886Y478330I-1J-1512D01*
G01Y478235D01*
X1818877Y478151D01*
G02X1817375Y476808I-1502J169D01*
G37*
G36*
G01X1829967Y475416D02*
X1825297D01*
G02Y478438I0J1511D01*
G01X1829967D01*
G02X1831478Y476937I0J-1511D01*
G01Y476842D01*
X1831469Y476758D01*
G02X1829967Y475416I-1502J169D01*
G37*
G36*
G01X1766700Y474144D02*
X1761699D01*
G02X1761700Y477166I1J1511D01*
G01X1766700D01*
G02X1768212Y475665I0J-1512D01*
G01Y475570D01*
X1768202Y475486D01*
G02X1766700Y474144I-1502J170D01*
G37*
G36*
G01X15473Y476510D02*
G03X16027I277J288D01*
G02Y474490I973J-1010D01*
G03X15473I-277J-288D01*
G02X13549Y474470I-973J1010D01*
G03X12988Y474451I-271J-294D01*
G02X12923Y476447I-1016J966D01*
G03X13484Y476466I271J294D01*
G02X15473Y476510I1016J-966D01*
G37*
G36*
G01X1779300Y473544D02*
X1774299D01*
G02X1774300Y476566I1J1511D01*
G01X1779300D01*
G02X1780812Y475065I0J-1512D01*
G01Y474970D01*
X1780802Y474886D01*
G02X1779300Y473544I-1502J170D01*
G37*
G36*
G01X1806525Y472444D02*
X1801524D01*
G02X1801525Y475466I1J1511D01*
G01X1806525D01*
G02X1808036Y473965I0J-1511D01*
G01Y473870D01*
X1808027Y473786D01*
G02X1806525Y472444I-1502J169D01*
G37*
G36*
G01X-13140Y474769D02*
G03X-12540I300J265D01*
G02Y472911I1050J-929D01*
G03X-13140I-300J-265D01*
G02Y474769I-1050J929D01*
G37*
G36*
G01X1679576Y472270D02*
G03X1679022Y472244I-263J-301D01*
G02X1678925Y474260I-1021J961D01*
G03X1679479Y474286I263J301D01*
G02X1679576Y472270I1021J-961D01*
G37*
G36*
G01X1895789Y469229D02*
G03X1895211I-289J-277D01*
G02X1893117Y471090I-1011J971D01*
G03X1893095Y471623I-309J254D01*
G02X1895111Y473571I1005J977D01*
G03X1895689I289J277D01*
G02X1897634Y473646I1011J-971D01*
G03X1898166I266J298D01*
G02X1900111Y473571I934J-1046D01*
G03X1900689I289J277D01*
G02X1902632Y473647I1011J-971D01*
G03X1903187Y473669I266J299D01*
G02X1905283Y471810I1013J-969D01*
G03X1905305Y471277I309J-254D01*
G02X1903368Y469253I-1005J-977D01*
G03X1902813Y469231I-266J-299D01*
G02X1900789Y469229I-1013J969D01*
G03X1900211I-289J-277D01*
G02X1898266Y469154I-1011J971D01*
G03X1897734I-266J-298D01*
G02X1895789Y469229I-934J1046D01*
G37*
G36*
G01X1634422Y471660D02*
G03X1634365Y471124I265J-299D01*
G02X1632012Y471373I-1290J-950D01*
G03X1632069Y471909I-265J299D01*
G02X1634422Y471660I1290J950D01*
G37*
G36*
G01X1915424Y468001D02*
G03X1916048I312J250D01*
G02X1916047Y465998I1250J-1002D01*
G03X1915423I-312J-250D01*
G02X1912903Y466023I-1250J1002D01*
G03X1912269I-317J-243D01*
G02Y467977I-1270J977D01*
G03X1912903I317J243D01*
G02X1915424Y468001I1270J-977D01*
G37*
G36*
G01X1463389Y464529D02*
G03X1462811I-289J-277D01*
G02Y466471I-1011J971D01*
G03X1463389I289J277D01*
G02Y464529I1011J-971D01*
G37*
G36*
G01X1455589D02*
G03X1455011I-289J-277D01*
G02Y466471I-1011J971D01*
G03X1455589I289J277D01*
G02Y464529I1011J-971D01*
G37*
G36*
G01X1667496Y465448D02*
G03X1667236Y465939I-384J111D01*
G02X1666657Y466306I438J1332D01*
G03X1666074Y466303I-290J-276D01*
G02X1666064Y468222I-1027J954D01*
G03X1666647Y468225I290J276D01*
G02X1669021Y466883I1027J-954D01*
G03X1669281Y466392I384J-111D01*
G02X1667496Y465448I-438J-1332D01*
G37*
G36*
G01X1322493Y464943D02*
G03X1323080Y464737I377J134D01*
G02X1322494Y463074I735J-1194D01*
G03X1321907Y463280I-377J-134D01*
G02X1322493Y464943I-735J1194D01*
G37*
G36*
G01X1343133Y462606D02*
G03X1342564Y462583I-273J-292D01*
G02X1342485Y464552I-1036J945D01*
G03X1343054Y464575I273J292D01*
G02X1345126I1036J-945D01*
G03X1345714Y464571I296J269D01*
G02X1345703Y462670I1025J-956D01*
G03X1345115Y462674I-296J-269D01*
G02X1343133Y462606I-1025J956D01*
G37*
G36*
G01X1624247Y462902D02*
G03X1624014Y462389I142J-374D01*
G02X1622202Y463211I-1314J-489D01*
G03X1622435Y463724I-142J374D01*
G02X1624247Y462902I1314J489D01*
G37*
G36*
G01X1586502Y459200D02*
G03X1585948I-277J-288D01*
G02X1583863Y459356I-973J1010D01*
G03X1583247Y459378I-317J-244D01*
G02X1580798Y460293I-1047J932D01*
G03X1580392Y460688I-400J-5D01*
G02X1581772Y462107I-22J1402D01*
G03X1582178Y461712I400J5D01*
G02X1582413Y461696I23J-1402D01*
G03X1582857Y462206I61J395D01*
G02X1585455Y461984I1343J404D01*
G03X1585627Y461451I358J-179D01*
G02X1585948Y461220I-650J-1242D01*
G03X1586502I277J288D01*
G02Y459200I973J-1010D01*
G37*
G36*
G01X1463389Y458829D02*
G03X1462811I-289J-277D01*
G02Y460771I-1011J971D01*
G03X1463389I289J277D01*
G02Y458829I1011J-971D01*
G37*
G36*
G01X1455589D02*
G03X1455011I-289J-277D01*
G02Y460771I-1011J971D01*
G03X1455589I289J277D01*
G02Y458829I1011J-971D01*
G37*
G36*
G01X1640942Y458579D02*
G03X1640920Y457958I241J-319D01*
G02X1639158Y458021I-920J-1058D01*
G03X1639180Y458642I-241J319D01*
G02X1640942Y458579I920J1058D01*
G37*
G36*
G01X1685410Y458414D02*
G03Y457839I279J-288D01*
G02X1683460I-975J-1007D01*
G03Y458414I-279J287D01*
G02X1685410I975J1007D01*
G37*
G36*
G01X1676848Y457738D02*
G03X1676782Y457142I230J-327D01*
G02X1674937Y457346I-1038J-942D01*
G03X1675003Y457942I-230J327D01*
G02X1676848Y457738I1038J942D01*
G37*
G36*
G01X1529333Y455957D02*
G03X1529260Y455398I245J-316D01*
G02X1527289Y455655I-1113J-852D01*
G03X1527362Y456214I-245J316D01*
G02X1529333Y455957I1113J852D01*
G37*
G36*
G01X1463389Y453129D02*
G03X1462811I-289J-277D01*
G02Y455071I-1011J971D01*
G03X1463389I289J277D01*
G02Y453129I1011J-971D01*
G37*
G36*
G01X1455589D02*
G03X1455011I-289J-277D01*
G02Y455071I-1011J971D01*
G03X1455589I289J277D01*
G02Y453129I1011J-971D01*
G37*
G36*
G01X1411986Y457571D02*
Y453476D01*
X1411977Y453392D01*
G02X1408964Y453561I-1502J169D01*
G01Y457561D01*
G02X1411986Y457571I1511J0D01*
G37*
G36*
G01X1404286D02*
Y453476D01*
X1404277Y453392D01*
G02X1401264Y453561I-1502J169D01*
G01Y457561D01*
G02X1404286Y457571I1511J0D01*
G37*
G36*
G01X1396886D02*
Y453476D01*
X1396877Y453392D01*
G02X1393864Y453561I-1502J169D01*
G01Y457562D01*
G02X1396886Y457571I1511J-1D01*
G37*
G36*
G01X1589693Y453068D02*
G03X1590295Y453064I303J261D01*
G02X1590283Y451217I1049J-930D01*
G03X1589681Y451221I-303J-261D01*
G02X1587504Y451319I-1049J930D01*
G03X1586902Y451367I-322J-238D01*
G02X1584927Y451378I-982J1001D01*
G03X1584325Y451338I-284J-282D01*
G02X1584201Y453175I-1117J847D01*
G03X1584803Y453215I284J282D01*
G02X1587048Y453200I1117J-847D01*
G03X1587650Y453152I322J238D01*
G02X1589693Y453068I982J-1001D01*
G37*
G36*
G01X1620175Y453672D02*
G03X1620664Y453361I393J77D01*
G02X1619625Y451728I336J-1361D01*
G03X1619136Y452039I-393J-77D01*
G02X1620175Y453672I-336J1361D01*
G37*
G36*
G01X1662542Y452789D02*
G03X1662548Y452234I291J-274D01*
G02X1660529Y452213I-999J-983D01*
G03X1660523Y452768I-291J274D01*
G02X1660492Y454703I999J984D01*
G03X1660481Y455257I-294J271D01*
G02X1662500Y455299I989J994D01*
G03X1662511Y454745I294J-271D01*
G02X1662542Y452789I-989J-994D01*
G37*
G36*
G01X1867886Y451591D02*
G03X1867450Y451172I-36J-398D01*
G02X1866179Y452496I-1400J-72D01*
G03X1866615Y452915I36J398D01*
G02X1869093Y453883I1400J72D01*
G03X1869715Y453891I308J256D01*
G02X1869737Y452126I1100J-869D01*
G03X1869115Y452118I-308J-256D01*
G02X1867886Y451591I-1100J869D01*
G37*
G36*
G01X1836495Y449088D02*
X1831494D01*
G02X1831495Y452112I1J1512D01*
G01X1836495D01*
G02X1838006Y450610I-1J-1512D01*
G01Y450515D01*
X1837997Y450431D01*
G02X1836495Y449088I-1502J168D01*
G37*
G36*
G01X1818760Y451920D02*
X1823760D01*
G02X1825272Y450418I0J-1512D01*
G01Y450323D01*
X1825262Y450239D01*
G02X1823760Y448896I-1502J169D01*
G01X1818760D01*
G02Y451920I0J1512D01*
G37*
G36*
G01X1811161Y448896D02*
X1806161D01*
G02Y451920I0J1512D01*
G01X1811161D01*
G02X1812672Y450418I-1J-1512D01*
G01Y450323D01*
X1812663Y450239D01*
G02X1811161Y448896I-1502J169D01*
G37*
G36*
G01X1793562Y451920D02*
X1798563D01*
G02X1800074Y450418I-1J-1512D01*
G01Y450323D01*
X1800065Y450239D01*
G02X1798563Y448896I-1502J169D01*
G01X1793562D01*
G02Y451920I1J1512D01*
G37*
G36*
G01X1780963D02*
X1785964D01*
G02X1787476Y450418I0J-1512D01*
G01Y450323D01*
X1787466Y450239D01*
G02X1785964Y448896I-1502J168D01*
G01X1780963D01*
G02Y451920I0J1512D01*
G37*
G36*
G01X1768366D02*
X1773366D01*
G02X1774878Y450418I0J-1512D01*
G01Y450323D01*
X1774868Y450239D01*
G02X1773366Y448896I-1502J169D01*
G01X1768366D01*
G02Y451920I0J1512D01*
G37*
G36*
G01X1760767Y448896D02*
X1755767D01*
G02Y451920I0J1512D01*
G01X1760767D01*
G02X1762278Y450418I-1J-1512D01*
G01Y450323D01*
X1762269Y450239D01*
G02X1760767Y448896I-1502J169D01*
G37*
G36*
G01X1748169D02*
X1743169D01*
G02Y451920I0J1512D01*
G01X1748169D01*
G02X1749680Y450418I-1J-1512D01*
G01Y450323D01*
X1749671Y450239D01*
G02X1748169Y448896I-1502J169D01*
G37*
G36*
G01X1470989Y449026D02*
G03X1470411I-289J-277D01*
G02Y450968I-1011J971D01*
G03X1470989I289J277D01*
G02Y449026I1011J-971D01*
G37*
G36*
G01X1463189D02*
G03X1462611I-289J-277D01*
G02Y450968I-1011J971D01*
G03X1463189I289J277D01*
G02Y449026I1011J-971D01*
G37*
G36*
G01X1631268Y451086D02*
G03X1631263Y450513I277J-289D01*
G02X1629308Y450531I-987J-996D01*
G03X1629313Y451104I-277J289D01*
G02X1629282Y453064I987J996D01*
G03X1629260Y453635I-291J275D01*
G02X1629190Y455648I940J1040D01*
G03Y456202I-288J277D01*
G02X1631210I1010J973D01*
G03Y455648I288J-277D01*
G02X1631218Y453711I-1010J-973D01*
G03X1631240Y453140I291J-275D01*
G02X1631268Y451086I-940J-1040D01*
G37*
G36*
G01X1682201Y450789D02*
G03X1682187Y450234I281J-285D01*
G02X1680168Y450283I-1033J-948D01*
G03X1680182Y450838I-281J285D01*
G02X1682201Y450789I1033J948D01*
G37*
G36*
G01X1873831Y449539D02*
G03Y448961I277J-289D01*
G02X1871889I-971J-1011D01*
G03Y449539I-277J289D01*
G02X1873831I971J1011D01*
G37*
G36*
G01X1887937Y446834D02*
G03X1887409Y446826I-259J-304D01*
G02X1887369Y449230I-1079J1184D01*
G03X1887897Y449238I259J304D01*
G02X1890236Y449043I1079J-1184D01*
G03X1890866I315J247D01*
G02X1893386I1260J-989D01*
G03X1894015I315J247D01*
G02Y447065I1260J-989D01*
G03X1893386I-314J-247D01*
G02X1890866I-1260J989D01*
G03X1890236I-315J-247D01*
G02X1887937Y446834I-1260J989D01*
G37*
G36*
G01X1647500Y449140D02*
G03X1647513Y448585I294J-271D01*
G02X1645494Y448540I-988J-995D01*
G03X1645481Y449095I-294J271D01*
G02X1645452Y451055I988J995D01*
G03X1645448Y451610I-290J275D01*
G02X1647468Y451625I1003J980D01*
G03X1647472Y451070I290J-275D01*
G02X1647500Y449140I-1003J-980D01*
G37*
G36*
G01X1677288Y448795D02*
G03X1677284Y448229I281J-285D01*
G02X1675303Y448243I-998J-985D01*
G03X1675307Y448809I-281J285D01*
G02X1677288Y448795I998J985D01*
G37*
G36*
G01X1674076Y447548D02*
G03X1674075Y446993I288J-278D01*
G02X1672056Y446996I-1011J-971D01*
G03X1672057Y447551I-288J278D01*
G02X1674076Y447548I1011J971D01*
G37*
G36*
G01X-719Y455008D02*
G03X-446Y455489I-115J383D01*
G02X2653Y455455I1554J390D01*
G03X2899Y454974I386J-106D01*
G02X3557Y452433I-560J-1501D01*
G03Y451913I304J-260D01*
G02Y449833I-1218J-1040D01*
G03Y449313I304J-260D01*
G02Y447233I-1218J-1040D01*
G03Y446713I304J-260D01*
G02X1299Y444455I-1218J-1040D01*
G03X779I-260J-304D01*
G02X-1479Y446713I-1040J1218D01*
G03Y447233I-304J260D01*
G02Y449313I1218J1040D01*
G03Y449833I-304J260D01*
G02Y451913I1218J1040D01*
G03Y452433I-304J260D01*
G02X-719Y455008I1218J1040D01*
G37*
G36*
G01X6783Y448093D02*
G03X7303I260J304D01*
G02X9791Y447561I1040J-1218D01*
G03X10362Y447392I361J171D01*
G02X9895Y445483I738J-1192D01*
G03X9310Y445598I-344J-204D01*
G02X7187Y445766I-967J1277D01*
G03X6899I-144J-139D01*
G02X6852Y445719I-1156J1109D01*
G03Y445431I139J-144D01*
G02X4525Y445315I-1109J-1156D01*
G03Y445835I-304J260D01*
G02X6783Y448093I1218J1040D01*
G37*
G36*
G01X1670826Y445480D02*
G03Y444926I288J-277D01*
G02X1668806I-1010J-973D01*
G03Y445480I-288J277D01*
G02Y447426I1010J973D01*
G03Y447980I-288J277D01*
G02X1670826I1010J973D01*
G03Y447426I288J-277D01*
G02Y445480I-1010J-973D01*
G37*
G36*
G01X1718140Y442709D02*
G03X1717978Y443287I-335J218D01*
G02X1717595Y443559I609J1263D01*
G03X1717029I-283J-282D01*
G02Y445541I-992J991D01*
G03X1717595I283J282D01*
G02X1719764Y443788I992J-991D01*
G03X1719926Y443210I335J-218D01*
G02X1718140Y442709I-609J-1263D01*
G37*
G36*
G01X10786Y443296D02*
X15787D01*
G02X17298Y441795I0J-1512D01*
G01Y441700D01*
X17288Y441616D01*
G02X15786Y440274I-1502J170D01*
G01X10786D01*
G02Y443296I0J1511D01*
G37*
G36*
G01X1413300Y442491D02*
G03X1413324Y441870I264J-301D01*
G02X1411559Y441802I-841J-1122D01*
G03X1411535Y442423I-264J301D01*
G02X1413300Y442491I841J1122D01*
G37*
G36*
G01X1589900Y441497D02*
G03X1590472Y441480I294J271D01*
G02X1590416Y439521I974J-1008D01*
G03X1589844Y439538I-294J-271D01*
G02X1589900Y441497I-974J1008D01*
G37*
G36*
G01X1613207Y441666D02*
G03X1613223Y441103I292J-273D01*
G02X1611232Y441045I-967J-1015D01*
G03X1611216Y441608I-292J273D01*
G02X1613207Y441666I967J1015D01*
G37*
G36*
G01X22936Y444354D02*
G02X25958Y444364I1511J0D01*
G01Y439354D01*
X25959D01*
X25958Y439269D01*
X25949Y439185D01*
G02X22936Y439354I-1502J169D01*
G01Y444354D01*
G37*
G36*
G01X750525Y439327D02*
G03X749900Y438975I-226J-330D01*
G02X747401Y439770I-1400J-75D01*
G03X747278Y440369I-314J248D01*
G02X748440Y442914I672J1231D01*
G03X748971Y443205I140J375D01*
G02X750525Y439327I3670J-780D01*
G37*
G36*
G01X1409123Y439924D02*
G03Y439309I257J-307D01*
G02X1407327I-898J-1076D01*
G03Y439924I-257J307D01*
G02X1409123I898J1076D01*
G37*
G36*
G01X1506427Y436187D02*
G03X1506443Y435632I296J-269D01*
G02X1504427Y435576I-981J-1002D01*
G03X1504411Y436131I-296J269D01*
G02X1506427Y436187I981J1002D01*
G37*
G36*
G01X1640510Y434727D02*
G03Y434173I288J-277D01*
G02X1638490I-1010J-973D01*
G03Y434727I-288J277D01*
G02X1640510I1010J973D01*
G37*
G36*
G01X1461099Y431902D02*
G03X1460510I-294J-271D01*
G02Y433800I-1032J949D01*
G03X1461099I295J271D01*
G02Y431902I1032J-949D01*
G37*
G36*
G01X1468386Y433869D02*
G03X1468958Y433852I294J271D01*
G02X1468900Y431892I973J-1010D01*
G03X1468328Y431909I-294J-271D01*
G02X1468386Y433869I-973J1010D01*
G37*
G36*
G01X1588351Y433445D02*
G03X1588973Y433428I318J243D01*
G02X1588924Y431663I1064J-913D01*
G03X1588302Y431680I-318J-243D01*
G02X1588351Y433445I-1064J913D01*
G37*
G36*
G01X1410812Y434785D02*
Y429690D01*
X1410802Y429606D01*
G02X1407788Y429775I-1502J169D01*
G01Y434776D01*
G02X1410812Y434785I1512J-1D01*
G37*
G36*
G01X1402910D02*
Y429690D01*
X1402900Y429606D01*
G02X1399886Y429775I-1502J169D01*
G01Y434776D01*
G02X1402910Y434785I1512J-1D01*
G37*
G36*
G01X1468885Y427046D02*
G03X1468305I-290J-276D01*
G02Y428980I-1015J967D01*
G03X1468885I290J276D01*
G02Y427046I1015J-967D01*
G37*
G36*
G01X1548776Y429391D02*
G03Y428844I292J-274D01*
G02X1546732I-1022J-960D01*
G03Y429391I-292J274D01*
G02X1548097Y431710I1022J960D01*
G03X1548579Y431986I98J388D01*
G02X1549582Y430235I1346J-392D01*
G03X1549100Y429959I-98J-388D01*
G02X1548776Y429391I-1346J392D01*
G37*
G36*
G01X1583820Y426607D02*
G03X1583311Y426307I-118J-382D01*
G02X1582352Y427934I-1372J287D01*
G03X1582861Y428234I118J382D01*
G02X1583820Y426607I1372J-287D01*
G37*
G36*
G01X17025Y423338D02*
X12024D01*
G02X12025Y426362I1J1512D01*
G01X17025D01*
G02X18536Y424860I-1J-1512D01*
G01Y424765D01*
X18527Y424681D01*
G02X17025Y423338I-1502J168D01*
G37*
G36*
G01X7025D02*
X2024D01*
G02X2025Y426362I1J1512D01*
G01X7025D01*
G02X8536Y424860I-1J-1512D01*
G01Y424765D01*
X8527Y424681D01*
G02X7025Y423338I-1502J168D01*
G37*
G36*
G01X62516Y424220D02*
X62507Y424136D01*
G02X59494Y424305I-1502J169D01*
G01Y429306D01*
G02X62516Y429315I1511J-1D01*
G01Y424220D01*
G37*
G36*
G01X1589368Y424272D02*
G03X1588961Y423864I-7J-400D01*
G02X1587587Y425237I-1402J-29D01*
G03X1587994Y425645I7J400D01*
G02X1589368Y424272I1402J29D01*
G37*
G36*
G01X1559675Y420042D02*
X1555775D01*
G02Y422866I0J1412D01*
G01X1559676D01*
G02X1561086Y421464I-1J-1412D01*
G01Y421370D01*
X1561076Y421286D01*
G02X1559675Y420042I-1401J167D01*
G37*
G36*
G01X1548790Y422624D02*
G03Y422084I295J-270D01*
G02X1546720I-1035J-946D01*
G03Y422624I-295J270D01*
G02X1548139Y424918I1035J946D01*
G03X1548629Y425181I109J385D01*
G02X1549580Y423405I1335J-428D01*
G03X1549090Y423142I-109J-385D01*
G02X1548790Y422624I-1335J427D01*
G37*
G36*
G01X1504996Y419784D02*
G03X1504478Y419514I-133J-377D01*
G02X1501738Y419711I-1350J378D01*
G03X1501304Y420058I-397J-51D01*
G02X1502565Y421635I-129J1396D01*
G03X1502999Y421288I397J51D01*
G02X1503591Y421215I128J-1396D01*
G03X1504109Y421485I133J377D01*
G02X1504508Y422137I1350J-378D01*
G03X1504541Y422692I-271J295D01*
G02X1506556Y422574I1064J912D01*
G03X1506523Y422019I271J-295D01*
G02X1504996Y419784I-1065J-912D01*
G37*
G36*
G01X50776Y424005D02*
Y418910D01*
X50767Y418826D01*
G02X47754Y418995I-1502J169D01*
G01Y423996D01*
G02X50776Y424005I1511J-1D01*
G37*
G36*
G01X1557725Y416662D02*
X1553824D01*
G02X1553825Y419486I1J1412D01*
G01X1554448D01*
G02X1554998Y418963I0J-551D01*
G03X1555016Y418813I777J17D01*
G02X1555159Y418507I-1189J-742D01*
G03X1556391I616J472D01*
G02X1556534Y418813I1332J-436D01*
G03X1556550Y419022I-759J163D01*
G02X1557050Y419486I500J-37D01*
G01X1557725D01*
G02X1559136Y418084I0J-1411D01*
G01Y417990D01*
X1559126Y417906D01*
G02X1557725Y416662I-1401J167D01*
G37*
G36*
G01X1413476Y416907D02*
X1413461Y417081D01*
X1413626Y421997D01*
X1413634Y422005D01*
X1413640Y422078D01*
G02X1416647Y422124I1506J-131D01*
G01X1416668Y421948D01*
X1416504Y417042D01*
X1416505D01*
X1416502Y416988D01*
X1416477Y416817D01*
G02X1413476Y416907I-1495J222D01*
G37*
G36*
G01X1405646Y421576D02*
G02X1408670Y421585I1512J-1D01*
G01Y416490D01*
X1408660Y416406D01*
G02X1405646Y416572I-1502J167D01*
G01Y421576D01*
G37*
G36*
G01X1567475Y413282D02*
X1563574D01*
G02X1563575Y416106I1J1412D01*
G01X1564198D01*
G02X1564748Y415583I0J-551D01*
G03X1564766Y415433I777J17D01*
G02X1564909Y415127I-1189J-742D01*
G03X1566141I616J472D01*
G02X1566284Y415433I1332J-436D01*
G03X1566300Y415642I-759J163D01*
G02X1566800Y416106I500J-37D01*
G01X1567475D01*
G02X1568886Y414704I0J-1411D01*
G01Y414610D01*
X1568876Y414526D01*
G02X1567475Y413282I-1401J167D01*
G37*
G36*
G01X767237Y416062D02*
G03X767281Y415483I296J-269D01*
G02X765357Y415340I-887J-1086D01*
G03X765313Y415919I-296J269D01*
G02X766261Y418406I887J1086D01*
G03X766678Y418800I17J399D01*
G02X768019Y417379I1402J-20D01*
G03X767602Y416985I-17J-399D01*
G02X767237Y416062I-1402J21D01*
G37*
G36*
G01X47006Y415201D02*
G03Y414590I258J-306D01*
G02X45194I-906J-1070D01*
G03Y415201I-258J305D01*
G02X47006I906J1070D01*
G37*
G36*
G01X1471147Y413091D02*
G03X1471720Y413069I297J268D01*
G02X1471647Y411116I968J-1014D01*
G03X1471074Y411138I-297J-268D01*
G02X1471147Y413091I-968J1014D01*
G37*
G36*
G01X1588551Y411003D02*
G03X1587996Y410990I-271J-295D01*
G02X1587949Y413008I-996J986D01*
G03X1588504Y413021I271J295D01*
G02X1588551Y411003I996J-986D01*
G37*
G36*
G01X120018Y413220D02*
G03X120037Y412643I286J-279D01*
G02X118098Y412581I-937J-1043D01*
G03X118079Y413158I-286J279D01*
G02X120018Y413220I937J1043D01*
G37*
G36*
G01X20473Y414391D02*
G03X21740Y414794I-2J2199D01*
G02X21756Y410156I1488J-2314D01*
G03X20502Y410569I-1283J-1786D01*
G01X20471D01*
G03X19204Y410166I2J-2199D01*
G02X19188Y414804I-1488J2314D01*
G03X20442Y414391I1283J1786D01*
G01X20473D01*
G37*
G36*
G01X3938D02*
G03X5205Y414794I-2J2199D01*
G02X5221Y410156I1488J-2314D01*
G03X3967Y410569I-1283J-1786D01*
G01X3936D01*
G03X2669Y410166I2J-2199D01*
G02X2653Y414804I-1488J2314D01*
G03X3907Y414391I1283J1786D01*
G01X3938D01*
G37*
G36*
G01X-12598D02*
G03X-11331Y414794I-2J2199D01*
G02X-11315Y410156I1488J-2314D01*
G03X-12569Y410569I-1283J-1786D01*
G01X-12599D01*
G03X-13866Y410166I2J-2199D01*
G02X-13882Y414804I-1488J2314D01*
G03X-12628Y414391I1283J1786D01*
G01X-12598D01*
G37*
G36*
G01X749612Y408828D02*
G03X749058I-277J-288D01*
G02X747075Y410811I-973J1010D01*
G03Y411365I-288J277D01*
G02X749058Y413348I1010J973D01*
G03X749612I277J288D01*
G02X751558I973J-1010D01*
G03X752112I277J288D01*
G02X753991Y413408I973J-1010D01*
G03X754524Y413422I259J305D01*
G02X755905Y413741I963J-1019D01*
G03X756424Y414133I119J382D01*
G02X758799Y415177I1402J34D01*
G03X759353I277J288D01*
G02X761303Y415172I972J-1010D01*
G03X761912Y415233I279J287D01*
G02X763960Y413358I1157J-793D01*
G03X763942Y412756I254J-309D01*
G02X761975Y410760I-953J-1028D01*
G03X761384Y410747I-290J-276D01*
G02X759353Y410657I-1058J920D01*
G03X758799I-277J-288D01*
G02X757408Y410329I-972J1010D01*
G03X756889Y409937I-119J-382D01*
G02X754581Y408833I-1402J-34D01*
G03X754048Y408819I-259J-305D01*
G02X752112Y408828I-963J1019D01*
G03X751558I-277J-288D01*
G02X749612I-973J1010D01*
G37*
G36*
G01X1403912Y408281D02*
Y413282D01*
G02X1406934Y413291I1511J-1D01*
G01Y408281D01*
X1406935D01*
X1406934Y408196D01*
X1406925Y408112D01*
G02X1403912Y408281I-1502J169D01*
G37*
G36*
G01X1571375Y406522D02*
X1567474D01*
G02X1567475Y409346I1J1412D01*
G01X1568098D01*
G02X1568648Y408823I0J-551D01*
G03X1568666Y408673I777J17D01*
G02X1568809Y408367I-1189J-742D01*
G03X1570041I616J472D01*
G02X1570184Y408673I1332J-436D01*
G03X1570200Y408882I-759J163D01*
G02X1570700Y409346I500J-37D01*
G01X1571375D01*
G02X1572786Y407944I0J-1411D01*
G01Y407850D01*
X1572776Y407766D01*
G02X1571375Y406522I-1401J167D01*
G37*
G36*
G01X1444049Y407876D02*
G03X1443955Y407308I227J-329D01*
G02X1442033Y407625I-1125J-836D01*
G03X1442127Y408193I-227J329D01*
G02X1444049Y407876I1125J836D01*
G37*
G36*
G01X106158Y407656D02*
G03X105910Y407071I100J-387D01*
G02X104120Y407831I-1393J-792D01*
G03X104368Y408416I-100J387D01*
G02X105975Y410796I1393J792D01*
G03X106425Y411249I54J396D01*
G02X107796Y409891I1585J230D01*
G03X107346Y409438I-54J-396D01*
G02X106158Y407656I-1585J-230D01*
G37*
G36*
G01X120709Y404984D02*
G03X120136Y405156I-363J-168D01*
G02X120670Y406937I-738J1192D01*
G03X121243Y406765I363J168D01*
G02X120709Y404984I738J-1192D01*
G37*
G36*
G01X53088Y406598D02*
X55227Y409137D01*
G02X57894Y408173I1156J-974D01*
G01Y408078D01*
X57885Y407994D01*
G02X57539Y407189I-1503J169D01*
G01X56228Y405632D01*
X56227D01*
X55422Y404678D01*
X55421Y404676D01*
G02X53088Y406598I-1177J948D01*
G37*
G36*
G01X1589833Y402984D02*
G03X1589253Y402806I-214J-338D01*
G02X1588716Y404554I-1285J562D01*
G03X1589296Y404732I214J338D01*
G02X1589833Y402984I1285J-562D01*
G37*
G36*
G01X25591Y406517D02*
G03X26858Y406920I-2J2199D01*
G02X26874Y402282I1488J-2314D01*
G03X25620Y402695I-1283J-1786D01*
G01X25590D01*
G03X24323Y402292I2J-2199D01*
G02X24307Y406930I-1488J2314D01*
G03X25561Y406517I1283J1786D01*
G01X25591D01*
G37*
G36*
G01X9056D02*
G03X10323Y406920I-2J2199D01*
G02X10339Y402282I1488J-2314D01*
G03X9085Y402695I-1283J-1786D01*
G01X9054D01*
G03X7787Y402292I2J-2199D01*
G02X7771Y406930I-1488J2314D01*
G03X9025Y406517I1283J1786D01*
G01X9056D01*
G37*
G36*
G01X-7480D02*
G03X-6213Y406920I-2J2199D01*
G02X-6197Y402282I1488J-2314D01*
G03X-7451Y402695I-1283J-1786D01*
G01X-7481D01*
G03X-8748Y402292I2J-2199D01*
G02X-8764Y406930I-1488J2314D01*
G03X-7510Y406517I1283J1786D01*
G01X-7480D01*
G37*
G36*
G01X66896Y403268D02*
Y403173D01*
X66886Y403089D01*
G02X64311Y402193I-1502J169D01*
G01X61973Y404550D01*
X61972Y404551D01*
G02X64097Y406701I1052J1085D01*
G01X65153Y405638D01*
X66457Y404323D01*
G02X66896Y403268I-1073J-1065D01*
G37*
G36*
G01X1383327Y397890D02*
G03X1382773I-277J-288D01*
G02X1380751Y399830I-973J1010D01*
G03X1380740Y400372I-299J265D01*
G02X1380658Y400466I1015J968D01*
G03X1380346I-156J-125D01*
G02X1378023Y400669I-1094J877D01*
G03X1377479Y400826I-350J-193D01*
G02X1375827Y401043I-679J1227D01*
G03X1375273I-277J-288D01*
G02Y403063I-973J1010D01*
G03X1375827I277J288D01*
G02X1378029Y402727I973J-1010D01*
G03X1378573Y402570I350J193D01*
G02X1380225Y402353I679J-1227D01*
G03X1380779I277J288D01*
G02X1382725I973J-1010D01*
G03X1383279I277J288D01*
G02X1385225I973J-1010D01*
G03X1385779I277J288D01*
G02X1387801Y400413I973J-1010D01*
G03X1387812Y399871I299J-265D01*
G02X1385827Y397890I-1012J-971D01*
G03X1385273I-277J-288D01*
G02X1383327I-973J1010D01*
G37*
G36*
G01X1586703Y396411D02*
G03X1586141Y396408I-279J-286D01*
G02X1586130Y398403I-991J992D01*
G03X1586692Y398406I279J286D01*
G02X1586703Y396411I991J-992D01*
G37*
G36*
G01X102620Y396017D02*
G03X102080I-270J-295D01*
G02X99817Y398280I-1080J1183D01*
G03Y398820I-295J270D01*
G02X102080Y401083I1183J1080D01*
G03X102620I270J295D01*
G02X104780I1080J-1183D01*
G03X105320I270J295D01*
G02X107480I1080J-1183D01*
G03X108020I270J295D01*
G02X110562Y400555I1080J-1183D01*
G03X111054Y400339I365J163D01*
G02X111173Y397265I507J-1520D01*
G03X110681Y396941I-97J-388D01*
G02X108020Y396017I-1581J259D01*
G03X107480I-270J-295D01*
G02X105320I-1080J1183D01*
G03X104780I-270J-295D01*
G02X102620I-1080J1183D01*
G37*
G36*
G01X1370996Y395697D02*
G03X1370418I-289J-277D01*
G02Y397639I-1011J971D01*
G03X1370996I289J277D01*
G02Y395697I1011J-971D01*
G37*
G36*
G01X1655811Y398206D02*
G03X1655831Y397649I297J-268D01*
G02X1653820Y397576I-970J-1012D01*
G03X1653800Y398133I-297J268D01*
G02X1653776Y400133I970J1012D01*
G03X1653784Y400688I-284J282D01*
G02X1655803Y400657I1024J957D01*
G03X1655795Y400102I284J-282D01*
G02X1655811Y398206I-1025J-957D01*
G37*
G36*
G01X3938Y398643D02*
G03X5205Y399046I-2J2199D01*
G02X5221Y394408I1488J-2314D01*
G03X3967Y394821I-1283J-1786D01*
G01X3936D01*
G03X2669Y394418I2J-2199D01*
G02X2653Y399056I-1488J2314D01*
G03X3907Y398643I1283J1786D01*
G01X3938D01*
G37*
G36*
G01X-12598D02*
G03X-11331Y399046I-2J2199D01*
G02X-11315Y394408I1488J-2314D01*
G03X-12569Y394821I-1283J-1786D01*
G01X-12599D01*
G03X-13866Y394418I2J-2199D01*
G02X-13882Y399056I-1488J2314D01*
G03X-12628Y398643I1283J1786D01*
G01X-12598D01*
G37*
G36*
G01X776372Y395822D02*
G03X776297Y395251I238J-322D01*
G02X774170Y395478I-1175J-935D01*
G03X774217Y396052I-253J310D01*
G02X774190Y396084I1211J1049D01*
G03X773893Y396095I-153J-128D01*
G02X771901Y395846I-1151J1114D01*
G03X771307Y395618I-210J-340D01*
G02X768542Y395042I-1537J452D01*
G03X767960Y395076I-307J-257D01*
G02X768088Y397268I-1100J1164D01*
G03X768670Y397234I307J257D01*
G02X770611Y397433I1100J-1164D01*
G03X771205Y397661I210J340D01*
G02X773857Y398359I1537J-452D01*
G03X774392Y398339I279J287D01*
G02X776372Y395822I1028J-1228D01*
G37*
G36*
G01X188611Y394532D02*
G03X189210Y394332I377J133D01*
G02X188589Y392468I890J-1332D01*
G03X187990Y392668I-377J-133D01*
G02X188611Y394532I-890J1332D01*
G37*
G36*
G01X66236Y391560D02*
X66227Y391476D01*
G02X63214Y391645I-1502J169D01*
G01Y396645D01*
G02X66236Y396655I1511J0D01*
G01Y391560D01*
G37*
G36*
G01X1662125Y389274D02*
G03X1662056Y388723I251J-311D01*
G02X1660052Y388973I-1122J-840D01*
G03X1660121Y389524I-251J311D01*
G02X1660264Y391367I1122J840D01*
G03Y391940I-280J286D01*
G02X1662222I979J1003D01*
G03Y391367I280J-286D01*
G02X1662125Y389274I-979J-1003D01*
G37*
G36*
G01X25591Y390769D02*
G03X26858Y391172I-2J2199D01*
G02X26874Y386534I1488J-2314D01*
G03X25620Y386947I-1283J-1786D01*
G01X25590D01*
G03X24323Y386544I2J-2199D01*
G02X24307Y391182I-1488J2314D01*
G03X25561Y390769I1283J1786D01*
G01X25591D01*
G37*
G36*
G01X702030Y383117D02*
G03X701477Y383037I-236J-323D01*
G02X698986Y385050I-1273J972D01*
G03Y385570I-304J260D01*
G02X699283Y387921I1218J1040D01*
G03X699320Y388545I-230J327D01*
G02X699248Y390859I1071J1191D01*
G03X699228Y391439I-285J281D01*
G02X699243Y393849I1063J1198D01*
G03X699276Y394421I-262J302D01*
G02X701339Y396841I1181J1082D01*
G03X701880Y396938I219J334D01*
G02X704312Y397109I1289J-952D01*
G03X704910Y397140I285J280D01*
G02X707276Y397296I1254J-997D01*
G03X707838Y397302I278J288D01*
G02X710027Y397383I1138J-1128D01*
G03X710546Y397378I262J302D01*
G02X712636Y394950I1028J-1229D01*
G03Y394350I265J-300D01*
G02Y391950I-1061J-1200D01*
G03Y391350I265J-300D01*
G02X712388Y388770I-1061J-1200D01*
G03X712308Y388143I203J-345D01*
G02X712356Y385932I-1135J-1131D01*
G03Y385392I295J-270D01*
G02X710012Y383208I-1184J-1079D01*
G03X709452Y383228I-290J-275D01*
G02X707293Y383229I-1079J1184D01*
G03X706753I-270J-295D01*
G02X704593I-1080J1183D01*
G03X704053I-270J-295D01*
G02X702030Y383117I-1080J1183D01*
G37*
G36*
G01X175811Y385108D02*
G03Y384508I265J-300D01*
G02X173689I-1061J-1200D01*
G03Y385108I-265J300D01*
G02Y387508I1061J1200D01*
G03Y388108I-265J300D01*
G02X175811I1061J1200D01*
G03Y387508I265J-300D01*
G02Y385108I-1061J-1200D01*
G37*
G36*
G01X822018Y381889D02*
G03X821418I-300J-265D01*
G02X819157Y384150I-1200J1061D01*
G03Y384750I-265J300D01*
G02X821418Y387011I1061J1200D01*
G03X822018I300J265D01*
G02X824380Y387052I1200J-1061D01*
G03X824956Y387047I290J275D01*
G02X827282Y384845I1141J-1124D01*
G03X827306Y384282I296J-269D01*
G02X825072Y381986I-1090J-1174D01*
G03X824473Y381955I-286J-280D01*
G02X822018Y381889I-1255J995D01*
G37*
G36*
G01X1465365Y384296D02*
G03X1465373Y383729I286J-280D01*
G02X1463396Y383699I-973J-1009D01*
G03X1463388Y384266I-286J280D01*
G02X1465365Y384296I973J1009D01*
G37*
G36*
G01X172219Y384568D02*
G03Y383968I265J-300D01*
G02X170097I-1061J-1200D01*
G03Y384568I-265J300D01*
G02Y386968I1061J1200D01*
G03Y387568I-265J300D01*
G02X172219I1061J1200D01*
G03Y386968I265J-300D01*
G02Y384568I-1061J-1200D01*
G37*
G36*
G01X1571657Y384060D02*
G03X1571944Y383585I390J-89D01*
G02X1570217Y382538I-359J-1355D01*
G03X1569930Y383013I-390J89D01*
G02X1571657Y384060I359J1355D01*
G37*
G36*
G01X3938Y382895D02*
G03X5205Y383298I-2J2199D01*
G02X5221Y378660I1488J-2314D01*
G03X3967Y379073I-1283J-1786D01*
G01X3936D01*
G03X2669Y378670I2J-2199D01*
G02X2653Y383308I-1488J2314D01*
G03X3907Y382895I1283J1786D01*
G01X3938D01*
G37*
G36*
G01X-12598D02*
G03X-11331Y383298I-2J2199D01*
G02X-11315Y378660I1488J-2314D01*
G03X-12569Y379073I-1283J-1786D01*
G01X-12599D01*
G03X-13866Y378670I2J-2199D01*
G02X-13882Y383308I-1488J2314D01*
G03X-12628Y382895I1283J1786D01*
G01X-12598D01*
G37*
G36*
G01X1665868Y378253D02*
G03X1665885Y377698I296J-269D01*
G02X1663866Y377636I-980J-1003D01*
G03X1663849Y378191I-296J269D01*
G02X1665868Y378253I980J1003D01*
G37*
G36*
G01X1600490Y380354D02*
Y376261D01*
X1600480Y376176D01*
G02X1597266Y376346I-1603J170D01*
G01Y380344D01*
G02X1600490Y380354I1612J0D01*
G37*
G36*
G01X1609758Y380332D02*
Y376086D01*
X1609748Y376001D01*
G02X1606534Y376171I-1603J170D01*
G01Y380322D01*
G02X1609758Y380332I1612J0D01*
G37*
G36*
G01X852495Y375114D02*
G03X852599Y374541I322J-238D01*
G02X850584Y372074I-873J-1344D01*
G03X850026Y372086I-285J-280D01*
G02X847676Y374252I-1094J1171D01*
G03X847612Y374814I-313J249D01*
G02X847568Y374850I992J1257D01*
G03X847048I-260J-304D01*
G02X844790Y377108I-1040J1218D01*
G03Y377628I-304J260D01*
G02X847048Y379886I1218J1040D01*
G03X847568I260J304D01*
G02X849648I1040J-1218D01*
G03X850168I260J304D01*
G02X852426Y377628I1040J-1218D01*
G03Y377108I304J-260D01*
G02X852495Y375114I-1218J-1040D01*
G37*
G36*
G01X778810Y371129D02*
G03X778193Y371122I-306J-258D01*
G02X778172Y372904I-1093J878D01*
G03X778789Y372911I306J258D01*
G02X778810Y371129I1093J-878D01*
G37*
G36*
G01X25591Y375021D02*
G03X26858Y375424I-2J2199D01*
G02X26874Y370786I1488J-2314D01*
G03X25620Y371199I-1283J-1786D01*
G01X25590D01*
G03X24323Y370796I2J-2199D01*
G02X24307Y375434I-1488J2314D01*
G03X25561Y375021I1283J1786D01*
G01X25591D01*
G37*
G36*
G01X9056D02*
G03X10323Y375424I-2J2199D01*
G02X10339Y370786I1488J-2314D01*
G03X9085Y371199I-1283J-1786D01*
G01X9054D01*
G03X7787Y370796I2J-2199D01*
G02X7771Y375434I-1488J2314D01*
G03X9025Y375021I1283J1786D01*
G01X9056D01*
G37*
G36*
G01X197777Y376372D02*
G03X198245Y376627I91J389D01*
G02X200996Y375078I1509J-537D01*
G03X201025Y374541I310J-253D01*
G02X200961Y372200I-1125J-1141D01*
G03Y371600I265J-300D01*
G02X198839I-1061J-1200D01*
G03Y372200I-265J300D01*
G02X198351Y372990I1060J1201D01*
G03X197854Y373272I-386J-102D01*
G02X197777Y376372I-442J1540D01*
G37*
G36*
G01X102761Y370050D02*
G03X102792Y369428I266J-298D01*
G02X101032Y369342I-827J-1132D01*
G03X101001Y369964I-266J298D01*
G02X102761Y370050I827J1132D01*
G37*
G36*
G01X1598821Y368943D02*
G03X1598810Y368350I263J-301D01*
G02X1596929Y368386I-960J-1021D01*
G03X1596940Y368979I-263J301D01*
G02X1598821Y368943I960J1021D01*
G37*
G36*
G01X835874Y367906D02*
G03X836174Y367903I151J131D01*
G02X836266Y365662I1189J-1074D01*
G03X835725Y365668I-274J-292D01*
G02X833618Y365645I-1067J1195D01*
G03X833098I-260J-304D01*
G02X831018I-1040J1218D01*
G03X830498I-260J-304D01*
G02X828418I-1040J1218D01*
G03X827898I-260J-304D01*
G02X825818I-1040J1218D01*
G03X825298I-260J-304D01*
G02X823218I-1040J1218D01*
G03X822698I-260J-304D01*
G02X820440Y367903I-1040J1218D01*
G03Y368423I-304J260D01*
G02X822698Y370681I1218J1040D01*
G03X823218I260J304D01*
G02X825298I1040J-1218D01*
G03X825818I260J304D01*
G02X827898I1040J-1218D01*
G03X828418I260J304D01*
G02X830498I1040J-1218D01*
G03X831018I260J304D01*
G02X833098I1040J-1218D01*
G03X833618I260J304D01*
G02X835767Y368307I1040J-1218D01*
G03Y368019I139J-144D01*
G02X835874Y367906I-1108J-1157D01*
G37*
G36*
G01X20473Y367147D02*
G03X21740Y367550I-2J2199D01*
G02X21756Y362912I1488J-2314D01*
G03X20502Y363325I-1283J-1786D01*
G01X20471D01*
G03X19204Y362922I2J-2199D01*
G02X19188Y367560I-1488J2314D01*
G03X20442Y367147I1283J1786D01*
G01X20473D01*
G37*
G36*
G01X3938D02*
G03X5205Y367550I-2J2199D01*
G02X5221Y362912I1488J-2314D01*
G03X3967Y363325I-1283J-1786D01*
G01X3936D01*
G03X2669Y362922I2J-2199D01*
G02X2653Y367560I-1488J2314D01*
G03X3907Y367147I1283J1786D01*
G01X3938D01*
G37*
G36*
G01X-12598D02*
G03X-11331Y367550I-2J2199D01*
G02X-11315Y362912I1488J-2314D01*
G03X-12569Y363325I-1283J-1786D01*
G01X-12599D01*
G03X-13866Y362922I2J-2199D01*
G02X-13882Y367560I-1488J2314D01*
G03X-12628Y367147I1283J1786D01*
G01X-12598D01*
G37*
G36*
G01X746633Y362791D02*
G03X746113I-260J-304D01*
G02X743930Y365131I-1040J1218D01*
G03X743910Y365711I-285J281D01*
G02X746013Y368127I1063J1198D01*
G03X746533I260J304D01*
G02X748613I1040J-1218D01*
G03X749133I260J304D01*
G02X751316Y365787I1040J-1218D01*
G03X751336Y365207I285J-281D01*
G02X749233Y362791I-1063J-1198D01*
G03X748713I-260J-304D01*
G02X746633I-1040J1218D01*
G37*
G36*
G01X412516Y364647D02*
G03X412494Y364092I277J-289D01*
G02X410478Y364173I-1047J-932D01*
G03X410500Y364728I-277J289D01*
G02X410576Y366671I1047J932D01*
G03Y367249I-277J289D01*
G02X412518I971J1011D01*
G03Y366671I277J-289D01*
G02X412516Y364647I-971J-1011D01*
G37*
G36*
G01X776217Y363952D02*
G03X776224Y363388I287J-278D01*
G02X774043Y363308I-1053J-1072D01*
G03X774008Y363871I-301J264D01*
G02X773978Y363897I1034J1223D01*
G03X773423Y363887I-272J-293D01*
G02X771547Y363601I-1133J1133D01*
G03X770977Y363359I-186J-354D01*
G02X768209Y364835I-1537J451D01*
G03X768197Y365360I-308J256D01*
G02X770958Y366719I1183J1080D01*
G03X771539Y366435I394J69D01*
G02X773382Y366193I752J-1415D01*
G03X773937Y366203I272J293D01*
G02X776217Y363952I1133J-1132D01*
G37*
G36*
G01X126754Y363789D02*
G03X126731Y363260I288J-278D01*
G02X124229Y361625I-1168J-944D01*
G03X123566Y361696I-355J-184D01*
G02X121298Y363940I-1236J1019D01*
G03X121351Y364496I-258J305D01*
G02X124003Y366273I1249J1003D01*
G03X124602Y366153I350J193D01*
G02X126754Y363789I998J-1253D01*
G37*
G36*
G01X1544310Y362427D02*
G03Y361873I288J-277D01*
G02X1542290I-1010J-973D01*
G03Y362427I-288J277D01*
G02X1544310I1010J973D01*
G37*
G36*
G01X1653798Y365610D02*
Y360515D01*
X1653788Y360430D01*
G02X1650574Y360600I-1603J170D01*
G01Y365601D01*
G02X1653798Y365610I1612J-1D01*
G37*
G36*
G01X1641878Y365510D02*
Y360415D01*
X1641868Y360330D01*
G02X1638654Y360500I-1603J170D01*
G01Y365501D01*
G02X1641878Y365510I1612J-1D01*
G37*
G36*
G01X1534756Y361839D02*
G03X1534771Y361284I295J-270D01*
G02X1532753Y361227I-982J-1001D01*
G03X1532738Y361782I-295J270D01*
G02X1534756Y361839I982J1001D01*
G37*
G36*
G01X823910Y358757D02*
G03X823310Y358745I-295J-271D01*
G02X821028Y360982I-1221J1036D01*
G03Y361582I-265J300D01*
G02X823289Y363843I1061J1200D01*
G03X823889I300J265D01*
G02X826289I1200J-1061D01*
G03X826889I300J265D01*
G02X829289I1200J-1061D01*
G03X829889I300J265D01*
G02X832289I1200J-1061D01*
G03X832889I300J265D01*
G02X835176Y361605I1200J-1061D01*
G03Y361018I271J-294D01*
G02X832889Y358780I-1087J-1177D01*
G03X832289I-300J-265D01*
G02X829889I-1200J1061D01*
G03X829289I-300J-265D01*
G02X826889I-1200J1061D01*
G03X826289I-300J-265D01*
G02X823910Y358757I-1200J1061D01*
G37*
G36*
G01X175224Y358560D02*
G03X174624I-300J-265D01*
G02Y360682I-1200J1061D01*
G03X175224I300J265D01*
G02X177624I1200J-1061D01*
G03X178224I300J265D01*
G02X180624I1200J-1061D01*
G03X181224I300J265D01*
G02X183624I1200J-1061D01*
G03X184224I300J265D01*
G02X186624I1200J-1061D01*
G03X187224I300J265D01*
G02Y358560I1200J-1061D01*
G03X186624I-300J-265D01*
G02X184224I-1200J1061D01*
G03X183624I-300J-265D01*
G02X181224I-1200J1061D01*
G03X180624I-300J-265D01*
G02X178224I-1200J1061D01*
G03X177624I-300J-265D01*
G02X175224I-1200J1061D01*
G37*
G36*
G01X49402Y358381D02*
G03X48839Y358449I-315J-246D01*
G02X49078Y360409I-869J1101D01*
G03X49641Y360341I315J246D01*
G02X49402Y358381I869J-1101D01*
G37*
G36*
G01X1479586Y360661D02*
G03X1479585Y360087I278J-287D01*
G02X1477633Y360091I-978J-1005D01*
G03X1477634Y360665I-278J287D01*
G02X1479586Y360661I978J1005D01*
G37*
G36*
G01X1588089Y357429D02*
G03X1587511I-289J-277D01*
G02Y359371I-1011J971D01*
G03X1588089I289J277D01*
G02Y357429I1011J-971D01*
G37*
G36*
G01X1489450Y359356D02*
G03Y358778I277J-289D01*
G02X1487508I-971J-1011D01*
G03Y359356I-277J289D01*
G02Y361378I971J1011D01*
G03Y361956I-277J289D01*
G02X1489450I971J1011D01*
G03Y361378I277J-289D01*
G02Y359356I-971J-1011D01*
G37*
G36*
G01X1484671Y358502D02*
G03X1484699Y357881I266J-299D01*
G02X1482936Y357801I-832J-1128D01*
G03X1482908Y358422I-266J299D01*
G02X1484671Y358502I832J1128D01*
G37*
G36*
G01X25591Y359273D02*
G03X26858Y359676I-2J2199D01*
G02X26874Y355038I1488J-2314D01*
G03X25620Y355451I-1283J-1786D01*
G01X25590D01*
G03X24323Y355048I2J-2199D01*
G02X24307Y359686I-1488J2314D01*
G03X25561Y359273I1283J1786D01*
G01X25591D01*
G37*
G36*
G01X9056D02*
G03X10323Y359676I-2J2199D01*
G02X10339Y355038I1488J-2314D01*
G03X9085Y355451I-1283J-1786D01*
G01X9054D01*
G03X7787Y355048I2J-2199D01*
G02X7771Y359686I-1488J2314D01*
G03X9025Y359273I1283J1786D01*
G01X9056D01*
G37*
G36*
G01X-7480D02*
G03X-6213Y359676I-2J2199D01*
G02X-6197Y355038I1488J-2314D01*
G03X-7451Y355451I-1283J-1786D01*
G01X-7481D01*
G03X-8748Y355048I2J-2199D01*
G02X-8764Y359686I-1488J2314D01*
G03X-7510Y359273I1283J1786D01*
G01X-7480D01*
G37*
G36*
G01X1631382Y356595D02*
G03X1631410Y355995I278J-288D01*
G02X1629560Y355908I-876J-1095D01*
G03X1629532Y356508I-278J288D01*
G02X1629425Y358603I876J1095D01*
G03X1629440Y359158I-280J285D01*
G02X1629414Y361018I1036J945D01*
G03X1629383Y361573I-303J261D01*
G02X1629291Y363533I954J1027D01*
G03X1629269Y364088I-299J266D01*
G02X1629267Y366108I971J1011D01*
G03X1629258Y366692I-278J288D01*
G02X1631173Y366721I942J1038D01*
G03X1631182Y366137I278J-288D01*
G02X1631286Y364166I-942J-1038D01*
G03X1631308Y363611I299J-266D01*
G02X1631399Y361685I-971J-1011D01*
G03X1631430Y361130I303J-261D01*
G02X1631459Y359103I-954J-1027D01*
G03X1631444Y358548I280J-285D01*
G02X1631382Y356595I-1036J-945D01*
G37*
G36*
G01X1521289Y356063D02*
G03X1521315Y355466I279J-287D01*
G02X1519453Y355385I-885J-1087D01*
G03X1519427Y355982I-279J287D01*
G02X1521289Y356063I885J1087D01*
G37*
G36*
G01X1525756Y355744D02*
G03Y355190I288J-277D01*
G02X1523736I-1010J-973D01*
G03Y355744I-288J277D01*
G02Y357690I1010J973D01*
G03Y358244I-288J277D01*
G02X1525756I1010J973D01*
G03Y357690I288J-277D01*
G02Y355744I-1010J-973D01*
G37*
G36*
G01X1499217Y353894D02*
G03Y353316I277J-289D01*
G02X1497275I-971J-1011D01*
G03Y353894I-277J289D01*
G02Y355916I971J1011D01*
G03Y356494I-277J289D01*
G02X1497261Y358503I971J1011D01*
G03X1497275Y359058I-281J285D01*
G02X1497356Y361034I1034J947D01*
G03X1497342Y361633I-272J293D01*
G02X1497293Y363734I904J1072D01*
G03X1497279Y364333I-272J293D01*
G02X1499136Y364376I904J1072D01*
G03X1499150Y363777I272J-293D01*
G02X1499199Y361676I-904J-1072D01*
G03X1499213Y361077I272J-293D01*
G02X1499294Y359007I-904J-1072D01*
G03X1499280Y358452I281J-285D01*
G02X1499217Y356494I-1034J-947D01*
G03Y355916I277J-289D01*
G02Y353894I-971J-1011D01*
G37*
G36*
G01X1653157Y353689D02*
G03Y353111I277J-289D01*
G02X1651215I-971J-1011D01*
G03Y353689I-277J289D01*
G02X1653157I971J1011D01*
G37*
G36*
G01X767955Y352504D02*
G03X768121Y351953I349J-195D01*
G02X766254Y351393I-644J-1245D01*
G03X766088Y351944I-349J195D01*
G02X767955Y352504I644J1245D01*
G37*
G36*
G01X1539449Y352283D02*
G03Y351705I277J-289D01*
G02X1537507I-971J-1011D01*
G03Y352283I-277J289D01*
G02Y354305I971J1011D01*
G03Y354883I-277J289D01*
G02X1539449I971J1011D01*
G03Y354305I277J-289D01*
G02Y352283I-971J-1011D01*
G37*
G36*
G01X1416430Y352151D02*
G03X1416419Y351563I266J-299D01*
G02X1414520Y351599I-969J-1013D01*
G03X1414531Y352187I-266J299D01*
G02X1416430Y352151I969J1013D01*
G37*
G36*
G01X1447394Y350654D02*
G03X1446911Y350277I-83J-391D01*
G02X1445801Y351698I-1401J50D01*
G03X1446284Y352075I83J391D01*
G02X1447394Y350654I1401J-50D01*
G37*
G36*
G01X1490844Y351587D02*
G03X1490827Y351004I265J-299D01*
G02X1488909Y351061I-989J-993D01*
G03X1488926Y351644I-265J299D01*
G02X1490844Y351587I989J993D01*
G37*
G36*
G01X1544538Y351473D02*
G03Y350919I288J-277D01*
G02X1542518I-1010J-973D01*
G03Y351473I-288J277D01*
G02X1544538I1010J973D01*
G37*
G36*
G01X1331153Y351026D02*
G03X1331708Y350981I301J264D01*
G02X1331547Y348974I892J-1082D01*
G03X1330992Y349019I-301J-264D01*
G02X1331153Y351026I-892J1082D01*
G37*
G36*
G01X115528Y351963D02*
G03X115764Y352490I-135J377D01*
G02X117535Y351696I1299J526D01*
G03X117299Y351169I135J-377D01*
G02X117398Y350750I-1299J-528D01*
G03X117844Y350383I399J30D01*
G02X116610Y348884I164J-1392D01*
G03X116164Y349251I-399J-30D01*
G02X115528Y351963I-163J1392D01*
G37*
G36*
G01X746378Y343688D02*
G03X745818I-280J-286D01*
G02X743637Y346033I-1120J1145D01*
G03Y346633I-265J300D01*
G02X745818Y348978I1061J1200D01*
G03X746378I280J286D01*
G02X748618I1120J-1145D01*
G03X749178I280J286D01*
G02X751359Y346633I1120J-1145D01*
G03Y346033I265J-300D01*
G02X749178Y343688I-1061J-1200D01*
G03X748618I-280J-286D01*
G02X746378I-1120J1145D01*
G37*
G36*
G01X1643534Y343999D02*
G03X1643594Y343437I312J-251D01*
G02X1641621Y343227I-882J-1090D01*
G03X1641561Y343789I-312J251D01*
G02X1643534Y343999I882J1090D01*
G37*
G36*
G01X1556480Y340194D02*
G03X1555870I-305J-259D01*
G02Y342006I-1070J906D01*
G03X1556480I305J259D01*
G02Y340194I1070J-906D01*
G37*
G36*
G01X778862Y339127D02*
G03X778252I-305J-259D01*
G02Y340939I-1070J906D01*
G03X778862I305J259D01*
G02Y339127I1070J-906D01*
G37*
G36*
G01X700168Y337953D02*
G03X699613Y337931I-266J-299D01*
G02X699532Y339947I-1013J969D01*
G03X700087Y339969I266J299D01*
G02X700168Y337953I1013J-969D01*
G37*
G36*
G01X1582841Y337739D02*
G03X1582273Y337715I-272J-293D01*
G02X1579704Y339598I-1183J1080D01*
G03X1579581Y340130I-346J200D01*
G02X1581408Y342230I785J1162D01*
G03X1581962Y342189I298J267D01*
G02X1584152Y340570I897J-1077D01*
G03X1584360Y340050I369J-154D01*
G02X1582841Y337739I-566J-1283D01*
G37*
G36*
G01X1069992Y337612D02*
G03X1069392I-300J-265D01*
G02Y339734I-1200J1061D01*
G03X1069992I300J265D01*
G02Y337612I1200J-1061D01*
G37*
G36*
G01X1062792D02*
G03X1062192I-300J-265D01*
G02Y339734I-1200J1061D01*
G03X1062792I300J265D01*
G02Y337612I1200J-1061D01*
G37*
G36*
G01X1079082Y337472D02*
G03X1078482I-300J-265D01*
G02Y339594I-1200J1061D01*
G03X1079082I300J265D01*
G02X1081384Y339696I1200J-1061D01*
G03X1081987Y339757I275J290D01*
G02X1084465Y339942I1314J-916D01*
G03X1085029Y339925I291J275D01*
G02X1084962Y337657I1097J-1167D01*
G03X1084398Y337674I-291J-275D01*
G02X1082199Y337678I-1097J1167D01*
G03X1081596Y337617I-275J-290D01*
G02X1079082Y337472I-1314J916D01*
G37*
G36*
G01X824282Y335966D02*
G03X823682I-300J-265D01*
G02X821337Y338147I-1200J1061D01*
G03Y338707I-286J280D01*
G02X821421Y341027I1145J1120D01*
G03Y341627I-265J300D01*
G02X823682Y343888I1061J1200D01*
G03X824282I300J265D01*
G02X826682I1200J-1061D01*
G03X827282I300J265D01*
G02X829682I1200J-1061D01*
G03X830282I300J265D01*
G02X832682I1200J-1061D01*
G03X833282I300J265D01*
G02X835623Y343951I1200J-1061D01*
G03X836203Y343961I285J281D01*
G02X838483Y344041I1179J-1084D01*
G03X839058Y344068I274J291D01*
G02X841421Y341905I1204J-1057D01*
G03X841425Y341349I290J-276D01*
G02X841466Y339148I-1143J-1122D01*
G03X841486Y338588I295J-270D01*
G02X839304Y336242I-1103J-1162D01*
G03X838704Y336172I-270J-295D01*
G02X836241Y335953I-1322J905D01*
G03X835661Y335943I-285J-281D01*
G02X833282Y335966I-1179J1084D01*
G03X832682I-300J-265D01*
G02X830282I-1200J1061D01*
G03X829682I-300J-265D01*
G02X827282I-1200J1061D01*
G03X826682I-300J-265D01*
G02X824282I-1200J1061D01*
G37*
G36*
G01X1620907Y337663D02*
G03Y337109I288J-277D01*
G02X1618887I-1010J-973D01*
G03Y337663I-288J277D01*
G02Y339609I1010J973D01*
G03Y340163I-288J277D01*
G02X1620907I1010J973D01*
G03Y339609I288J-277D01*
G02Y337663I-1010J-973D01*
G37*
G36*
G01X746378Y334371D02*
G03X745818I-280J-286D01*
G02X743553Y336636I-1120J1145D01*
G03Y337196I-286J280D01*
G02X745818Y339461I1145J1120D01*
G03X746378I280J286D01*
G02X748618I1120J-1145D01*
G03X749178I280J286D01*
G02X751443Y337196I1120J-1145D01*
G03Y336636I286J-280D01*
G02X749178Y334371I-1145J-1120D01*
G03X748618I-280J-286D01*
G02X746378I-1120J1145D01*
G37*
G36*
G01X852875Y334344D02*
G03X852275I-300J-265D01*
G02X849944Y336539I-1200J1061D01*
G03X849925Y337123I-283J283D01*
G02X849782Y337266I1059J1202D01*
G03X849182I-300J-265D01*
G02X846921Y339527I-1200J1061D01*
G03Y340127I-265J300D01*
G02Y342527I1061J1200D01*
G03Y343127I-265J300D01*
G02X849182Y345388I1061J1200D01*
G03X849782I300J265D01*
G02X852182I1200J-1061D01*
G03X852782I300J265D01*
G02X855182I1200J-1061D01*
G03X855782I300J265D01*
G02X858043Y343127I1200J-1061D01*
G03Y342527I265J-300D01*
G02Y340127I-1061J-1200D01*
G03Y339527I265J-300D01*
G02X858113Y337193I-1061J-1200D01*
G03X858132Y336609I283J-283D01*
G02X855875Y334344I-1057J-1204D01*
G03X855275I-300J-265D01*
G02X852875I-1200J1061D01*
G37*
G36*
G01X81379Y334629D02*
G03X80813Y334496I-220J-334D01*
G02X80371Y336371I-1213J704D01*
G03X80937Y336504I220J334D01*
G02X81379Y334629I1213J-704D01*
G37*
G36*
G01X102187Y334221D02*
G03X101599Y334210I-289J-277D01*
G02X101563Y336109I-1049J930D01*
G03X102151Y336120I289J277D01*
G02X102187Y334221I1049J-930D01*
G37*
G36*
G01X1497795Y336516D02*
G03X1498283Y336166I398J40D01*
G02X1497205Y334660I317J-1366D01*
G03X1496717Y335010I-398J-40D01*
G02X1495105Y336914I-317J1366D01*
G03X1494893Y337435I-369J153D01*
G02X1494589Y339834I552J1289D01*
G03X1494670Y340384I-244J317D01*
G02X1496666Y340090I1140J816D01*
G03X1496585Y339540I244J-317D01*
G02X1496620Y339488I-1145J-808D01*
G03X1496939Y339466I168J109D01*
G02X1498126Y337150I1058J-920D01*
G03X1497771Y336668I36J-398D01*
G02X1497795Y336516I-1371J-294D01*
G37*
G36*
G01X1473398Y336467D02*
G03X1473409Y335868I270J-295D01*
G02X1471552Y335833I-909J-1068D01*
G03X1471541Y336432I-270J295D01*
G02X1473398Y336467I909J1068D01*
G37*
G36*
G01X1416971Y334489D02*
G03Y333911I277J-289D01*
G02X1415029I-971J-1011D01*
G03Y334489I-277J289D01*
G02Y336511I971J1011D01*
G03Y337089I-277J289D01*
G02X1416971I971J1011D01*
G03Y336511I277J-289D01*
G02Y334489I-971J-1011D01*
G37*
G36*
G01X1570182Y333131D02*
G03Y332553I277J-289D01*
G02X1568240I-971J-1011D01*
G03Y333131I-277J289D01*
G02X1570182I971J1011D01*
G37*
G36*
G01X1548600Y333102D02*
G03X1548734Y332556I343J-205D01*
G02X1546798Y332082I-733J-1195D01*
G03X1546664Y332628I-343J205D01*
G02X1548600Y333102I733J1195D01*
G37*
G36*
G01X200006Y337822D02*
G03X200004Y338371I-292J273D01*
G02X199866Y338536I1157J1108D01*
G03X199257Y338583I-324J-234D01*
G02X196987Y340843I-1138J1127D01*
G03X197007Y341387I-283J283D01*
G02X197154Y343623I1216J1043D01*
G03X197156Y344216I-267J297D01*
G02X197033Y344341I1079J1184D01*
G03X196433I-300J-265D01*
G02X194299Y346704I-1200J1061D01*
G03X194325Y347334I-233J325D01*
G02Y349470I908J1068D01*
G03X194299Y350100I-259J305D01*
G02X196433Y352463I934J1302D01*
G03X197033I300J265D01*
G02X199294Y350202I1200J-1061D01*
G03Y349602I265J-300D01*
G02X199339Y349561I-1056J-1204D01*
G03X199901Y349570I276J289D01*
G02X202106Y347249I1144J-1121D01*
G03Y346649I265J-300D01*
G02X202224Y346534I-1058J-1203D01*
G03X202826Y346549I294J270D01*
G02X205121Y344327I1234J-1022D01*
G03Y343727I265J-300D01*
G02X205137Y341341I-1061J-1200D01*
G03X205158Y340732I269J-296D01*
G02X205334Y338382I-995J-1256D01*
G03X205336Y337833I292J-273D01*
G02X202977Y335667I-1159J-1105D01*
G03X202377I-300J-265D01*
G02X202238Y335528I-1200J1061D01*
G03Y334928I265J-300D01*
G02Y332528I-1061J-1200D01*
G03Y331928I265J-300D01*
G02X200116I-1061J-1200D01*
G03Y332528I-265J300D01*
G02Y334928I1061J1200D01*
G03Y335528I-265J300D01*
G02X200006Y337822I1061J1201D01*
G37*
G36*
G01X776587Y331634D02*
G03X776458Y331090I214J-338D01*
G02X773785Y329738I-1286J-775D01*
G03X773079Y329800I-369J-154D01*
G02X770216Y331188I-1349J864D01*
G03X769926Y331709I-378J131D01*
G02X771463Y334350I352J1563D01*
G03X771997Y334297I296J269D01*
G02X774071Y334153I953J-1288D01*
G03X774627Y334149I280J285D01*
G02X776587Y331634I1105J-1160D01*
G37*
G36*
G01X1526765Y328878D02*
G03X1526213Y328768I-220J-334D01*
G02X1525823Y330723I-1162J785D01*
G03X1526375Y330833I220J334D01*
G02X1526765Y328878I1162J-785D01*
G37*
G36*
G01X1560995Y330789D02*
G03Y330211I277J-289D01*
G02X1559053I-971J-1011D01*
G03Y330789I-277J289D01*
G02X1560995I971J1011D01*
G37*
G36*
G01X1654016Y328102D02*
G03X1654038Y327534I292J-273D01*
G02X1652066Y327457I-947J-1034D01*
G03X1652044Y328025I-292J273D01*
G02X1654016Y328102I947J1034D01*
G37*
G36*
G01X645706Y326977D02*
G03X645589Y327576I-312J250D01*
G02X647366Y327923I683J1224D01*
G03X647483Y327324I312J-250D01*
G02X645706Y326977I-683J-1224D01*
G37*
G36*
G01X1493775Y327586D02*
G03X1493930Y327048I352J-190D01*
G02X1492005Y326492I-690J-1220D01*
G03X1491850Y327030I-352J190D01*
G02X1493775Y327586I690J1220D01*
G37*
G36*
G01X1017937Y325288D02*
G03X1017717Y324783I156J-368D01*
G02X1015855Y325596I-1318J-479D01*
G03X1016075Y326101I-156J368D01*
G02X1018366Y327590I1318J480D01*
G03X1018920I277J288D01*
G02X1020866I973J-1010D01*
G03X1021420I277J288D01*
G02X1023366I973J-1010D01*
G03X1023920I277J288D01*
G02X1024287Y327844I971J-1011D01*
G03X1024479Y328371I-172J361D01*
G02X1026567Y330094I1276J580D01*
G03X1027153Y330233I232J326D01*
G02X1028642Y328200I1240J-653D01*
G03X1028420Y327534I71J-394D01*
G02X1026420Y325570I-1027J-955D01*
G03X1025866I-277J-288D01*
G02X1023920I-973J1010D01*
G03X1023366I-277J-288D01*
G02X1021420I-973J1010D01*
G03X1020866I-277J-288D01*
G02X1018920I-973J1010D01*
G03X1018366I-277J-288D01*
G02X1017937Y325288I-972J1011D01*
G37*
G36*
G01X376998Y330627D02*
G03X377585Y330641I287J279D01*
G02X379464Y328129I1200J-1061D01*
G03X379286Y327569I170J-362D01*
G02X376816Y325592I-1392J-792D01*
G03X376282Y325596I-269J-296D01*
G02X374111Y325645I-1059J1202D01*
G03X373545Y325635I-278J-288D01*
G02X371263Y325609I-1154J1111D01*
G03X370735Y325640I-282J-284D01*
G02X368626Y325759I-987J1262D01*
G03X368101Y325790I-280J-286D01*
G02X368083Y325776I-992J1257D01*
G03X368050Y325488I120J-160D01*
G02X365736Y325637I-1228J-1029D01*
G03X365796Y326156I-271J294D01*
G02X368243Y328200I1325J901D01*
G03X368768Y328169I280J286D01*
G02X370876Y328039I980J-1267D01*
G03X371404Y328008I282J284D01*
G02X373503Y327899I987J-1262D01*
G03X374069Y327909I278J288D01*
G02X374351Y328142I1155J-1110D01*
G03X374476Y328684I-217J336D01*
G02X376998Y330627I1371J828D01*
G37*
G36*
G01X1543591Y324428D02*
G03X1543924Y323984I397J-49D01*
G02X1542309Y322772I-224J-1384D01*
G03X1541976Y323216I-397J49D01*
G02X1543591Y324428I224J1384D01*
G37*
G36*
G01X1590800Y323413D02*
G03X1591385Y323202I378J131D01*
G02X1590786Y321542I725J-1200D01*
G03X1590201Y321753I-378J-131D01*
G02X1590800Y323413I-725J1200D01*
G37*
G36*
G01X688320Y318775D02*
G03X688262Y318235I263J-301D01*
G02X686218Y318455I-1124J-838D01*
G03X686276Y318995I-263J301D01*
G02X688320Y318775I1124J838D01*
G37*
G36*
G01X647783Y319011D02*
G03Y318389I252J-311D01*
G02X646017I-883J-1089D01*
G03Y319011I-252J311D01*
G02X647783I883J1089D01*
G37*
G36*
G01X115528Y319963D02*
G03X115764Y320490I-135J377D01*
G02X117535Y319696I1299J526D01*
G03X117299Y319169I135J-377D01*
G02X117398Y318750I-1299J-528D01*
G03X117844Y318383I399J30D01*
G02X116610Y316884I164J-1392D01*
G03X116164Y317251I-399J-30D01*
G02X115528Y319963I-163J1392D01*
G37*
G36*
G01X1549195Y318450D02*
G03X1549443Y317930I374J-141D01*
G02X1547687Y317092I-443J-1330D01*
G03X1547439Y317612I-374J141D01*
G02X1549195Y318450I443J1330D01*
G37*
G36*
G01X82378Y317044D02*
G03X82972Y317036I301J264D01*
G02X82946Y315158I1028J-953D01*
G03X82352Y315166I-301J-264D01*
G02X82378Y317044I-1028J953D01*
G37*
G36*
G01X64971Y315489D02*
G03Y314911I277J-289D01*
G02X63029I-971J-1011D01*
G03Y315489I-277J289D01*
G02X64971I971J1011D01*
G37*
G36*
G01X1568271Y314778D02*
G03X1568629Y314283I388J-96D01*
G02X1567163Y313224I-105J-1398D01*
G03X1566805Y313719I-388J96D01*
G02X1565900Y314144I104J1398D01*
G03X1565346Y314165I-288J-277D01*
G02X1565421Y316183I-935J1045D01*
G03X1565975Y316162I288J277D01*
G02X1568271Y314778I935J-1045D01*
G37*
G36*
G01X1517245Y312208D02*
G03X1517209Y311654I269J-296D01*
G02X1515194Y311785I-1071J-905D01*
G03X1515230Y312339I-269J296D01*
G02X1517245Y312208I1071J905D01*
G37*
G36*
G01X1640423Y311762D02*
G03Y311208I288J-277D01*
G02X1638403I-1010J-973D01*
G03Y311762I-288J277D01*
G02X1640423I1010J973D01*
G37*
G36*
G01X1054857Y310895D02*
G03X1055487Y310894I315J246D01*
G02X1055484Y308919I1260J-989D01*
G03X1054854Y308920I-315J-246D01*
G02X1054857Y310895I-1260J989D01*
G37*
G36*
G01X1047789Y310997D02*
G03X1048375Y310996I293J272D01*
G02X1048370Y308817I1172J-1092D01*
G03X1047784Y308818I-293J-272D01*
G02X1047789Y310997I-1172J1092D01*
G37*
G36*
G01X1040571Y310985D02*
G03X1041163Y310983I297J268D01*
G02X1041159Y308829I1184J-1079D01*
G03X1040567Y308831I-297J-268D01*
G02X1040571Y310985I-1184J1079D01*
G37*
G36*
G01X1033286Y310919D02*
G03X1033907Y310918I311J252D01*
G02X1033903Y308895I1240J-1014D01*
G03X1033282Y308896I-311J-252D01*
G02X1033286Y310919I-1240J1014D01*
G37*
G36*
G01X405310Y310979D02*
G03X405905Y310978I298J267D01*
G02X405901Y308835I1189J-1074D01*
G03X405306Y308836I-298J-267D01*
G02X405310Y310979I-1189J1074D01*
G37*
G36*
G01X397985Y310878D02*
G03X398621Y310877I318J242D01*
G02X398618Y308936I1273J-972D01*
G03X397982Y308937I-318J-242D01*
G02X397985Y310878I-1273J972D01*
G37*
G36*
G01X390781Y310875D02*
G03X391419Y310874I319J241D01*
G02X391415Y308939I1275J-970D01*
G03X390777Y308940I-319J-241D01*
G02X390781Y310875I-1275J970D01*
G37*
G36*
G01X383698Y310970D02*
G03X384297Y310969I300J265D01*
G02X384293Y308844I1197J-1065D01*
G03X383694Y308845I-300J-265D01*
G02X383698Y310970I-1197J1065D01*
G37*
G36*
G01X1022960Y308827D02*
G03X1022346Y308796I-294J-271D01*
G02X1022245Y310842I-1281J962D01*
G03X1022859Y310873I294J271D01*
G02X1022960Y308827I1281J-962D01*
G37*
G36*
G01X1565345Y310023D02*
G03X1565339Y309424I262J-302D01*
G02X1563482Y309443I-939J-1041D01*
G03X1563488Y310042I-262J302D01*
G02X1565345Y310023I939J1041D01*
G37*
G36*
G01X714980Y309887D02*
G03Y309333I288J-277D01*
G02X712960I-1010J-973D01*
G03Y309887I-288J277D01*
G02X714980I1010J973D01*
G37*
G36*
G01X455158Y309368D02*
G03Y308814I288J-277D01*
G02X452981Y307064I-1010J-972D01*
G03X452426Y307175I-333J-222D01*
G02X450266Y308104I-778J1166D01*
G03X449789Y308428I-394J-67D01*
G02X448527Y308790I-289J1372D01*
G03X447973I-277J-288D01*
G02Y310810I-973J1010D01*
G03X448527I277J288D01*
G02X450882Y310037I973J-1010D01*
G03X451359Y309713I394J67D01*
G02X452218Y309622I289J-1372D01*
G03X452773Y310066I163J365D01*
G02X455158Y309368I1375J275D01*
G37*
G36*
G01X1561087Y309435D02*
G03X1561176Y308850I311J-252D01*
G02X1559310Y308565I-776J-1167D01*
G03X1559221Y309150I-311J252D01*
G02X1561087Y309435I776J1167D01*
G37*
G36*
G01X1306859Y308248D02*
G03X1306876Y307664I281J-284D01*
G02X1304964Y307608I-926J-1053D01*
G03X1304947Y308192I-281J284D01*
G02X1304824Y308315I928J1051D01*
G03X1304271Y308358I-299J-266D01*
G02X1304429Y310371I-891J1083D01*
G03X1304982Y310328I299J266D01*
G02X1306859Y308248I891J-1083D01*
G37*
G36*
G01X198917Y305660D02*
G03X198404Y305796I-333J-221D01*
G02X196532Y308340I-720J1431D01*
G03X196541Y308886I-288J278D01*
G02X198882Y308846I1189J1073D01*
G03X198873Y308300I288J-278D01*
G02X199018Y308115I-1185J-1078D01*
G03X199531Y307979I333J221D01*
G02X198917Y305660I720J-1431D01*
G37*
G36*
G01X1537386Y305392D02*
G03X1537870Y305102I388J98D01*
G02X1536847Y303397I336J-1361D01*
G03X1536363Y303687I-388J-98D01*
G02X1537386Y305392I-336J1361D01*
G37*
G36*
G01X1637893Y304142D02*
G03X1637906Y303586I294J-271D01*
G02X1635890Y303537I-984J-998D01*
G03X1635877Y304093I-294J271D01*
G02X1637893Y304142I984J998D01*
G37*
G36*
G01X1564358Y302020D02*
G03X1564356Y302642I-253J310D01*
G02X1566121Y302648I879J1092D01*
G03X1566123Y302026I253J-310D01*
G02X1564358Y302020I-879J-1092D01*
G37*
G36*
G01X1584487Y302124D02*
G03Y301556I281J-284D01*
G02X1582513I-987J-996D01*
G03Y302124I-281J284D01*
G02X1584487I987J996D01*
G37*
G36*
G01X1300631Y300220D02*
G03X1300624Y299612I256J-307D01*
G02X1298804Y299635I-923J-1055D01*
G03X1298811Y300243I-256J307D01*
G02X1300631Y300220I923J1055D01*
G37*
G36*
G01X776240Y299981D02*
G03X776220Y299391I260J-304D01*
G02X773762Y297796I-1049J-1075D01*
G03X773189Y298006I-376J-138D01*
G02X771445Y298114I-789J1394D01*
G03X770853Y297981I-239J-321D01*
G02X768107Y299624I-1414J754D01*
G03X767877Y300232I-333J222D01*
G02X769325Y303003I413J1548D01*
G03X769846Y303007I258J305D01*
G02X772461Y301440I1054J-1207D01*
G03X772761Y300961I390J-89D01*
G02X773039Y300869I-362J-1561D01*
G03X773598Y301229I159J367D01*
G02X776240Y299981I1602J-29D01*
G37*
G36*
G01X824482Y294466D02*
G03X823882I-300J-265D01*
G02X821621Y296727I-1200J1061D01*
G03Y297327I-265J300D01*
G02X821499Y299607I1061J1200D01*
G03Y300147I-295J270D01*
G02Y302307I1183J1080D01*
G03Y302847I-295J270D01*
G02X823882Y304988I1183J1080D01*
G03X824482I300J265D01*
G02X826882I1200J-1061D01*
G03X827482I300J265D01*
G02X829882I1200J-1061D01*
G03X830482I300J265D01*
G02X832882I1200J-1061D01*
G03X833482I300J265D01*
G02X835922Y304941I1200J-1061D01*
G03X836542I310J253D01*
G02X838887Y302767I1240J-1014D01*
G03Y302187I275J-290D01*
G02Y299867I-1105J-1160D01*
G03Y299287I275J-290D01*
G02X836414Y297294I-1105J-1160D01*
G03X835794Y297374I-342J-208D01*
G02X833482Y297466I-1112J1153D01*
G03X832882I-300J-265D01*
G02X830482I-1200J1061D01*
G03X829882I-300J-265D01*
G02X827482I-1200J1061D01*
G03X826882I-300J-265D01*
G02X826743Y297327I-1200J1061D01*
G03Y296727I265J-300D01*
G02X824482Y294466I-1061J-1200D01*
G37*
G36*
G01X189138Y307917D02*
G03X189444Y307915I154J127D01*
G02X189544Y308022I1219J-1039D01*
G03X189534Y308317I-140J143D01*
G02X191803Y308517I1036J1222D01*
G03X191822Y307985I308J-255D01*
G02X189549Y305728I-1157J-1108D01*
G03X188997Y305732I-278J-287D01*
G02X188963Y305702I-1077J1186D01*
G03X188943Y305122I265J-299D01*
G02X188905Y302840I-1143J-1122D01*
G03Y302260I275J-290D01*
G02X188983Y300020I-1105J-1160D01*
G03Y299480I295J-270D01*
G02X188997Y297336I-1183J-1080D01*
G03X189029Y296773I299J-265D01*
G02X189127Y296676I-1077J-1186D01*
G03X189695Y296660I292J273D01*
G02X192000Y296561I1105J-1160D01*
G03X192600I300J265D01*
G02X195037Y296518I1200J-1061D01*
G03X195667Y296535I308J254D01*
G02X195719Y294565I1289J-952D01*
G03X195089Y294548I-308J-254D01*
G02X192600Y294439I-1289J952D01*
G03X192000I-300J-265D01*
G02X189629Y294407I-1200J1061D01*
G03X189061Y294423I-292J-273D01*
G02X186719Y294565I-1105J1160D01*
G03X186089Y294548I-308J-254D01*
G02X183600Y294439I-1289J952D01*
G03X183000I-300J-265D01*
G02X180629Y294407I-1200J1061D01*
G03X180061Y294423I-292J-273D01*
G02X177719Y294565I-1105J1160D01*
G03X177089Y294548I-308J-254D01*
G02X174600Y294439I-1289J952D01*
G03X174000I-300J-265D01*
G02X171695Y296660I-1200J1061D01*
G03Y297240I-275J290D01*
G02X171617Y299480I1105J1160D01*
G03Y300020I-295J270D01*
G02X171695Y302260I1183J1080D01*
G03Y302840I-275J290D01*
G02X174000Y305061I1105J1160D01*
G03X174600I300J265D01*
G02X177000I1200J-1061D01*
G03X177600I300J265D01*
G02X180000I1200J-1061D01*
G03X180600I300J265D01*
G02X183000I1200J-1061D01*
G03X183600I300J265D01*
G02X186000I1200J-1061D01*
G03X186600I300J265D01*
G02X186737Y305198I1199J-1062D01*
G03X186757Y305778I-265J299D01*
G02X189138Y307917I1143J1123D01*
G37*
G36*
G01X657627Y294985D02*
G03X657426Y295549I-350J193D01*
G02X659176Y296170I524J1301D01*
G03X659377Y295606I350J-193D01*
G02X657627Y294985I-524J-1301D01*
G37*
G36*
G01X1054894Y293960D02*
G03X1055497Y293959I302J262D01*
G02X1055492Y291854I1205J-1055D01*
G03X1054889Y291855I-302J-262D01*
G02X1054894Y293960I-1205J1055D01*
G37*
G36*
G01X1040435Y293917D02*
G03X1041058Y293914I313J249D01*
G02X1041049Y291906I1244J-1010D01*
G03X1040426Y291909I-313J-249D01*
G02X1040435Y293917I-1244J1010D01*
G37*
G36*
G01X1033215Y293897D02*
G03X1033844Y293896I315J247D01*
G02X1033840Y291917I1258J-992D01*
G03X1033211Y291918I-315J-247D01*
G02X1033215Y293897I-1258J992D01*
G37*
G36*
G01X1026163Y294014D02*
G03X1026744Y294011I292J273D01*
G02X1026733Y291808I1158J-1107D01*
G03X1026152Y291811I-292J-273D01*
G02X1026163Y294014I-1158J1107D01*
G37*
G36*
G01X1018861Y293935D02*
G03X1019475Y293934I307J256D01*
G02X1019471Y291879I1227J-1030D01*
G03X1018857Y291880I-307J-256D01*
G02X1018861Y293935I-1227J1030D01*
G37*
G36*
G01X405448Y294111D02*
G03X406013Y294086I295J270D01*
G02X405912Y291823I1081J-1182D01*
G03X405347Y291848I-295J-270D01*
G02X405448Y294111I-1081J1182D01*
G37*
G36*
G01X398151Y294056D02*
G03X398749Y294025I313J249D01*
G02X398640Y291906I1145J-1121D01*
G03X398042Y291937I-313J-249D01*
G02X398151Y294056I-1145J1121D01*
G37*
G36*
G01X390797Y293888D02*
G03X391429Y293887I316J245D01*
G02X391425Y291926I1265J-983D01*
G03X390793Y291927I-316J-245D01*
G02X390797Y293888I-1265J983D01*
G37*
G36*
G01X383890Y294190D02*
G03X384463Y294130I315J246D01*
G02X384229Y291921I1031J-1226D01*
G03X383656Y291981I-315J-246D01*
G02X383890Y294190I-1031J1226D01*
G37*
G36*
G01X372753Y291803D02*
G03X372226Y291770I-245J-316D01*
G02X369837Y291911I-1132J1134D01*
G03X369242Y291947I-314J-248D01*
G02X369373Y294080I-1126J1140D01*
G03X369968Y294044I314J248D01*
G02X372077Y294169I1126J-1140D01*
G03X372604Y294202I245J316D01*
G02X372753Y291803I1132J-1134D01*
G37*
G36*
G01X1637832Y293973D02*
G03Y293419I288J-277D01*
G02X1635812I-1010J-973D01*
G03Y293973I-288J277D01*
G02X1635853Y295959I1010J973D01*
G03X1635876Y296514I-276J289D01*
G02X1637894Y296431I1049J930D01*
G03X1637871Y295876I276J-289D01*
G02X1637832Y293973I-1049J-930D01*
G37*
G36*
G01X1305637Y292913D02*
G03X1305262Y292476I23J-399D01*
G02X1303787Y293745I-1396J-131D01*
G03X1304162Y294182I-23J399D01*
G02X1305637Y292913I1396J131D01*
G37*
G36*
G01X1335501Y292918D02*
G03X1336123Y292909I315J247D01*
G02X1336099Y291144I1077J-897D01*
G03X1335477Y291153I-315J-247D01*
G02X1335501Y292918I-1077J897D01*
G37*
G36*
G01X49683Y291311D02*
G03Y290689I252J-311D01*
G02X47917I-883J-1089D01*
G03Y291311I-252J311D01*
G02X49683I883J1089D01*
G37*
G36*
G01X1534824Y287709D02*
G03X1534841Y287125I281J-284D01*
G02X1532928Y287070I-927J-1052D01*
G03X1532911Y287654I-281J284D01*
G02X1534824Y287709I927J1052D01*
G37*
G36*
G01X1548006Y287663D02*
G03X1548358Y287223I398J-43D01*
G02X1546805Y285979I-159J-1393D01*
G03X1546453Y286419I-398J43D01*
G02X1548006Y287663I159J1393D01*
G37*
G36*
G01X637881Y287185D02*
G03X637839Y286610I255J-308D01*
G02X636064Y286864I-1040J-940D01*
G03X636087Y287187I-105J170D01*
G02X635967Y287300I900J1076D01*
G03X635645Y287257I-146J-137D01*
G02X635280Y289012I-1238J658D01*
G03X635852Y289090I249J313D01*
G02X637881Y287185I1133J-827D01*
G37*
G36*
G01X115528Y287963D02*
G03X115764Y288490I-135J377D01*
G02X117535Y287696I1299J526D01*
G03X117299Y287169I135J-377D01*
G02X117398Y286750I-1299J-528D01*
G03X117844Y286383I399J30D01*
G02X116610Y284884I164J-1392D01*
G03X116164Y285251I-399J-30D01*
G02X115528Y287963I-163J1392D01*
G37*
G36*
G01X663911Y283917D02*
G03X663289I-311J-252D01*
G02X660957Y285448I-1089J883D01*
G03X660742Y286007I-355J184D01*
G02X662475Y286673I490J1314D01*
G03X662690Y286114I355J-184D01*
G02X663289Y285683I-491J-1314D01*
G03X663911I311J252D01*
G02Y283917I1089J-883D01*
G37*
G36*
G01X1580115Y283805D02*
G03X1579560Y283799I-274J-291D01*
G02X1579539Y285819I-983J1000D01*
G03X1580094Y285825I274J291D01*
G02X1580115Y283805I983J-1000D01*
G37*
G36*
G01X1570790Y286064D02*
G03X1571021Y286576I-144J373D01*
G02X1573704Y286758I1315J487D01*
G03X1574027Y286277I391J-87D01*
G02X1572875Y283833I-237J-1382D01*
G03X1572321Y283802I-261J-303D01*
G02X1570790Y286064I-1028J953D01*
G37*
G36*
G01X560979Y284997D02*
G03X560608Y284565I28J-399D01*
G02X559116Y285846I-1397J-118D01*
G03X559487Y286278I-28J399D01*
G02X560979Y284997I1397J118D01*
G37*
G36*
G01X1315646Y285315D02*
G03X1315579Y284745I243J-318D01*
G02X1313636Y284974I-1089J-883D01*
G03X1313703Y285544I-243J318D01*
G02X1315646Y285315I1089J883D01*
G37*
G36*
G01X69311Y282571D02*
G03X69889I289J277D01*
G02Y280629I1011J-971D01*
G03X69311I-289J-277D01*
G02Y282571I-1011J971D01*
G37*
G36*
G01X1399552Y283306D02*
G03X1399680Y282764I343J-205D01*
G02X1397721Y282299I-754J-1182D01*
G03X1397593Y282841I-343J205D01*
G02X1399552Y283306I754J1182D01*
G37*
G36*
G01X1097703Y279975D02*
G03X1098242I269J295D01*
G02X1098239Y277904I944J-1037D01*
G03X1097700I-269J-295D01*
G02X1097703Y279975I-944J1037D01*
G37*
G36*
G01X448798Y277912D02*
G03X448198I-300J-265D01*
G02Y279770I-1050J929D01*
G03X448798I300J265D01*
G02Y277912I1050J-929D01*
G37*
G36*
G01X1434372Y279771D02*
G03Y279217I288J-277D01*
G02X1432352I-1010J-973D01*
G03Y279771I-288J277D01*
G02X1434372I1010J973D01*
G37*
G36*
G01X662303Y279878D02*
G03X662721Y279485I400J6D01*
G02X661384Y278062I65J-1401D01*
G03X660966Y278455I-400J-6D01*
G02X662303Y279878I-65J1401D01*
G37*
G36*
G01X60473Y279010D02*
G03X61027I277J288D01*
G02Y276990I973J-1010D01*
G03X60473I-277J-288D01*
G02Y279010I-973J1010D01*
G37*
G36*
G01X648422Y279263D02*
G03X648418Y278671I267J-298D01*
G02X646534Y278684I-949J-1032D01*
G03X646538Y279276I-267J298D01*
G02X648422Y279263I949J1032D01*
G37*
G36*
G01X1333680Y274524D02*
X1330171D01*
G02Y277546I0J1511D01*
G01X1333681D01*
G02X1335192Y276045I0J-1512D01*
G01Y275950D01*
X1335182Y275866D01*
G02X1333680Y274524I-1502J169D01*
G37*
G36*
G01X452389Y274629D02*
G03X451811I-289J-277D01*
G02Y276571I-1011J971D01*
G03X452389I289J277D01*
G02Y274629I1011J-971D01*
G37*
G36*
G01X778572Y275068D02*
G03X777973Y274913I-236J-323D01*
G02X777528Y276632I-1273J588D01*
G03X778127Y276787I236J323D01*
G02X778572Y275068I1273J-588D01*
G37*
G36*
G01X1637694Y276342D02*
G03Y275788I288J-277D01*
G02X1635674I-1010J-973D01*
G03Y276342I-288J277D01*
G02Y278288I1010J973D01*
G03Y278842I-288J277D01*
G02X1637694I1010J973D01*
G03Y278288I288J-277D01*
G02Y276342I-1010J-973D01*
G37*
G36*
G01X199827Y276169D02*
G03X199847Y276768I-254J308D01*
G02X199776Y276839I1097J1168D01*
G03X199204Y276852I-292J-273D01*
G02X197062Y279231I-1122J1144D01*
G03X197082Y279830I-254J308D01*
G02X199314Y282128I1100J1165D01*
G03X199867Y282116I283J283D01*
G02X202249Y281867I1080J-1183D01*
G03X202879Y281841I325J233D01*
G02X204855Y279865I1068J-908D01*
G03X204881Y279235I259J-305D01*
G02X204967Y276697I-934J-1302D01*
G03X204947Y276098I254J-308D01*
G02X202647Y273872I-1100J-1165D01*
G03X202047I-300J-265D01*
G02X199827Y276169I-1200J1062D01*
G37*
G36*
G01X824264Y273849D02*
G03X823664I-300J-265D01*
G02X821246Y275950I-1200J1061D01*
G03Y276470I-304J260D01*
G02Y278550I1218J1040D01*
G03Y279070I-304J260D01*
G02X823664Y281171I1218J1040D01*
G03X824264I300J265D01*
G02X826664I1200J-1061D01*
G03X827264I300J265D01*
G02X829664I1200J-1061D01*
G03X830264I300J265D01*
G02X832664I1200J-1061D01*
G03X833264I300J265D01*
G02X835584Y281255I1200J-1061D01*
G03X836144I280J286D01*
G02X838384I1120J-1145D01*
G03X838944I280J286D01*
G02X841282Y279070I1120J-1145D01*
G03Y278550I304J-260D01*
G02X838944Y276365I-1218J-1040D01*
G03X838384I-280J-286D01*
G02X838373Y276354I-1138J1127D01*
G03Y276066I139J-144D01*
G02X836144Y273765I-1109J-1156D01*
G03X835584I-280J-286D01*
G02X833264Y273849I-1120J1145D01*
G03X832664I-300J-265D01*
G02X830264I-1200J1061D01*
G03X829664I-300J-265D01*
G02X827264I-1200J1061D01*
G03X826664I-300J-265D01*
G02X824264I-1200J1061D01*
G37*
G36*
G01X850182Y273366D02*
G03X849582I-300J-265D01*
G02X847164Y275467I-1200J1061D01*
G03Y275987I-304J260D01*
G02X847199Y278107I1218J1040D01*
G03Y278647I-295J270D01*
G02X847164Y280767I1183J1080D01*
G03Y281287I-304J260D01*
G02X849582Y283388I1218J1040D01*
G03X850182I300J265D01*
G02X852582I1200J-1061D01*
G03X853182I300J265D01*
G02X855582I1200J-1061D01*
G03X856182I300J265D01*
G02X858600Y281287I1200J-1061D01*
G03Y280767I304J-260D01*
G02X858565Y278647I-1218J-1040D01*
G03Y278107I295J-270D01*
G02X858600Y275987I-1183J-1080D01*
G03Y275467I304J-260D01*
G02X856182Y273366I-1218J-1040D01*
G03X855582I-300J-265D01*
G02X853182I-1200J1061D01*
G03X852582I-300J-265D01*
G02X850182I-1200J1061D01*
G37*
G36*
G01X1340248Y270244D02*
X1336448D01*
G02Y273266I0J1511D01*
G01X1340249D01*
G02X1341760Y271765I0J-1512D01*
G01Y271670D01*
X1341750Y271586D01*
G02X1340248Y270244I-1502J169D01*
G37*
G36*
G01X184648Y273848D02*
G03X184644Y274431I-276J290D01*
G02X184615Y274459I1098J1166D01*
G03X184055I-280J-286D01*
G02X181823Y274451I-1120J1145D01*
G03X181203Y274371I-278J-288D01*
G02X178635Y274143I-1368J833D01*
G03X178035I-300J-265D01*
G02X175635I-1200J1061D01*
G03X175035I-300J-265D01*
G02X172617Y276244I-1200J1061D01*
G03Y276764I-304J260D01*
G02X175035Y278865I1218J1040D01*
G03X175635I300J265D01*
G02X178035I1200J-1061D01*
G03X178635I300J265D01*
G02X180947Y278957I1200J-1061D01*
G03X181567Y279037I278J288D01*
G02X184055Y279349I1368J-833D01*
G03X184615I280J286D01*
G02X186844Y279360I1120J-1145D01*
G03X187416Y279379I277J289D01*
G02X189679Y279484I1184J-1079D01*
G03X190239Y279504I270J295D01*
G02X190321Y277216I1161J-1104D01*
G03X189761Y277196I-270J-295D01*
G02X189758Y277193I-1134J1131D01*
G03X189745Y276654I289J-277D01*
G02X189613Y274419I-1210J-1050D01*
G03X189608Y273832I269J-296D01*
G02X189714Y271609I-1098J-1166D01*
G03X189707Y271089I300J-264D01*
G02X187392Y268885I-1232J-1023D01*
G03X186851I-271J-295D01*
G02X184552Y271108I-1083J1181D01*
G03X184550Y271633I-303J261D01*
G02X184648Y273848I1204J1056D01*
G37*
G36*
G01X1412345Y270158D02*
G03X1412700Y269670I390J-90D01*
G02X1411213Y268588I-121J-1397D01*
G03X1410858Y269076I-390J90D01*
G02X1412345Y270158I121J1397D01*
G37*
G36*
G01X1010655Y269874D02*
G03X1011064Y269502I399J28D01*
G02X1009701Y268003I36J-1402D01*
G03X1009292Y268375I-399J-28D01*
G02X1007949Y269270I-36J1402D01*
G03X1007382Y269475I-373J-145D01*
G02X1005785Y271762I-682J1225D01*
G03X1005777Y272375I-261J303D01*
G02X1007580Y272398I888J1085D01*
G03X1007588Y271785I261J-303D01*
G02X1008007Y271207I-888J-1085D01*
G03X1008574Y271002I373J145D01*
G02X1010655Y269874I682J-1225D01*
G37*
G36*
G01X361047D02*
G03X361456Y269502I399J28D01*
G02X360093Y268003I36J-1402D01*
G03X359684Y268375I-399J-28D01*
G02X358341Y269270I-36J1402D01*
G03X357774Y269475I-373J-145D01*
G02X356177Y271762I-682J1225D01*
G03X356169Y272375I-261J303D01*
G02X357972Y272398I888J1085D01*
G03X357980Y271785I261J-303D01*
G02X358399Y271207I-888J-1085D01*
G03X358966Y271002I373J145D01*
G02X361047Y269874I682J-1225D01*
G37*
G36*
G01X1347468Y266584D02*
X1343668D01*
G02Y269606I0J1511D01*
G01X1347469D01*
G02X1348980Y268105I0J-1512D01*
G01Y268010D01*
X1348970Y267926D01*
G02X1347468Y266584I-1502J169D01*
G37*
G36*
G01X748148Y268571D02*
G03X748170Y269192I-241J319D01*
G02X749932Y269129I920J1058D01*
G03X749910Y268508I241J-319D01*
G02X748148Y268571I-920J-1058D01*
G37*
G36*
G01X773929Y267748D02*
G03X774446Y267632I324J234D01*
G02X774006Y265368I725J-1316D01*
G03X773483Y265454I-310J-253D01*
G02X771490Y265684I-853J1356D01*
G03X770892Y265652I-285J-281D01*
G02X768945Y268092I-1255J995D01*
G03X769114Y268660I-173J361D01*
G02X771987Y268933I1371J829D01*
G03X772416Y268398I375J-139D01*
G02X773929Y267748I214J-1588D01*
G37*
G36*
G01X1356268Y264184D02*
X1352468D01*
G02Y267206I0J1511D01*
G01X1356269D01*
G02X1357780Y265705I0J-1512D01*
G01Y265610D01*
X1357770Y265526D01*
G02X1356268Y264184I-1502J170D01*
G37*
G36*
G01X1217244Y267082D02*
G03Y266528I288J-277D01*
G02X1215224I-1010J-973D01*
G03Y267082I-288J277D01*
G02X1217244I1010J973D01*
G37*
G36*
G01X567936D02*
G03Y266528I288J-277D01*
G02X565916I-1010J-973D01*
G03Y267082I-288J277D01*
G02X567936I1010J973D01*
G37*
G36*
G01X1381031Y264088D02*
X1377522D01*
G02Y267112I0J1512D01*
G01X1381032D01*
G02X1382542Y265610I-1J-1512D01*
G01Y265515D01*
X1382533Y265431D01*
G02X1381031Y264088I-1502J168D01*
G37*
G36*
G01X1362803Y267036D02*
X1366313D01*
G02X1367824Y265535I0J-1512D01*
G01Y265440D01*
X1367814Y265356D01*
G02X1366312Y264014I-1502J169D01*
G01X1362803D01*
G02Y267036I1J1511D01*
G37*
G36*
G01X1074367Y266089D02*
G03X1074899Y266044I291J274D01*
G02X1074698Y263668I966J-1278D01*
G03X1074166Y263713I-291J-274D01*
G02X1072074Y263851I-966J1278D01*
G03X1071495Y263833I-281J-285D01*
G02X1071426Y266040I-1195J1067D01*
G03X1072005Y266058I281J285D01*
G02X1074367Y266089I1195J-1067D01*
G37*
G36*
G01X1064599Y265863D02*
G03X1065178Y265844I299J266D01*
G02X1065103Y263636I1122J-1143D01*
G03X1064524Y263655I-299J-266D01*
G02X1062202Y263738I-1122J1144D01*
G03X1061602I-300J-265D01*
G02X1059092Y263877I-1200J1061D01*
G03X1058452Y263897I-327J-230D01*
G02X1056002Y263838I-1250J1002D01*
G03X1055402I-300J-265D01*
G02Y265960I-1200J1061D01*
G03X1056002I300J265D01*
G02X1058512Y265821I1200J-1061D01*
G03X1059152Y265801I327J230D01*
G02X1061602Y265860I1250J-1002D01*
G03X1062202I300J265D01*
G02X1064599Y265863I1200J-1061D01*
G37*
G36*
G01X437620Y263877D02*
G03X437658Y263359I322J-237D01*
G02X435228Y263181I-1139J-1127D01*
G03X435190Y263699I-322J237D01*
G02X437620Y263877I1139J1127D01*
G37*
G36*
G01X1628763Y261318D02*
G03X1628481Y260782I90J-390D01*
G02X1626286Y261349I-1304J-515D01*
G03X1626299Y261955I-255J309D01*
G02X1628763Y261318I1843J2044D01*
G37*
G36*
G01X1884784Y261829D02*
G03Y261229I265J-300D01*
G02X1882460Y259043I-1061J-1200D01*
G03X1881843Y259059I-315J-246D01*
G02X1879572Y261309I-1210J1050D01*
G03Y261909I-265J300D01*
G02X1881896Y264095I1061J1200D01*
G03X1882513Y264079I315J246D01*
G02X1884784Y261829I1210J-1050D01*
G37*
G36*
G01X1160308Y261401D02*
G03X1160313Y260793I262J-302D01*
G02X1158492Y260779I-902J-1073D01*
G03X1158487Y261387I-262J302D01*
G02X1160308Y261401I902J1073D01*
G37*
G36*
G01X1455205Y261089D02*
G03X1455127Y260534I244J-317D01*
G02X1453298Y260914I-1127J-834D01*
G03X1453342Y261226I-100J173D01*
G02X1453256Y261323I1005J978D01*
G03X1452944I-156J-125D01*
G02X1452823Y263210I-1094J877D01*
G03X1453377I277J288D01*
G02X1455205Y261089I972J-1010D01*
G37*
G36*
G01X1226918Y260827D02*
G03Y260273I288J-277D01*
G02X1224898I-1010J-973D01*
G03Y260827I-288J277D01*
G02X1226918I1010J973D01*
G37*
G36*
G01X576610D02*
G03Y260273I288J-277D01*
G02X574590I-1010J-973D01*
G03Y260827I-288J277D01*
G02X576610I1010J973D01*
G37*
G36*
G01X510478Y259111D02*
G03X510102Y258672I22J-399D01*
G02X508630Y259932I-1395J-140D01*
G03X509006Y260371I-22J399D01*
G02X510478Y259111I1395J140D01*
G37*
G36*
G01X1494858Y254727D02*
G03X1494307Y254648I-235J-324D01*
G02X1494023Y256641I-1108J859D01*
G03X1494574Y256720I235J324D01*
G02X1494678Y256839I1106J-861D01*
G03X1494681Y257394I-287J279D01*
G02X1496700Y257383I1015J967D01*
G03X1496697Y256828I287J-279D01*
G02X1494858Y254727I-1015J-967D01*
G37*
G36*
G01X1465810Y255243D02*
G03X1465890Y254676I316J-244D01*
G02X1463781Y252976I-827J-1132D01*
G03X1463257Y253182I-366J-161D01*
G02X1462861Y255863I-553J1288D01*
G03X1463304Y256225I44J398D01*
G02X1465810Y255243I1396J-125D01*
G37*
G36*
G01X621974Y254930D02*
G03X621904Y254340I231J-327D01*
G02X620041Y254561I-1054J-924D01*
G03X620111Y255151I-231J327D01*
G02X621974Y254930I1054J924D01*
G37*
G36*
G01X1275468Y254991D02*
G03X1275795Y254508I390J-88D01*
G02X1274209Y253432I-218J-1385D01*
G03X1273882Y253915I-390J88D01*
G02X1275468Y254991I218J1385D01*
G37*
G36*
G01X116610Y252884D02*
G03X116164Y253251I-399J-30D01*
G02X115528Y255963I-163J1392D01*
G03X115764Y256490I-135J377D01*
G02X117535Y255696I1299J526D01*
G03X117299Y255169I135J-377D01*
G02X117398Y254750I-1299J-528D01*
G03X117844Y254383I399J30D01*
G02X116610Y252884I164J-1392D01*
G37*
G36*
G01X1469444Y253888D02*
G03X1469999Y253876I284J282D01*
G02X1469956Y251858I951J-1030D01*
G03X1469401Y251870I-284J-282D01*
G02X1469444Y253888I-951J1030D01*
G37*
G36*
G01X766693Y253259D02*
G03X766354Y252751I45J-397D01*
G02X764846Y253756I-1347J-388D01*
G03X765185Y254264I-45J397D01*
G02X765602Y255701I1347J388D01*
G03X765624Y256278I-266J299D01*
G02X767562Y256203I1008J974D01*
G03X767540Y255626I266J-299D01*
G02X766693Y253259I-1008J-974D01*
G37*
G36*
G01X1479777Y253333D02*
G03X1479666Y252778I222J-333D01*
G02X1477723Y253167I-1166J-778D01*
G03X1477834Y253722I-222J333D01*
G02X1477627Y254782I1166J778D01*
G03X1477271Y255261I-392J80D01*
G02X1478770Y256375I126J1396D01*
G03X1479126Y255896I392J-80D01*
G02X1479777Y253333I-126J-1396D01*
G37*
G36*
G01X1434852Y253400D02*
G03X1434985Y252823I328J-228D01*
G02X1433148Y252400I-686J-1223D01*
G03X1433015Y252977I-328J228D01*
G02X1434852Y253400I686J1223D01*
G37*
G36*
G01X1817282Y248886D02*
X1812281D01*
G02X1812282Y252110I1J1612D01*
G01X1817282D01*
G02X1818894Y250508I0J-1612D01*
G01Y250413D01*
X1818884Y250328D01*
G02X1817282Y248886I-1602J169D01*
G37*
G36*
G01X1798384D02*
X1793384D01*
G02Y252110I0J1612D01*
G01X1798385D01*
G02X1799996Y250508I-1J-1612D01*
G01Y250413D01*
X1799986Y250328D01*
G02X1798384Y248886I-1602J169D01*
G37*
G36*
G01X1825702Y251794D02*
G03X1826143Y251395I400J-1D01*
G02X1824885Y250006I144J-1395D01*
G03X1824444Y250405I-400J1D01*
G02X1825702Y251794I-144J1395D01*
G37*
G36*
G01X1736800Y248939D02*
G03X1736200I-300J-265D01*
G02Y251061I-1200J1061D01*
G03X1736800I300J265D01*
G02X1739200I1200J-1061D01*
G03X1739800I300J265D01*
G02Y248939I1200J-1061D01*
G03X1739200I-300J-265D01*
G02X1736800I-1200J1061D01*
G37*
G36*
G01X1690282Y249679D02*
G03X1689813Y249382I-80J-392D01*
G02X1687183Y249118I-1362J334D01*
G03X1686664Y249315I-362J-171D01*
G02X1685186Y249552I-551J1289D01*
G03X1684632Y249528I-265J-300D01*
G02X1684542Y251545I-1017J965D01*
G03X1685096Y251569I265J300D01*
G02X1687381Y251202I1017J-965D01*
G03X1687900Y251005I362J171D01*
G02X1688734Y251089I551J-1289D01*
G03X1689203Y251386I80J392D01*
G02X1690282Y249679I1362J-334D01*
G37*
G36*
G01X1597653Y247276D02*
G03X1598245Y247267I300J264D01*
G02X1598217Y245384I1025J-957D01*
G03X1597625Y245393I-300J-264D01*
G02X1597653Y247276I-1025J957D01*
G37*
G36*
G01X199940Y245395D02*
G03X199360I-290J-275D01*
G02X197139Y247700I-1160J1105D01*
G03Y248300I-265J300D01*
G02Y250700I1061J1200D01*
G03Y251300I-265J300D01*
G02X197118Y251319I1064J1197D01*
G03X196499Y251219I-270J-295D01*
G02X196182Y253181I-1399J781D01*
G03X196801Y253281I270J295D01*
G02X199400Y253561I1399J-781D01*
G03X200000I300J265D01*
G02X202400I1200J-1061D01*
G03X203000I300J265D01*
G02X205400I1200J-1061D01*
G03X206000I300J265D01*
G02X208261Y251300I1200J-1061D01*
G03Y250700I265J-300D01*
G02X207939Y248078I-1061J-1200D01*
G03X207829Y247452I184J-355D01*
G02X205774Y245545I-1029J-952D01*
G03X205165Y245517I-293J-273D01*
G02X202780Y245355I-1265J983D01*
G03X202220I-280J-286D01*
G02X199940Y245395I-1120J1145D01*
G37*
G36*
G01X1468298Y245076D02*
G03X1467721Y244868I-201J-345D01*
G02X1467110Y246561I-1317J482D01*
G03X1467687Y246769I201J345D01*
G02X1470015Y247258I1317J-482D01*
G03X1470593I289J277D01*
G02Y245316I1011J-971D01*
G03X1470015I-289J-277D01*
G02X1468298Y245076I-1011J971D01*
G37*
G36*
G01X1510804Y246222D02*
G03X1510800Y245658I282J-284D01*
G02X1508810Y245669I-1000J-982D01*
G03X1508814Y246233I-282J284D01*
G02X1510804Y246222I1000J982D01*
G37*
G36*
G01X89240Y260118D02*
G03X89760I260J304D01*
G02X91840I1040J-1218D01*
G03X92360I260J304D01*
G02X94440I1040J-1218D01*
G03X94960I260J304D01*
G02X97040I1040J-1218D01*
G03X97560I260J304D01*
G02X99818Y257860I1040J-1218D01*
G03Y257340I304J-260D01*
G02X99705Y255140I-1218J-1040D01*
G03Y254560I275J-290D01*
G02X99661Y252200I-1105J-1160D01*
G03Y251600I265J-300D01*
G02Y249200I-1061J-1200D01*
G03Y248600I265J-300D01*
G02Y246200I-1061J-1200D01*
G03Y245600I265J-300D01*
G02X97560Y243182I-1061J-1200D01*
G03X97040I-260J-304D01*
G02X94960I-1040J1218D01*
G03X94440I-260J-304D01*
G02X92360I-1040J1218D01*
G03X91840I-260J-304D01*
G02X89760I-1040J1218D01*
G03X89240I-260J-304D01*
G02X87139Y245600I-1040J1218D01*
G03Y246200I-265J300D01*
G02Y248600I1061J1200D01*
G03Y249200I-265J300D01*
G02Y251600I1061J1200D01*
G03Y252200I-265J300D01*
G02X87095Y254560I1061J1200D01*
G03Y255140I-275J290D01*
G02X86982Y257340I1105J1160D01*
G03Y257860I-304J260D01*
G02X89240Y260118I1218J1040D01*
G37*
G36*
G01X1662588Y245377D02*
G03X1662981Y244984I400J7D01*
G02X1661554Y243557I-25J-1402D01*
G03X1661161Y243950I-400J-7D01*
G02X1662588Y245377I25J1402D01*
G37*
G36*
G01X1215804Y244399D02*
G03X1216413Y244396I306J258D01*
G02X1216404Y242579I1063J-914D01*
G03X1215795Y242582I-306J-258D01*
G02X1215804Y244399I-1063J914D01*
G37*
G36*
G01X569422Y242495D02*
G03X568860Y242491I-279J-286D01*
G02X566796Y242579I-992J991D01*
G03X566187Y242582I-306J-258D01*
G02X566196Y244399I-1063J914D01*
G03X566805Y244396I306J258D01*
G02X568846Y244487I1063J-914D01*
G03X569408Y244491I279J286D01*
G02X569422Y242495I992J-991D01*
G37*
G36*
G01X1548542Y245073D02*
G03X1548652Y244519I333J-222D01*
G02X1546702Y244133I-783J-1163D01*
G03X1546592Y244687I-333J222D01*
G02X1548542Y245073I783J1163D01*
G37*
G36*
G01X1515570Y244955D02*
G03Y244424I299J-266D01*
G02X1513172Y244422I-1198J-1063D01*
G03Y244953I-299J265D01*
G02X1513153Y247057I1198J1063D01*
G03Y247577I-304J260D01*
G02X1515589Y247575I1219J1039D01*
G03Y247055I304J-260D01*
G02X1515570Y244955I-1219J-1039D01*
G37*
G36*
G01X1626025Y242615D02*
G03X1626599Y242478I350J194D01*
G02X1625390Y240152I1543J-2279D01*
G03X1624948Y240543I-400J-7D01*
G02X1626025Y242615I-150J1394D01*
G37*
G36*
G01X1779451Y236100D02*
X1774450D01*
G02X1774451Y239324I1J1612D01*
G01X1779451D01*
G02X1781062Y237722I0J-1611D01*
G01Y237627D01*
X1781053Y237542D01*
G02X1779451Y236100I-1602J169D01*
G37*
G36*
G01X1760554D02*
X1755554D01*
G02Y239324I0J1612D01*
G01X1760555D01*
G02X1762166Y237722I-1J-1612D01*
G01Y237627D01*
X1762156Y237542D01*
G02X1760554Y236100I-1602J169D01*
G37*
G36*
G01X642759Y237588D02*
G03Y237068I304J-260D01*
G02X640323I-1218J-1040D01*
G03Y237588I-304J260D01*
G02Y239668I1218J1040D01*
G03Y240188I-304J260D01*
G02Y242268I1218J1040D01*
G03Y242788I-304J260D01*
G02X642759I1218J1040D01*
G03Y242268I304J-260D01*
G02Y240188I-1218J-1040D01*
G03Y239668I304J-260D01*
G02Y237588I-1218J-1040D01*
G37*
G36*
G01X1572141Y234659D02*
G03X1571596Y234427I-167J-363D01*
G02X1570861Y236161I-1324J462D01*
G03X1571406Y236393I167J363D01*
G02X1572753Y237333I1324J-462D01*
G03X1573159Y237717I6J400D01*
G02X1573165Y237800I1401J-60D01*
G03X1572933Y238017I-199J20D01*
G02X1572213Y238085I-233J1383D01*
G03X1571684Y237800I-139J-375D01*
G02X1570805Y239431I-1366J316D01*
G03X1571334Y239716I139J375D01*
G02X1573024Y240764I1366J-316D01*
G03X1573512Y241097I92J389D01*
G02X1574377Y239599I1388J-197D01*
G03X1574102Y239412I-75J-185D01*
G02X1574095Y239260I-1402J-12D01*
G03X1574327Y239043I199J-20D01*
G02X1574537Y236258I232J-1383D01*
G03X1574131Y235874I-6J-400D01*
G02X1572141Y234659I-1401J57D01*
G37*
G36*
G01X772003Y236299D02*
G03X771937Y235762I260J-304D01*
G02X769730Y236157I-1305J-929D01*
G03X769767Y236455I-112J165D01*
G02X769672Y236574I1203J1058D01*
G03X769385Y236612I-162J-118D01*
G02X769575Y238930I-1003J1249D01*
G03X770091Y238862I298J267D01*
G02X772027Y238718I873J-1343D01*
G03X772594Y238754I266J299D01*
G02X772738Y236501I1206J-1054D01*
G03X772171Y236465I-266J-299D01*
G02X772003Y236299I-1207J1053D01*
G37*
G36*
G01X1844293Y237781D02*
G03X1844175Y237187I197J-348D01*
G02X1839851Y237383I-2246J-1757D01*
G03X1839724Y238022I-291J274D01*
G02X1841617Y238819I576J1278D01*
G03X1841985Y238281I376J-138D01*
G02X1842075Y238278I-50J-2851D01*
G03X1842275Y238543I11J200D01*
G02X1844293Y237781I1325J457D01*
G37*
G36*
G01X1682700Y234573D02*
G03X1683292Y234554I305J259D01*
G02X1683232Y232671I1008J-975D01*
G03X1682640Y232690I-305J-259D01*
G02X1682700Y234573I-1008J975D01*
G37*
G36*
G01X1767985Y232438D02*
G03X1767403Y232224I-204J-344D01*
G02X1766792Y233887I-1326J457D01*
G03X1767374Y234101I204J344D01*
G02X1767985Y232438I1326J-457D01*
G37*
G36*
G01X1804379Y233482D02*
G03X1805001Y233476I313J248D01*
G02X1804984Y231713I1082J-892D01*
G03X1804362Y231719I-313J-248D01*
G02X1804379Y233482I-1082J892D01*
G37*
G36*
G01X1794608Y234126D02*
G03X1794630Y233549I288J-278D01*
G02X1792692Y233474I-930J-1049D01*
G03X1792670Y234051I-288J278D01*
G02X1794608Y234126I930J1049D01*
G37*
G36*
G01X1883239Y233459D02*
G03X1883271Y232890I296J-269D01*
G02X1881306Y232778I-926J-1053D01*
G03X1881274Y233347I-296J269D01*
G02X1882924Y235600I926J1052D01*
G03X1883468Y235728I206J343D01*
G02X1883927Y233775I1183J-752D01*
G03X1883383Y233647I-206J-343D01*
G02X1883239Y233459I-1181J755D01*
G37*
G36*
G01X824272Y230535D02*
G03X823747Y230530I-260J-304D01*
G02X821464Y232767I-1064J1197D01*
G03Y233287I-304J260D01*
G02X821499Y235407I1218J1040D01*
G03Y235947I-295J270D01*
G02X821464Y238067I1183J1080D01*
G03Y238587I-304J260D01*
G02X823882Y240688I1218J1040D01*
G03X824482I300J265D01*
G02X826882I1200J-1061D01*
G03X827482I300J265D01*
G02X829882I1200J-1061D01*
G03X830482I300J265D01*
G02X832882I1200J-1061D01*
G03X833482I300J265D01*
G02X835861Y240712I1200J-1061D01*
G03X836424Y240687I294J271D01*
G02X838625Y238360I1076J-1187D01*
G03Y237790I281J-285D01*
G02X839043Y236218I-1125J-1141D01*
G03X839573Y235738I385J-108D01*
G02X839180Y232974I582J-1493D01*
G03X838650Y232935I-243J-318D01*
G02X836319Y232968I-1150J1115D01*
G03X835759Y232998I-295J-270D01*
G02X833448Y233200I-1059J1202D01*
G03X832845Y233226I-313J-249D01*
G02X830482Y233266I-1163J1101D01*
G03X829882I-300J-265D01*
G02X829668Y233064I-1202J1059D01*
G03X829567Y232549I246J-316D01*
G02X827031Y230632I-1387J-800D01*
G03X826458Y230633I-287J-279D01*
G02X824272Y230535I-1145J1120D01*
G37*
G36*
G01X1926924Y232852D02*
G03X1926983Y232289I311J-252D01*
G02X1925011Y232083I-883J-1089D01*
G03X1924952Y232646I-311J252D01*
G02X1926924Y232852I883J1089D01*
G37*
G36*
G01X186410Y240955D02*
G03X186979Y240945I289J276D01*
G02X189200Y238635I1121J-1145D01*
G03X189220Y238036I274J-291D01*
G02X189384Y235721I-1020J-1236D01*
G03X189404Y235161I295J-270D01*
G02X186995Y233070I-1105J-1160D01*
G03X186386Y233120I-326J-232D01*
G02X184090Y233145I-1136J1130D01*
G03X183521Y233155I-289J-276D01*
G02X181200Y233239I-1121J1145D01*
G03X180600I-300J-265D01*
G02X178200I-1200J1061D01*
G03X177600I-300J-265D01*
G02X177512Y233147I-1201J1060D01*
G03X177524Y232848I139J-144D01*
G02X175332Y230521I-1017J-1238D01*
G03X174711Y230479I-294J-272D01*
G02X172295Y232560I-1311J921D01*
G03Y233140I-275J290D01*
G02X172217Y235380I1105J1160D01*
G03Y235920I-295J270D01*
G02X172295Y238160I1183J1080D01*
G03Y238740I-275J290D01*
G02X174600Y240961I1105J1160D01*
G03X175200I300J265D01*
G02X177600I1200J-1061D01*
G03X178200I300J265D01*
G02X180600I1200J-1061D01*
G03X181200I300J265D01*
G02X183560Y241005I1200J-1061D01*
G03X184129Y240995I289J276D01*
G02X186410Y240955I1121J-1145D01*
G37*
G36*
G01X1499741Y233065D02*
G03X1499981Y232510I360J-174D01*
G02X1498296Y231783I-422J-1337D01*
G03X1498056Y232338I-360J174D01*
G02X1499741Y233065I422J1337D01*
G37*
G36*
G01X578805Y232720D02*
G03X578809Y232141I278J-288D01*
G02X576876Y232128I-960J-1022D01*
G03X576872Y232707I-278J288D01*
G02X578805Y232720I960J1022D01*
G37*
G36*
G01X1387761Y232456D02*
G03X1388231Y232161I388J96D01*
G02X1387157Y230451I287J-1372D01*
G03X1386687Y230746I-388J-96D01*
G02X1387761Y232456I-287J1372D01*
G37*
G36*
G01X1968220Y228637D02*
G03X1967580I-320J-240D01*
G02Y230563I-1280J963D01*
G03X1968220I320J240D01*
G02Y228637I1280J-963D01*
G37*
G36*
G01X571477Y230511D02*
G03X571449Y229950I270J-295D01*
G02X569455Y230047I-1045J-935D01*
G03X569483Y230608I-270J295D01*
G02X571477Y230511I1045J935D01*
G37*
G36*
G01X1939229Y229179D02*
G03X1939773Y229172I276J290D01*
G02X1939745Y226821I1074J-1188D01*
G03X1939201Y226828I-276J-290D01*
G02X1939229Y229179I-1074J1188D01*
G37*
G36*
G01X89640Y237668D02*
G03X90160I260J304D01*
G02X92240I1040J-1218D01*
G03X92760I260J304D01*
G02X94840I1040J-1218D01*
G03X95360I260J304D01*
G02X97440I1040J-1218D01*
G03X97960I260J304D01*
G02X100061Y235250I1040J-1218D01*
G03Y234650I265J-300D01*
G02Y232250I-1061J-1200D01*
G03Y231650I265J-300D01*
G02Y229250I-1061J-1200D01*
G03Y228650I265J-300D01*
G02X97960Y226232I-1061J-1200D01*
G03X97440I-260J-304D01*
G02X95360I-1040J1218D01*
G03X94840I-260J-304D01*
G02X92760I-1040J1218D01*
G03X92240I-260J-304D01*
G02X90160I-1040J1218D01*
G03X89640I-260J-304D01*
G02X87539Y228650I-1040J1218D01*
G03Y229250I-265J300D01*
G02Y231650I1061J1200D01*
G03Y232250I-265J300D01*
G02Y234650I1061J1200D01*
G03Y235250I-265J300D01*
G02X89640Y237668I1061J1200D01*
G37*
G36*
G01X703380Y225694D02*
G03X702770I-305J-259D01*
G02Y227506I-1070J906D01*
G03X703380I305J259D01*
G02Y225694I1070J-906D01*
G37*
G36*
G01X1253531Y228169D02*
G03X1253880Y227627I374J-143D01*
G02X1252796Y225241I-89J-1399D01*
G03X1252264Y225273I-284J-282D01*
G02X1250295Y225504I-869J1100D01*
G03X1249691Y225531I-314J-248D01*
G02X1249772Y227363I-1019J963D01*
G03X1250376Y227336I314J248D01*
G02X1250745Y227615I1018J-963D01*
G03X1250929Y228125I-185J355D01*
G02X1253531Y228169I1292J543D01*
G37*
G36*
G01X1945635Y227689D02*
G03X1945738Y227143I334J-220D01*
G02X1943753Y226770I-813J-1142D01*
G03X1943650Y227316I-334J220D01*
G02X1945635Y227689I813J1142D01*
G37*
G36*
G01X1627679Y224282D02*
G03X1627124Y224267I-270J-295D01*
G02X1627069Y226286I-1000J983D01*
G03X1627624Y226301I270J295D01*
G02X1627679Y224282I1000J-983D01*
G37*
G36*
G01X1883427Y223090D02*
G03X1882873I-277J-288D01*
G02Y225110I-973J1010D01*
G03X1883427I277J288D01*
G02Y223090I973J-1010D01*
G37*
G36*
G01X1401311Y222717D02*
G03X1400689I-311J-252D01*
G02Y224483I-1089J883D01*
G03X1401311I311J252D01*
G02Y222717I1089J-883D01*
G37*
G36*
G01X1622167Y224930D02*
G03Y224372I286J-279D01*
G02X1620161I-1003J-980D01*
G03Y224930I-286J279D01*
G02X1622167I1003J980D01*
G37*
G36*
G01X1245144Y223407D02*
G03X1244700Y223029I-44J-398D01*
G02X1243456Y224493I-1400J71D01*
G03X1243900Y224871I44J398D01*
G02X1245144Y223407I1400J-71D01*
G37*
G36*
G01X767662Y224140D02*
G03X767640Y223563I266J-299D01*
G02X765702Y223638I-1008J-974D01*
G03X765724Y224215I-266J299D01*
G02X767662Y224140I1008J974D01*
G37*
G36*
G01X638219Y223697D02*
G03Y223177I304J-260D01*
G02X635783I-1218J-1040D01*
G03Y223697I-304J260D01*
G02Y225777I1218J1040D01*
G03Y226297I-304J260D01*
G02Y228377I1218J1040D01*
G03Y228897I-304J260D01*
G02X638219I1218J1040D01*
G03Y228377I304J-260D01*
G02Y226297I-1218J-1040D01*
G03Y225777I304J-260D01*
G02Y223697I-1218J-1040D01*
G37*
G36*
G01X714708Y223170D02*
G03X714730Y222593I288J-278D01*
G02X712792Y222518I-930J-1049D01*
G03X712770Y223095I-288J278D01*
G02X714708Y223170I930J1049D01*
G37*
G36*
G01X115652Y224178D02*
G03X115823Y224709I-187J353D01*
G02X117738Y224092I1257J621D01*
G03X117567Y223561I187J-353D01*
G02X117707Y222824I-1257J-621D01*
G03X118084Y222391I399J-34D01*
G02X116611Y221107I-76J-1400D01*
G03X116234Y221540I-399J34D01*
G02X115652Y224178I76J1400D01*
G37*
G36*
G01X1911372Y222246D02*
G03X1911367Y221696I288J-278D01*
G02X1909230Y221597I-1027J-955D01*
G03X1909174Y222144I-317J244D01*
G02X1909022Y224423I1045J1214D01*
G03X1909009Y224969I-299J266D01*
G02X1911350Y225025I1144J1121D01*
G03X1911363Y224479I299J-266D01*
G02X1911372Y222246I-1144J-1121D01*
G37*
G36*
G01X1627988Y218701D02*
G03X1628578Y218690I300J264D01*
G02X1628542Y216799I1017J-965D01*
G03X1627952Y216810I-300J-264D01*
G02X1627988Y218701I-1017J965D01*
G37*
G36*
G01X94077Y218891D02*
G03X94053Y219509I-266J299D01*
G02X93755Y219794I1088J1436D01*
G03X93150Y219805I-307J-256D01*
G02X90389Y219899I-1341J1204D01*
G03X89779Y219922I-315J-247D01*
G02X87038Y220013I-1332J1214D01*
G03X86446Y220050I-313J-249D01*
G02X86597Y222464I-1258J1290D01*
G03X87189Y222427I313J249D01*
G02X89867Y222246I1258J-1291D01*
G03X90477Y222223I315J247D01*
G02X93194Y222161I1332J-1214D01*
G03X93799Y222150I307J256D01*
G02X96338Y219600I1341J-1204D01*
G03X96362Y218982I266J-299D01*
G02X94077Y218891I-1087J-1437D01*
G37*
G36*
G01X1592264Y213948D02*
G03X1591703Y213814I-216J-337D01*
G02X1589500Y215513I-1208J711D01*
G03X1589507Y216069I-284J282D01*
G02X1590941Y218372I1018J964D01*
G03X1591421Y218583I118J382D01*
G02X1593973Y216738I1449J-683D01*
G03X1593975Y216155I275J-291D01*
G02X1592264Y213948I-955J-1026D01*
G37*
G36*
G01X1898421Y215540D02*
G03Y214962I277J-289D01*
G02X1896479I-971J-1011D01*
G03Y215540I-277J289D01*
G02X1898421I971J1011D01*
G37*
G36*
G01X1612670Y215183D02*
G03Y214574I260J-305D01*
G02X1610852I-909J-1067D01*
G03Y215183I-260J304D01*
G02X1612670I909J1067D01*
G37*
G36*
G01X715613Y215122D02*
G03X715771Y214575I349J-196D01*
G02X713878Y214031I-671J-1231D01*
G03X713720Y214578I-349J196D01*
G02X714134Y217187I671J1231D01*
G03X714431Y217733I-73J393D01*
G02X715984Y216889I1296J534D01*
G03X715687Y216343I73J-393D01*
G02X715613Y215122I-1296J-534D01*
G37*
G36*
G01X591383Y214711D02*
G03Y214089I252J-311D01*
G02X589617I-883J-1089D01*
G03Y214711I-252J311D01*
G02X591383I883J1089D01*
G37*
G36*
G01X824127Y213264D02*
G03X823755Y212761I14J-400D01*
G02X821097Y212917I-1355J-361D01*
G03X820873Y213437I-372J148D01*
G02X820418Y216137I593J1488D01*
G03X820480Y216674I-262J302D01*
G02X822907Y218751I1295J944D01*
G03X823440Y218723I282J283D01*
G02X825615Y218572I1006J-1247D01*
G03X826189Y218563I291J274D01*
G02X828825Y216876I1133J-1133D01*
G03X829226Y216339I375J-138D01*
G02X830502Y215829I101J-1599D01*
G03X831091Y215832I293J272D01*
G02X831101Y213665I1185J-1078D01*
G03X830512Y213662I-293J-272D01*
G02X828247Y213556I-1185J1078D01*
G03X827723Y213569I-269J-295D01*
G02X825620Y213619I-1023J1233D01*
G03X825095Y213632I-270J-295D01*
G02X824127Y213264I-1023J1233D01*
G37*
G36*
G01X1814125Y210720D02*
X1809125D01*
G02Y213742I0J1511D01*
G01X1814126D01*
G02X1815636Y212241I-1J-1511D01*
G01Y212146D01*
X1815627Y212062D01*
G02X1814125Y210720I-1502J169D01*
G37*
G36*
G01X1801526D02*
X1796526D01*
G02Y213742I0J1511D01*
G01X1801527D01*
G02X1803038Y212241I0J-1512D01*
G01Y212146D01*
X1803028Y212062D01*
G02X1801526Y210720I-1502J169D01*
G37*
G36*
G01X1826685Y210650D02*
X1821685D01*
G02Y213672I0J1511D01*
G01X1826686D01*
G02X1828196Y212171I-1J-1511D01*
G01Y212076D01*
X1828187Y211992D01*
G02X1826685Y210650I-1502J169D01*
G37*
G36*
G01X778862Y211127D02*
G03X778252I-305J-259D01*
G02Y212939I-1070J906D01*
G03X778862I305J259D01*
G02Y211127I1070J-906D01*
G37*
G36*
G01X129393Y210985D02*
G03X128822Y210945I-266J-299D01*
G02X128685Y212901I-1068J908D01*
G03X129256Y212941I266J299D01*
G02X129393Y210985I1068J-908D01*
G37*
G36*
G01X1788925Y210120D02*
X1783925D01*
G02Y213142I0J1511D01*
G01X1788926D01*
G02X1790436Y211641I-1J-1511D01*
G01Y211546D01*
X1790427Y211462D01*
G02X1788925Y210120I-1502J169D01*
G37*
G36*
G01X1776325D02*
X1771325D01*
G02Y213142I0J1511D01*
G01X1776326D01*
G02X1777836Y211641I-1J-1511D01*
G01Y211546D01*
X1777827Y211462D01*
G02X1776325Y210120I-1502J169D01*
G37*
G36*
G01X1763725D02*
X1758725D01*
G02Y213142I0J1511D01*
G01X1763726D01*
G02X1765236Y211641I-1J-1511D01*
G01Y211546D01*
X1765227Y211462D01*
G02X1763725Y210120I-1502J169D01*
G37*
G36*
G01X1751125D02*
X1746125D01*
G02Y213142I0J1511D01*
G01X1751126D01*
G02X1752636Y211641I-1J-1511D01*
G01Y211546D01*
X1752627Y211462D01*
G02X1751125Y210120I-1502J169D01*
G37*
G36*
G01X1738484D02*
X1733484D01*
G02Y213142I0J1511D01*
G01X1738485D01*
G02X1739996Y211641I0J-1512D01*
G01Y211546D01*
X1739986Y211462D01*
G02X1738484Y210120I-1502J169D01*
G37*
G36*
G01X1863263Y210799D02*
G03X1862670Y210713I-259J-305D01*
G02X1860096Y211423I-1173J768D01*
G03X1859676Y211806I-400J-16D01*
G02X1861005Y213264I-72J1400D01*
G03X1861425Y212881I400J16D01*
G02X1862404Y212551I73J-1400D01*
G03X1862997Y212637I259J305D01*
G02X1863263Y210799I1173J-769D01*
G37*
G36*
G01X1726480Y210155D02*
G03X1725920I-280J-286D01*
G02Y212445I-1120J1145D01*
G03X1726480I280J286D01*
G02Y210155I1120J-1145D01*
G37*
G36*
G01X89628Y210958D02*
G03X89293Y210468I54J-396D01*
G02X85796Y210488I-1751J-425D01*
G03X85362Y210984I-388J99D01*
G02X83439Y213322I-206J1790D01*
G03X83114Y213840I-381J122D01*
G02X85083Y215076I252J1784D01*
G03X85408Y214558I381J-122D01*
G02X85527Y214537I-253J-1784D01*
G03X85753Y214810I41J196D01*
G02X89158Y215043I1663J694D01*
G03X89516Y214541I387J-103D01*
G02X89697Y214519I-127J-1797D01*
G03X89921Y214781I35J197D01*
G02X91562Y213563I1705J583D01*
G03X91155Y213087I-14J-400D01*
G02X89628Y210958I-1769J-343D01*
G37*
G36*
G01X1358537Y208181D02*
G03X1357965Y208159I-275J-290D01*
G02X1357889Y210119I-1039J941D01*
G03X1358461Y210141I275J290D01*
G02X1360432Y210247I1039J-941D01*
G03X1360987Y210269I266J299D01*
G02X1361068Y208253I1013J-969D01*
G03X1360513Y208231I-266J-299D01*
G02X1358537Y208181I-1013J969D01*
G37*
G36*
G01X1227826Y209464D02*
G03X1227844Y208909I297J-268D01*
G02X1225826Y208843I-977J-1005D01*
G03X1225808Y209398I-297J268D01*
G02X1225814Y211414I977J1005D01*
G03Y211992I-277J289D01*
G02X1225978Y214149I971J1011D01*
G03X1226070Y214713I-230J327D01*
G02X1228007Y214397I1130J830D01*
G03X1227915Y213833I230J-327D01*
G02X1227756Y211992I-1130J-830D01*
G03Y211414I277J-289D01*
G02X1227826Y209464I-971J-1011D01*
G37*
G36*
G01X1475934Y208720D02*
G03X1475721Y208189I153J-369D01*
G02X1473906Y208918I-1282J-568D01*
G03X1474119Y209449I-153J369D01*
G02X1475934Y208720I1282J568D01*
G37*
G36*
G01X1479760Y208891D02*
G03X1479846Y208343I328J-229D01*
G02X1477851Y208029I-846J-1118D01*
G03X1477765Y208577I-328J229D01*
G02X1479760Y208891I846J1118D01*
G37*
G36*
G01X617675Y205984D02*
G03X617121I-277J-288D01*
G02Y208004I-973J1010D01*
G03X617675I277J288D01*
G02X617771Y208088I970J-1012D01*
G03Y208400I-125J156D01*
G02X619658Y208521I877J1094D01*
G03Y207967I288J-277D01*
G02X619742Y207871I-1012J-970D01*
G03X620054I156J125D01*
G02X622121Y208004I1094J-877D01*
G03X622675I277J288D01*
G02X622771Y208088I970J-1012D01*
G03Y208400I-125J156D01*
G02X622638Y210467I877J1094D01*
G03Y211021I-288J277D01*
G02X622554Y211117I1012J970D01*
G03X622242I-156J-125D01*
G02X622121Y213004I-1094J877D01*
G03X622675I277J288D01*
G02X622771Y213088I970J-1012D01*
G03Y213400I-125J156D01*
G02X622638Y215467I877J1094D01*
G03Y216021I-288J277D01*
G02X622554Y216117I1012J970D01*
G03X622242I-156J-125D01*
G02X622121Y218004I-1094J877D01*
G03X622675I277J288D01*
G02X622771Y218088I970J-1012D01*
G03Y218400I-125J156D01*
G02X622638Y220467I877J1094D01*
G03Y221021I-288J277D01*
G02X622554Y221117I1012J970D01*
G03X622242I-156J-125D01*
G02X622121Y223004I-1094J877D01*
G03X622675I277J288D01*
G02X622771Y223088I970J-1012D01*
G03Y223400I-125J156D01*
G02X622638Y225467I877J1094D01*
G03Y226021I-288J277D01*
G02X622554Y226117I1012J970D01*
G03X622242I-156J-125D01*
G02X620175Y225984I-1094J877D01*
G03X619621I-277J-288D01*
G02X619525Y225900I-970J1012D01*
G03Y225588I125J-156D01*
G02X617638Y225467I-877J-1094D01*
G03Y226021I-288J277D01*
G02X617554Y226117I1012J970D01*
G03X617242I-156J-125D01*
G02X615175Y225984I-1094J877D01*
G03X614621I-277J-288D01*
G02X614525Y225900I-970J1012D01*
G03Y225588I125J-156D01*
G02X614658Y223521I-877J-1094D01*
G03Y222967I288J-277D01*
G02X614742Y222871I-1012J-970D01*
G03X615054I156J125D01*
G02X615175Y220984I1094J-877D01*
G03X614621I-277J-288D01*
G02X614525Y220900I-970J1012D01*
G03Y220588I125J-156D01*
G02X614658Y218521I-877J-1094D01*
G03Y217967I288J-277D01*
G02X614742Y217871I-1012J-970D01*
G03X615054I156J125D01*
G02X615175Y215984I1094J-877D01*
G03X614621I-277J-288D01*
G02X614525Y215900I-970J1012D01*
G03Y215588I125J-156D01*
G02X614658Y213521I-877J-1094D01*
G03Y212967I288J-277D01*
G02X614742Y212871I-1012J-970D01*
G03X615054I156J125D01*
G02X615175Y210984I1094J-877D01*
G03X614621I-277J-288D01*
G02X614525Y210900I-970J1012D01*
G03Y210588I125J-156D01*
G02X612638Y210467I-877J-1094D01*
G03Y211021I-288J277D01*
G02Y212967I1010J973D01*
G03Y213521I-288J277D01*
G02Y215467I1010J973D01*
G03Y216021I-288J277D01*
G02Y217967I1010J973D01*
G03Y218521I-288J277D01*
G02Y220467I1010J973D01*
G03Y221021I-288J277D01*
G02X612554Y221117I1012J970D01*
G03X612242I-156J-125D01*
G02X610138Y222967I-1094J877D01*
G03Y223521I-288J277D01*
G02X610054Y223617I1012J970D01*
G03X609742I-156J-125D01*
G02X607638Y225467I-1094J877D01*
G03Y226021I-288J277D01*
G02X609658I1010J973D01*
G03Y225467I288J-277D01*
G02X609742Y225371I-1012J-970D01*
G03X610054I156J125D01*
G02X612121Y225504I1094J-877D01*
G03X612675I277J288D01*
G02X612771Y225588I970J-1012D01*
G03Y225900I-125J156D01*
G02X612638Y227967I877J1094D01*
G03Y228521I-288J277D01*
G02X612554Y228617I1012J970D01*
G03X612242I-156J-125D01*
G02X612121Y230504I-1094J877D01*
G03X612675I277J288D01*
G02X614658Y228521I973J-1010D01*
G03Y227967I288J-277D01*
G02X614742Y227871I-1012J-970D01*
G03X615054I156J125D01*
G02X617121Y228004I1094J-877D01*
G03X617675I277J288D01*
G02X617771Y228088I970J-1012D01*
G03Y228400I-125J156D01*
G02X619621Y230504I877J1094D01*
G03X620175I277J288D01*
G02X622158Y228521I973J-1010D01*
G03Y227967I288J-277D01*
G02X622242Y227871I-1012J-970D01*
G03X622554I156J125D01*
G02X624658Y226021I1094J-877D01*
G03Y225467I288J-277D01*
G02Y223521I-1010J-973D01*
G03Y222967I288J-277D01*
G02Y221021I-1010J-973D01*
G03Y220467I288J-277D01*
G02Y218521I-1010J-973D01*
G03Y217967I288J-277D01*
G02Y216021I-1010J-973D01*
G03Y215467I288J-277D01*
G02Y213521I-1010J-973D01*
G03Y212967I288J-277D01*
G02Y211021I-1010J-973D01*
G03Y210467I288J-277D01*
G02Y208521I-1010J-973D01*
G03Y207967I288J-277D01*
G02X622675Y205984I-1010J-973D01*
G03X622121I-277J-288D01*
G02X620175I-973J1010D01*
G03X619621I-277J-288D01*
G02X617675I-973J1010D01*
G37*
G36*
G01X1856789Y207274D02*
G03X1857411Y207253I319J241D01*
G02X1857351Y205491I1059J-918D01*
G03X1856729Y205512I-319J-241D01*
G02X1856789Y207274I-1059J918D01*
G37*
G36*
G01X1222271Y206989D02*
G03Y206411I277J-289D01*
G02X1220329I-971J-1011D01*
G03Y206989I-277J289D01*
G02X1222271I971J1011D01*
G37*
G36*
G01X1517619Y204557D02*
G03X1517615Y204002I286J-280D01*
G02X1515595Y204017I-1017J-965D01*
G03X1515599Y204572I-286J280D01*
G02X1517619Y204557I1017J965D01*
G37*
G36*
G01X708189Y200329D02*
G03X707611I-289J-277D01*
G02X705698Y202374I-1011J972D01*
G03X705677Y203003I-257J306D01*
G02X707756Y205127I884J1214D01*
G03X708320Y205054I318J242D01*
G02X710479Y204479I862J-1106D01*
G03X711061Y204291I370J152D01*
G02X711171Y201847I739J-1191D01*
G03X710594Y201447I-179J-358D01*
G02X708189Y200329I-1394J-147D01*
G37*
G36*
G01X1884247Y201333D02*
G03X1884271Y201009I128J-153D01*
G02X1882499Y200753I-732J-1196D01*
G03X1882457Y201329I-297J268D01*
G02X1884491Y203224I893J1081D01*
G03X1885100Y203174I326J232D01*
G02X1884952Y201370I993J-990D01*
G03X1884343Y201420I-326J-232D01*
G02X1884247Y201333I-988J994D01*
G37*
G36*
G01X1227471Y201389D02*
G03Y200811I277J-289D01*
G02X1225529I-971J-1011D01*
G03Y201389I-277J289D01*
G02X1227471I971J1011D01*
G37*
G36*
G01X1546924Y199009D02*
G03X1546944Y198437I289J-276D01*
G02X1544986Y198368I-944J-1037D01*
G03X1544966Y198940I-289J276D01*
G02X1546924Y199009I944J1037D01*
G37*
G36*
G01X1763668Y195332D02*
X1758668D01*
G02Y198354I0J1511D01*
G01X1763669D01*
G02X1765180Y196853I0J-1512D01*
G01Y196758D01*
X1765170Y196674D01*
G02X1763668Y195332I-1502J169D01*
G37*
G36*
G01X1751082D02*
X1746082D01*
G02Y198354I0J1511D01*
G01X1751083D01*
G02X1752594Y196853I0J-1512D01*
G01Y196758D01*
X1752584Y196674D01*
G02X1751082Y195332I-1502J169D01*
G37*
G36*
G01X1826682Y195330D02*
X1821682D01*
G02Y198352I0J1511D01*
G01X1826683D01*
G02X1828194Y196851I0J-1512D01*
G01Y196756D01*
X1828184Y196672D01*
G02X1826682Y195330I-1502J169D01*
G37*
G36*
G01X1814041D02*
X1809041D01*
G02Y198352I0J1511D01*
G01X1814042D01*
G02X1815552Y196851I-1J-1511D01*
G01Y196756D01*
X1815543Y196672D01*
G02X1814041Y195330I-1502J169D01*
G37*
G36*
G01X1801441D02*
X1796441D01*
G02Y198352I0J1511D01*
G01X1801442D01*
G02X1802952Y196851I-1J-1511D01*
G01Y196756D01*
X1802943Y196672D01*
G02X1801441Y195330I-1502J169D01*
G37*
G36*
G01X1788841D02*
X1783841D01*
G02Y198352I0J1511D01*
G01X1788842D01*
G02X1790352Y196851I-1J-1511D01*
G01Y196756D01*
X1790343Y196672D01*
G02X1788841Y195330I-1502J169D01*
G37*
G36*
G01X1776241D02*
X1771241D01*
G02Y198352I0J1511D01*
G01X1776242D01*
G02X1777752Y196851I-1J-1511D01*
G01Y196756D01*
X1777743Y196672D01*
G02X1776241Y195330I-1502J169D01*
G37*
G36*
G01X720641Y196447D02*
G03X721181Y196442I273J293D01*
G02X721162Y194373I936J-1043D01*
G03X720622Y194378I-273J-293D01*
G02X720641Y196447I-936J1043D01*
G37*
G36*
G01X1638880Y196604D02*
G03Y196050I288J-277D01*
G02X1636860I-1010J-973D01*
G03Y196604I-288J277D01*
G02X1638880I1010J973D01*
G37*
G36*
G01X44856Y266869D02*
X44734Y266817D01*
Y197413D01*
X39300Y191980D01*
X11160D01*
X7096Y196043D01*
Y230568D01*
X4000Y233664D01*
Y233754D01*
X2126Y235627D01*
Y264825D01*
X4000Y266698D01*
Y266736D01*
X8800Y271536D01*
Y338936D01*
X14164Y344300D01*
X40829D01*
X44734Y340395D01*
Y269503D01*
X44856Y269451D01*
G02Y266869I-546J-1291D01*
G37*
G36*
G01X1708794Y193293D02*
G02X1712894Y191735I3218J2294D01*
G02X1708794Y193293I-882J3852D01*
G37*
G36*
G01X1209145Y193611D02*
G03X1209161Y194233I-243J317D01*
G02X1210925Y194189I909J1067D01*
G03X1210909Y193567I243J-317D01*
G02X1209145Y193611I-909J-1067D01*
G37*
G36*
G01X1621217Y184110D02*
G03X1620607Y184084I-294J-271D01*
G02X1620531Y185894I-1107J860D01*
G03X1621141Y185920I294J271D01*
G02X1621217Y184110I1107J-860D01*
G37*
G36*
G01X1609625Y183827D02*
G03X1609071Y183803I-265J-300D01*
G02X1608985Y185821I-1015J968D01*
G03X1609539Y185845I265J300D01*
G02X1611497Y185914I1014J-968D01*
G03X1612052Y185930I269J296D01*
G02X1614042Y185943I1001J-981D01*
G03X1614597Y185934I282J283D01*
G02X1614564Y183914I956J-1026D01*
G03X1614009Y183923I-282J-283D01*
G02X1612110Y183912I-955J1026D01*
G03X1611555Y183896I-269J-296D01*
G02X1609625Y183827I-1001J981D01*
G37*
G36*
G01X1682294Y182678D02*
G03X1681795Y182531I-164J-365D01*
G02X1679261Y184475I-1345J870D01*
G03X1679252Y184752I-148J134D01*
G02X1681967Y186024I1118J1148D01*
G03X1682483Y185672I399J31D01*
G02X1682294Y182678I467J-1532D01*
G37*
G36*
G01X1656005Y183496D02*
G03X1656044Y182887I277J-288D01*
G02X1654235Y182770I-835J-1126D01*
G03X1654196Y183379I-277J288D01*
G02X1656005Y183496I835J1126D01*
G37*
G36*
G01X1493491Y178427D02*
G03X1493498Y177872I291J-274D01*
G02X1491478Y177847I-998J-985D01*
G03X1491471Y178402I-291J274D01*
G02X1493491Y178427I998J985D01*
G37*
G36*
G01X1615361Y178138D02*
G03X1615868Y177853I388J97D01*
G02X1614925Y176177I418J-1338D01*
G03X1614418Y176462I-388J-97D01*
G02X1615361Y178138I-418J1338D01*
G37*
G36*
G01X1820382Y175014D02*
X1815382D01*
G02Y178036I0J1511D01*
G01X1820383D01*
G02X1821894Y176535I0J-1512D01*
G01Y176440D01*
X1821884Y176356D01*
G02X1820382Y175014I-1502J169D01*
G37*
G36*
G01X1807784D02*
X1802784D01*
G02Y178036I0J1511D01*
G01X1807785D01*
G02X1809296Y176535I0J-1512D01*
G01Y176440D01*
X1809286Y176356D01*
G02X1807784Y175014I-1502J169D01*
G37*
G36*
G01X1795185D02*
X1790185D01*
G02Y178036I0J1511D01*
G01X1795185D01*
G02X1796696Y176535I0J-1511D01*
G01Y176440D01*
X1796687Y176356D01*
G02X1795185Y175014I-1502J169D01*
G37*
G36*
G01X1782587D02*
X1777587D01*
G02Y178036I0J1511D01*
G01X1782588D01*
G02X1784098Y176535I-1J-1511D01*
G01Y176440D01*
X1784089Y176356D01*
G02X1782587Y175014I-1502J169D01*
G37*
G36*
G01X1764988Y178036D02*
X1769989D01*
G02X1771500Y176535I0J-1512D01*
G01Y176440D01*
X1771490Y176356D01*
G02X1769988Y175014I-1502J169D01*
G01X1764987D01*
G02X1764988Y178036I1J1511D01*
G37*
G36*
G01X1739792D02*
X1744793D01*
G02X1746304Y176535I0J-1512D01*
G01Y176440D01*
X1746294Y176356D01*
G02X1744792Y175014I-1502J169D01*
G01X1739792D01*
G02Y178036I1J1511D01*
G37*
G36*
G01X1732193Y175014D02*
X1727193D01*
G02Y178036I1J1511D01*
G01X1732193D01*
G02X1733704Y176535I0J-1511D01*
G01Y176440D01*
X1733695Y176356D01*
G02X1732193Y175014I-1502J169D01*
G37*
G36*
G01X1254266Y174954D02*
G03X1253734I-266J-298D01*
G02Y177046I-934J1046D01*
G03X1254266I266J298D01*
G02Y174954I934J-1046D01*
G37*
G36*
G01X1856427Y174890D02*
G03X1855873I-277J-288D01*
G02Y176910I-973J1010D01*
G03X1856427I277J288D01*
G02Y174890I973J-1010D01*
G37*
G36*
G01X1876467Y175734D02*
G03X1876859Y175321I400J-13D01*
G02X1875431Y173967I-27J-1402D01*
G03X1875039Y174380I-400J13D01*
G02X1876467Y175734I27J1402D01*
G37*
G36*
G01X1472924Y172703D02*
G03X1472369Y172698I-275J-290D01*
G02X1472352Y174718I-981J1002D01*
G03X1472907Y174723I275J290D01*
G02X1472924Y172703I981J-1002D01*
G37*
G36*
G01X1245937Y172140D02*
G03X1245383I-277J-288D01*
G02X1243022Y173350I-973J1010D01*
G03X1242665Y173805I-396J57D01*
G02X1244188Y175000I135J1395D01*
G03X1244545Y174545I396J-57D01*
G02X1245383Y174160I-134J-1396D01*
G03X1245937I277J288D01*
G02Y172140I973J-1010D01*
G37*
G36*
G01X1614926Y174330D02*
G03X1615426Y174119I364J166D01*
G02X1614624Y172220I474J-1319D01*
G03X1614124Y172431I-364J-166D01*
G02X1613209Y172419I-475J1319D01*
G03X1612732Y172230I-126J-380D01*
G02X1610389Y172044I-1232J670D01*
G03X1609884Y172153I-317J-244D01*
G02X1610333Y174245I-662J1236D01*
G03X1610838Y174136I317J244D01*
G02X1611941Y174231I662J-1236D01*
G03X1612418Y174420I126J380D01*
G02X1614926Y174330I1232J-670D01*
G37*
G36*
G01X1596631Y171213D02*
G03X1596053I-289J-277D01*
G02Y173155I-1011J971D01*
G03X1596631I289J277D01*
G02Y171213I1011J-971D01*
G37*
G36*
G01X1887371Y171589D02*
G03Y171011I277J-289D01*
G02X1885429I-971J-1011D01*
G03Y171589I-277J289D01*
G02X1887371I971J1011D01*
G37*
G36*
G01X1701968Y162401D02*
G03X1702523Y162390I283J283D01*
G02X1702478Y160081I1087J-1176D01*
G03X1701923Y160092I-283J-283D01*
G02X1701968Y162401I-1087J1176D01*
G37*
G36*
G01X1840909Y158413D02*
G03X1840924Y157858I295J-270D01*
G02X1838905Y157803I-983J-1000D01*
G03X1838890Y158358I-295J270D01*
G02X1840909Y158413I983J1000D01*
G37*
G36*
G01X1531912Y157489D02*
G03X1532143Y156930I358J-179D01*
G02X1530362Y155182I-443J-1330D01*
G03X1529807Y155424I-382J-119D01*
G02X1531912Y157489I-1963J4107D01*
G37*
G36*
G01X20473Y158250D02*
G03X21740Y158653I-2J2199D01*
G02X21756Y154015I1488J-2314D01*
G03X20502Y154428I-1283J-1786D01*
G01X20471D01*
G03X19204Y154025I2J-2199D01*
G02X19188Y158663I-1488J2314D01*
G03X20442Y158250I1283J1786D01*
G01X20473D01*
G37*
G36*
G01X3938D02*
G03X5205Y158653I-2J2199D01*
G02X5221Y154015I1488J-2314D01*
G03X3967Y154428I-1283J-1786D01*
G01X3936D01*
G03X2669Y154025I2J-2199D01*
G02X2653Y158663I-1488J2314D01*
G03X3907Y158250I1283J1786D01*
G01X3938D01*
G37*
G36*
G01X-12598D02*
G03X-11331Y158653I-2J2199D01*
G02X-11315Y154015I1488J-2314D01*
G03X-12569Y154428I-1283J-1786D01*
G01X-12599D01*
G03X-13866Y154025I2J-2199D01*
G02X-13882Y158663I-1488J2314D01*
G03X-12628Y158250I1283J1786D01*
G01X-12598D01*
G37*
G36*
G01X51309Y152844D02*
X47309D01*
G02Y155868I0J1512D01*
G01X51310D01*
G02X52820Y154366I-1J-1512D01*
G01Y154271D01*
X52811Y154187D01*
G02X51309Y152844I-1502J168D01*
G37*
G36*
G01X1788818Y155649D02*
G03X1789375Y155428I376J136D01*
G02X1788550Y153595I725J-1428D01*
G03X1788016Y153866I-387J-101D01*
G02X1788818Y155649I-516J1304D01*
G37*
G36*
G01X1700076Y154255D02*
G03X1700357Y154249I144J140D01*
G02X1700306Y151967I1098J-1166D01*
G03X1700025Y151973I-144J-140D01*
G02X1700076Y154255I-1098J1166D01*
G37*
G36*
G01X1876493Y153833D02*
G03X1877086Y153815I305J259D01*
G02X1877028Y151935I1010J-972D01*
G03X1876435Y151953I-305J-259D01*
G02X1876493Y153833I-1010J972D01*
G37*
G36*
G01X1913160Y153727D02*
G03X1913765Y153634I342J208D01*
G02X1913491Y151853I925J-1054D01*
G03X1912886Y151946I-342J-208D01*
G02X1913160Y153727I-925J1054D01*
G37*
G36*
G01X1514888Y153600D02*
G03X1515300Y153144I396J-57D01*
G02X1513970Y151943I58J-1401D01*
G03X1513558Y152399I-396J57D01*
G02X1514888Y153600I-58J1401D01*
G37*
G36*
G01X1885299Y154911D02*
G03X1885233Y155526I-285J280D01*
G02X1887000Y155717I767J1174D01*
G03X1887066Y155102I285J-280D01*
G02X1887203Y152857I-767J-1173D01*
G03X1887148Y152303I258J-305D01*
G02X1885146Y152502I-1098J-872D01*
G03X1885201Y153056I-258J305D01*
G02X1885299Y154911I1098J872D01*
G37*
G36*
G01X68098Y149962D02*
X63098D01*
G02Y152984I0J1511D01*
G01X68099D01*
G02X69610Y151483I0J-1512D01*
G01Y151388D01*
X69600Y151304D01*
G02X68098Y149962I-1502J169D01*
G37*
G36*
G01X1265136Y151576D02*
G03X1265691Y151567I282J284D01*
G02X1265656Y149548I955J-1026D01*
G03X1265101Y149557I-282J-284D01*
G02X1263135Y149613I-955J1027D01*
G03X1262557I-289J-277D01*
G02Y151555I-1011J971D01*
G03X1263135I289J277D01*
G02X1265136Y151576I1011J-971D01*
G37*
G36*
G01X1574971Y151089D02*
G03Y150511I277J-289D01*
G02X1573029I-971J-1011D01*
G03Y151089I-277J289D01*
G02X1574971I971J1011D01*
G37*
G36*
G01X1945607Y150725D02*
G03X1945609Y150166I287J-278D01*
G02X1943602Y150159I-1000J-982D01*
G03X1943600Y150718I-287J278D01*
G02X1945607Y150725I1000J982D01*
G37*
G36*
G01X1295155Y148431D02*
G03X1294732Y148064I-24J-400D01*
G02X1291935Y148249I-1397J113D01*
G03X1291580Y148668I-400J21D01*
G02X1291742Y151463I156J1393D01*
G03X1292143Y151839I2J400D01*
G02X1292145Y151862I1398J-110D01*
G03X1291752Y152292I-399J30D01*
G02X1293170Y153588I20J1402D01*
G03X1293563Y153158I399J-30D01*
G02X1293594Y153157I-30J-1402D01*
G03X1293797Y153396I7J200D01*
G02X1295303Y152274I1375J274D01*
G03X1294942Y151849I38J-398D01*
G02Y151657I-1399J-96D01*
G03X1295318Y151230I399J-28D01*
G02X1295155Y148431I-78J-1400D01*
G37*
G36*
G01X1496967Y149755D02*
G03X1497034Y149203I319J-241D01*
G02X1495031Y148960I-884J-1088D01*
G03X1494964Y149512I-319J241D01*
G02X1496967Y149755I884J1088D01*
G37*
G36*
G01X1964194Y149150D02*
G03X1964545Y148710I398J-43D01*
G02X1962988Y147468I-163J-1392D01*
G03X1962637Y147908I-398J43D01*
G02X1964194Y149150I163J1392D01*
G37*
G36*
G01X25591Y150376D02*
G03X26858Y150779I-2J2199D01*
G02X26874Y146141I1488J-2314D01*
G03X25620Y146554I-1283J-1786D01*
G01X25590D01*
G03X24323Y146151I2J-2199D01*
G02X24307Y150789I-1488J2314D01*
G03X25561Y150376I1283J1786D01*
G01X25591D01*
G37*
G36*
G01X9056D02*
G03X10323Y150779I-2J2199D01*
G02X10339Y146141I1488J-2314D01*
G03X9085Y146554I-1283J-1786D01*
G01X9054D01*
G03X7787Y146151I2J-2199D01*
G02X7771Y150789I-1488J2314D01*
G03X9025Y150376I1283J1786D01*
G01X9056D01*
G37*
G36*
G01X-7480D02*
G03X-6213Y150779I-2J2199D01*
G02X-6197Y146141I1488J-2314D01*
G03X-7451Y146554I-1283J-1786D01*
G01X-7481D01*
G03X-8748Y146151I2J-2199D01*
G02X-8764Y150789I-1488J2314D01*
G03X-7510Y150376I1283J1786D01*
G01X-7480D01*
G37*
G36*
G01X1278933Y147438D02*
G03X1278927Y146832I258J-306D01*
G02X1277097Y146852I-927J-1052D01*
G03X1277103Y147458I-258J306D01*
G02X1278933Y147438I927J1052D01*
G37*
G36*
G01X1490661Y145218D02*
G03X1490195Y144863I-68J-394D01*
G02X1489039Y146382I-1395J138D01*
G03X1489505Y146737I68J394D01*
G02X1490661Y145218I1395J-138D01*
G37*
G36*
G01X1533237Y146370D02*
G03X1533446Y145819I358J-180D01*
G02X1531671Y145148I-523J-1301D01*
G03X1531462Y145699I-358J180D01*
G02X1533237Y146370I523J1301D01*
G37*
G36*
G01X1849616Y143180D02*
G03X1849627Y142581I270J-295D01*
G02X1847506Y142540I-1037J-1221D01*
G03X1847495Y143139I-270J295D01*
G02X1849616Y143180I1037J1221D01*
G37*
G36*
G01X1267743Y140626D02*
G03X1267208Y140322I-141J-375D01*
G02X1266321Y141880I-1380J246D01*
G03X1266856Y142184I141J375D01*
G02X1267743Y140626I1380J-246D01*
G37*
G36*
G01X62342Y144760D02*
Y139665D01*
X62333Y139581D01*
G02X59320Y139750I-1502J169D01*
G01Y144750D01*
G02X62342Y144760I1511J0D01*
G37*
G36*
G01X48412D02*
Y139665D01*
X48402Y139581D01*
G02X45388Y139750I-1502J169D01*
G01Y144750D01*
G02X48412Y144760I1512J0D01*
G37*
G36*
G01X3938Y142502D02*
G03X5205Y142905I-2J2199D01*
G02X5221Y138267I1488J-2314D01*
G03X3967Y138680I-1283J-1786D01*
G01X3936D01*
G03X2669Y138277I2J-2199D01*
G02X2653Y142915I-1488J2314D01*
G03X3907Y142502I1283J1786D01*
G01X3938D01*
G37*
G36*
G01X-12598D02*
G03X-11331Y142905I-2J2199D01*
G02X-11315Y138267I1488J-2314D01*
G03X-12569Y138680I-1283J-1786D01*
G01X-12599D01*
G03X-13866Y138277I2J-2199D01*
G02X-13882Y142915I-1488J2314D01*
G03X-12628Y142502I1283J1786D01*
G01X-12598D01*
G37*
G36*
G01X1452354Y140426D02*
G03X1452435Y139869I322J-238D01*
G02X1450464Y139585I-845J-1119D01*
G03X1450383Y140142I-322J238D01*
G02X1450207Y142221I845J1118D01*
G03X1450200Y142776I-292J274D01*
G02X1450259Y144802I998J985D01*
G03X1450267Y145389I-268J297D01*
G02X1452172Y145364I966J1016D01*
G03X1452164Y144777I268J-297D01*
G02X1452219Y142801I-966J-1016D01*
G03X1452226Y142246I292J-274D01*
G02X1452354Y140426I-998J-985D01*
G37*
G36*
G01X1856050Y137539D02*
G03X1855450I-300J-265D01*
G02Y139661I-1200J1061D01*
G03X1856050I300J265D01*
G02Y137539I1200J-1061D01*
G37*
G36*
G01X1846743Y136086D02*
G03X1847327Y135919I364J167D01*
G02X1846826Y134164I773J-1170D01*
G03X1846242Y134331I-364J-167D01*
G02X1846743Y136086I-773J1170D01*
G37*
G36*
G01X67198Y137760D02*
Y132665D01*
X67189Y132581D01*
G02X64176Y132750I-1502J169D01*
G01Y137750D01*
G02X67198Y137760I1511J0D01*
G37*
G36*
G01X53080D02*
Y132665D01*
X53071Y132581D01*
G02X50058Y132750I-1502J169D01*
G01Y137751D01*
G02X53080Y137760I1511J-1D01*
G37*
G36*
G01X1920235Y133456D02*
G03X1920306Y132858I297J-268D01*
G02X1918474Y132641I-792J-1157D01*
G03X1918403Y133239I-297J268D01*
G02X1920235Y133456I792J1157D01*
G37*
G36*
G01X25591Y134628D02*
G03X26858Y135031I-2J2199D01*
G02X26874Y130393I1488J-2314D01*
G03X25620Y130806I-1283J-1786D01*
G01X25590D01*
G03X24323Y130403I2J-2199D01*
G02X24307Y135041I-1488J2314D01*
G03X25561Y134628I1283J1786D01*
G01X25591D01*
G37*
G36*
G01X1855539Y132335D02*
G03X1855351Y131782I165J-364D01*
G02X1853538Y132399I-1236J-661D01*
G03X1853726Y132952I-165J364D01*
G02X1855539Y132335I1236J661D01*
G37*
G36*
G01X1580308Y130140D02*
G03X1580312Y129585I290J-275D01*
G02X1578292Y129568I-1002J-981D01*
G03X1578288Y130123I-290J275D01*
G02X1580308Y130140I1002J981D01*
G37*
G36*
G01X1469569Y130197D02*
G03X1469606Y129592I279J-287D01*
G02X1467776Y129481I-851J-1114D01*
G03X1467739Y130086I-279J287D01*
G02X1469569Y130197I851J1114D01*
G37*
G36*
G01X1920681Y127497D02*
G03Y126924I279J-287D01*
G02X1918723I-979J-1004D01*
G03Y127497I-279J286D01*
G02X1920681I979J1004D01*
G37*
G36*
G01X62342Y130760D02*
Y125665D01*
X62333Y125581D01*
G02X59320Y125750I-1502J169D01*
G01Y130750D01*
G02X62342Y130760I1511J0D01*
G37*
G36*
G01X48412D02*
Y125665D01*
X48402Y125581D01*
G02X45388Y125750I-1502J169D01*
G01Y130750D01*
G02X48412Y130760I1512J0D01*
G37*
G36*
G01X-12598Y126754D02*
G03X-11331Y127157I-2J2199D01*
G02X-11315Y122519I1488J-2314D01*
G03X-12569Y122932I-1283J-1786D01*
G01X-12599D01*
G03X-13866Y122529I2J-2199D01*
G02X-13882Y127167I-1488J2314D01*
G03X-12628Y126754I1283J1786D01*
G01X-12598D01*
G37*
G36*
G01X1270489Y121529D02*
G03X1269911I-289J-277D01*
G02Y123471I-1011J971D01*
G03X1270489I289J277D01*
G02Y121529I1011J-971D01*
G37*
G36*
G01X1543504Y120435D02*
G03X1543326Y119880I172J-361D01*
G02X1541496Y120465I-1226J-680D01*
G03X1541674Y121020I-172J361D01*
G02X1543504Y120435I1226J680D01*
G37*
G36*
G01X1760020Y118137D02*
G03X1759380I-320J-240D01*
G02Y120063I-1280J963D01*
G03X1760020I320J240D01*
G02Y118137I1280J-963D01*
G37*
G36*
G01X53080Y123760D02*
Y118665D01*
X53071Y118581D01*
G02X50058Y118750I-1502J169D01*
G01Y123751D01*
G02X53080Y123760I1511J-1D01*
G37*
G36*
G01X63894Y123731D02*
G02X66916Y123740I1511J-1D01*
G01Y118730D01*
X66917D01*
X66916Y118645D01*
X66907Y118561D01*
G02X63894Y118730I-1502J169D01*
G01Y123731D01*
G37*
G36*
G01X1474064Y119985D02*
G03X1474087Y119386I276J-289D01*
G02X1472232Y119314I-887J-1086D01*
G03X1472209Y119913I-276J289D01*
G02X1471986Y121856I887J1086D01*
G03X1471854Y122456I-316J245D01*
G02X1473610Y122843I646J1244D01*
G03X1473742Y122243I316J-245D01*
G02X1474064Y119985I-646J-1244D01*
G37*
G36*
G01X1528024Y120779D02*
Y115684D01*
X1528015Y115600D01*
G02X1525002Y115769I-1502J169D01*
G01Y120769D01*
G02X1528024Y120779I1511J0D01*
G37*
G36*
G01X25591Y118880D02*
G03X26858Y119283I-2J2199D01*
G02X26874Y114645I1488J-2314D01*
G03X25620Y115058I-1283J-1786D01*
G01X25590D01*
G03X24323Y114655I2J-2199D01*
G02X24307Y119293I-1488J2314D01*
G03X25561Y118880I1283J1786D01*
G01X25591D01*
G37*
G36*
G01X9054Y115058D02*
G03X7787Y114655I2J-2199D01*
G02X7771Y119293I-1488J2314D01*
G03X9025Y118880I1283J1786D01*
G01X9056D01*
G03X10323Y119283I-2J2199D01*
G02X10339Y114645I1488J-2314D01*
G03X9085Y115058I-1283J-1786D01*
G01X9054D01*
G37*
G36*
G01X1907363Y116972D02*
G03X1907375Y116373I271J-294D01*
G02X1905518Y116337I-908J-1068D01*
G03X1905506Y116936I-271J294D01*
G02X1907363Y116972I908J1068D01*
G37*
G36*
G01X1303475Y113289D02*
G03Y112711I277J-289D01*
G02X1301533I-971J-1011D01*
G03Y113289I-277J289D01*
G02X1301458Y115234I971J1011D01*
G03Y115766I-298J266D01*
G02X1301467Y117644I1046J934D01*
G03X1301472Y118177I-295J269D01*
G02X1303563Y118158I1054J925D01*
G03X1303558Y117625I295J-269D01*
G02X1303550Y115766I-1054J-925D01*
G03Y115234I298J-266D01*
G02X1303475Y113289I-1046J-934D01*
G37*
G36*
G01X62212Y116760D02*
Y111665D01*
X62202Y111581D01*
G02X59188Y111750I-1502J169D01*
G01Y116750D01*
G02X62212Y116760I1512J0D01*
G37*
G36*
G01X48412D02*
Y111665D01*
X48402Y111581D01*
G02X45388Y111750I-1502J169D01*
G01Y116750D01*
G02X48412Y116760I1512J0D01*
G37*
G36*
G01X1599621Y109666D02*
G03X1599111Y109654I-248J-314D01*
G02X1599059Y111811I-921J1057D01*
G03X1599569Y111823I248J314D01*
G02X1599621Y109666I921J-1057D01*
G37*
G36*
G01X1188924Y109493D02*
G03X1188929Y108905I274J-292D01*
G02X1187028Y108886I-940J-1040D01*
G03X1187023Y109474I-274J292D01*
G02X1188924Y109493I940J1040D01*
G37*
G36*
G01X1152113D02*
G03X1152118Y108905I274J-292D01*
G02X1150217Y108886I-940J-1040D01*
G03X1150212Y109474I-274J292D01*
G02X1152113Y109493I940J1040D01*
G37*
G36*
G01X934593D02*
G03X934598Y108905I274J-292D01*
G02X932697Y108886I-940J-1040D01*
G03X932692Y109474I-274J292D01*
G02X934593Y109493I940J1040D01*
G37*
G36*
G01X897782D02*
G03X897787Y108905I274J-292D01*
G02X895886Y108886I-940J-1040D01*
G03X895881Y109474I-274J292D01*
G02X897782Y109493I940J1040D01*
G37*
G36*
G01X539316D02*
G03X539321Y108905I274J-292D01*
G02X537420Y108886I-940J-1040D01*
G03X537415Y109474I-274J292D01*
G02X539316Y109493I940J1040D01*
G37*
G36*
G01X502505D02*
G03X502510Y108905I274J-292D01*
G02X500609Y108886I-940J-1040D01*
G03X500604Y109474I-274J292D01*
G02X502505Y109493I940J1040D01*
G37*
G36*
G01X284985D02*
G03X284990Y108905I274J-292D01*
G02X283089Y108886I-940J-1040D01*
G03X283084Y109474I-274J292D01*
G02X284985Y109493I940J1040D01*
G37*
G36*
G01X248174D02*
G03X248179Y108905I274J-292D01*
G02X246278Y108886I-940J-1040D01*
G03X246273Y109474I-274J292D01*
G02X248174Y109493I940J1040D01*
G37*
G36*
G01X20473Y111006D02*
G03X21740Y111409I-2J2199D01*
G02X21756Y106771I1488J-2314D01*
G03X20502Y107184I-1283J-1786D01*
G01X20471D01*
G03X19204Y106781I2J-2199D01*
G02X19188Y111419I-1488J2314D01*
G03X20442Y111006I1283J1786D01*
G01X20473D01*
G37*
G36*
G01X3936Y107184D02*
G03X2669Y106781I2J-2199D01*
G02X2653Y111419I-1488J2314D01*
G03X3907Y111006I1283J1786D01*
G01X3938D01*
G03X5205Y111409I-2J2199D01*
G02X5221Y106771I1488J-2314D01*
G03X3967Y107184I-1283J-1786D01*
G01X3936D01*
G37*
G36*
G01X-12598Y111006D02*
G03X-11331Y111409I-2J2199D01*
G02X-11315Y106771I1488J-2314D01*
G03X-12569Y107184I-1283J-1786D01*
G01X-12599D01*
G03X-13866Y106781I2J-2199D01*
G02X-13882Y111419I-1488J2314D01*
G03X-12628Y111006I1283J1786D01*
G01X-12598D01*
G37*
G36*
G01X1194046Y109239D02*
G03X1194040Y108660I273J-292D01*
G02X1192106Y108680I-977J-1005D01*
G03X1192112Y109259I-273J292D01*
G02X1194046Y109239I977J1005D01*
G37*
G36*
G01X1157235D02*
G03X1157229Y108660I273J-292D01*
G02X1155295Y108680I-977J-1005D01*
G03X1155301Y109259I-273J292D01*
G02X1157235Y109239I977J1005D01*
G37*
G36*
G01X939715D02*
G03X939709Y108660I273J-292D01*
G02X937775Y108680I-977J-1005D01*
G03X937781Y109259I-273J292D01*
G02X939715Y109239I977J1005D01*
G37*
G36*
G01X902904D02*
G03X902898Y108660I273J-292D01*
G02X900964Y108680I-977J-1005D01*
G03X900970Y109259I-273J292D01*
G02X902904Y109239I977J1005D01*
G37*
G36*
G01X544438D02*
G03X544432Y108660I273J-292D01*
G02X542498Y108680I-977J-1005D01*
G03X542504Y109259I-273J292D01*
G02X544438Y109239I977J1005D01*
G37*
G36*
G01X507627D02*
G03X507621Y108660I273J-292D01*
G02X505687Y108680I-977J-1005D01*
G03X505693Y109259I-273J292D01*
G02X507627Y109239I977J1005D01*
G37*
G36*
G01X290107D02*
G03X290101Y108660I273J-292D01*
G02X288167Y108680I-977J-1005D01*
G03X288173Y109259I-273J292D01*
G02X290107Y109239I977J1005D01*
G37*
G36*
G01X253296D02*
G03X253290Y108660I273J-292D01*
G02X251356Y108680I-977J-1005D01*
G03X251362Y109259I-273J292D01*
G02X253296Y109239I977J1005D01*
G37*
G36*
G01X1853181Y106802D02*
G03X1852743Y106393I-38J-398D01*
G02X1851477Y107753I-1402J-35D01*
G03X1851915Y108162I38J398D01*
G02X1853181Y106802I1402J35D01*
G37*
G36*
G01X66896Y109760D02*
Y104665D01*
X66886Y104581D01*
G02X63872Y104750I-1502J169D01*
G01Y109751D01*
G02X66896Y109760I1512J-1D01*
G37*
G36*
G01X52892D02*
Y104665D01*
X52883Y104581D01*
G02X49870Y104750I-1502J169D01*
G01Y109750D01*
G02X52892Y109760I1511J0D01*
G37*
G36*
G01X1512424Y108332D02*
G02X1515446Y108342I1511J0D01*
G01Y104447D01*
X1515437Y104363D01*
G02X1512424Y104532I-1502J169D01*
G01Y108332D01*
G37*
G36*
G01X1811259Y105468D02*
G03X1811814Y105445I289J276D01*
G02X1811729Y103427I929J-1050D01*
G03X1811174Y103450I-289J-276D01*
G02X1811259Y105468I-929J1050D01*
G37*
G36*
G01X1525004Y103876D02*
X1524995Y104048D01*
X1524994D01*
X1525295Y109060D01*
X1525327Y109232D01*
G02X1528314Y109136I1486J-275D01*
G01X1528335Y108960D01*
X1528378D01*
X1528498Y108816D01*
X1528246Y107442D01*
X1528032Y103868D01*
X1528031Y103867D01*
X1528027Y103788D01*
X1528015Y103789D01*
G02X1525004Y103876I-1502J168D01*
G37*
G36*
G01X1490430Y104578D02*
G03X1490268Y104024I185J-355D01*
G02X1488403Y104567I-1215J-699D01*
G03X1488565Y105121I-185J355D01*
G02X1490430Y104578I1215J699D01*
G37*
G36*
G01X977337Y104779D02*
G03X977448Y104207I324J-234D01*
G02X975563Y103842I-748J-1186D01*
G03X975452Y104414I-324J234D01*
G02X977337Y104779I748J1186D01*
G37*
G36*
G01X327729D02*
G03X327840Y104207I324J-234D01*
G02X325955Y103842I-748J-1186D01*
G03X325844Y104414I-324J234D01*
G02X327729Y104779I748J1186D01*
G37*
G36*
G01X700017Y103801D02*
G03X699840Y103255I176J-359D01*
G02X697587Y101631I-1240J-655D01*
G03X697032Y101653I-289J-277D01*
G02X694970Y101870I-932J1047D01*
G03X694415Y101959I-323J-236D01*
G02X692290Y103599I-815J1141D01*
G03X691892Y104140I-374J142D01*
G02X692897Y106425I-82J1400D01*
G03X693485Y106390I310J253D01*
G02X695554Y106258I974J-1008D01*
G03X696081Y106170I312J249D01*
G02X697803Y105998I751J-1184D01*
G03X698373Y106014I277J288D01*
G02X700454Y105984I1027J-954D01*
G03X701021Y105949I301J264D01*
G02X703095Y105716I932J-1047D01*
G03X703642Y105615I326J232D01*
G02X703277Y103634I777J-1167D01*
G03X702730Y103735I-326J-232D01*
G02X700899Y103978I-777J1167D01*
G03X700332Y104013I-301J-264D01*
G02X700017Y103801I-933J1046D01*
G37*
G36*
G01X743520Y101574D02*
G03X742965Y101396I-194J-350D01*
G02X742380Y103226I-1265J604D01*
G03X742935Y103404I194J350D01*
G02X744736Y104095I1265J-604D01*
G03X745269Y104340I153J370D01*
G02X746064Y102605I1331J-440D01*
G03X745531Y102360I-153J-370D01*
G02X743520Y101574I-1331J440D01*
G37*
G36*
G01X25591Y103132D02*
G03X26858Y103535I-2J2199D01*
G02X26874Y98897I1488J-2314D01*
G03X25620Y99310I-1283J-1786D01*
G01X25590D01*
G03X24323Y98907I2J-2199D01*
G02X24307Y103545I-1488J2314D01*
G03X25561Y103132I1283J1786D01*
G01X25591D01*
G37*
G36*
G01X9054Y99310D02*
G03X7787Y98907I2J-2199D01*
G02X7771Y103545I-1488J2314D01*
G03X9025Y103132I1283J1786D01*
G01X9056D01*
G03X10323Y103535I-2J2199D01*
G02X10339Y98897I1488J-2314D01*
G03X9085Y99310I-1283J-1786D01*
G01X9054D01*
G37*
G36*
G01X-7480Y103132D02*
G03X-6213Y103535I-2J2199D01*
G02X-6197Y98897I1488J-2314D01*
G03X-7451Y99310I-1283J-1786D01*
G01X-7481D01*
G03X-8748Y98907I2J-2199D01*
G02X-8764Y103545I-1488J2314D01*
G03X-7510Y103132I1283J1786D01*
G01X-7480D01*
G37*
G36*
G01X1500216Y99529D02*
G02X1497194Y99501I-1511J-7D01*
G01X1497149Y102725D01*
G02X1500161Y102924I1511J21D01*
G01X1500169Y102860D01*
X1500171Y102795D01*
G02X1500172Y102767I-1510J-68D01*
G01Y102746D01*
X1500216Y99544D01*
G02Y99529I-1511J-8D01*
G37*
G36*
G01X757771Y100989D02*
G03Y100411I277J-289D01*
G02X755829I-971J-1011D01*
G03Y100989I-277J289D01*
G02X757771I971J1011D01*
G37*
G36*
G01X1375685Y100772D02*
G03Y100460I125J-156D01*
G02X1373798Y100339I-877J-1094D01*
G03Y100893I-288J277D01*
G02Y102839I1010J973D01*
G03Y103393I-288J277D01*
G02Y105339I1010J973D01*
G03Y105893I-288J277D01*
G02X1375781Y107876I1010J973D01*
G03X1376335I277J288D01*
G02X1378318Y105893I973J-1010D01*
G03Y105339I288J-277D01*
G02Y103393I-1010J-973D01*
G03Y102839I288J-277D01*
G02X1376335Y100856I-1010J-973D01*
G03X1375781I-277J-288D01*
G02X1375685Y100772I-970J1012D01*
G37*
G36*
G01X1687931Y99885D02*
G03X1688484Y99838I301J264D01*
G02X1688313Y97827I884J-1088D01*
G03X1687760Y97874I-301J-264D01*
G02X1687931Y99885I-884J1088D01*
G37*
G36*
G01X1659414Y100014D02*
G03X1659913Y99815I359J176D01*
G02X1659140Y97886I487J-1315D01*
G03X1658641Y98085I-359J-176D01*
G02X1659414Y100014I-487J1315D01*
G37*
G36*
G01X62312Y102760D02*
Y97665D01*
X62303Y97581D01*
G02X59290Y97750I-1502J169D01*
G01Y102751D01*
G02X62312Y102760I1511J-1D01*
G37*
G36*
G01X48412D02*
Y97665D01*
X48402Y97581D01*
G02X45388Y97750I-1502J169D01*
G01Y102751D01*
G02X48412Y102760I1512J-1D01*
G37*
G36*
G01X1542883Y98810D02*
G03X1542905Y98277I309J-254D01*
G02X1540817Y98190I-1005J-977D01*
G03X1540795Y98723I-309J254D01*
G02X1542883Y98810I1005J977D01*
G37*
G36*
G01X763520Y94433D02*
G03X762998Y94166I-137J-376D01*
G02X762130Y95867I-1348J384D01*
G03X762652Y96134I137J376D01*
G02X763520Y94433I1348J-384D01*
G37*
G36*
G01X1919170Y95082D02*
G03X1919149Y94521I274J-291D01*
G02X1917153Y94597I-1035J-945D01*
G03X1917174Y95158I-274J291D01*
G02X1917196Y97071I1036J945D01*
G03X1917137Y97674I-289J276D01*
G02X1919039Y97816I865J1228D01*
G03X1919070Y97210I276J-290D01*
G02X1919170Y95082I-860J-1107D01*
G37*
G36*
G01X1525232Y98265D02*
G02X1528256Y98275I1512J0D01*
G01Y93180D01*
X1528246Y93096D01*
G02X1525232Y93265I-1502J169D01*
G01Y98265D01*
G37*
G36*
G01X1405579Y90903D02*
G03X1404913I-333J-222D01*
G02X1403448Y93050I-1167J777D01*
G03X1403759Y93494I-85J391D01*
G02X1406205Y94601I1390J185D01*
G03X1406829Y94628I301J263D01*
G02X1408382Y92463I1131J-828D01*
G03X1408113Y91993I121J-381D01*
G02X1405579Y90903I-1367J-313D01*
G37*
G36*
G01X35367Y93038D02*
G03X35733Y92550I390J-89D01*
G02X34283Y91462I-83J-1400D01*
G03X33917Y91950I-390J89D01*
G02X35367Y93038I83J1400D01*
G37*
G36*
G01X1908550Y92826D02*
G03X1908558Y92268I291J-275D01*
G02X1906263Y92233I-1130J-1135D01*
G03X1906255Y92791I-291J275D01*
G02X1906213Y92833I1112J1153D01*
G03X1905913Y92824I-146J-136D01*
G02X1903524Y94956I-1234J1022D01*
G03X1903537Y95497I-288J278D01*
G02X1905797Y97757I1205J1055D01*
G03X1906338Y97770I263J301D01*
G02X1908609Y95511I1110J-1155D01*
G03X1908597Y94974I290J-275D01*
G02X1908550Y92826I-1212J-1048D01*
G37*
G36*
G01X68725Y89388D02*
X63724D01*
G02X63725Y92412I1J1512D01*
G01X68725D01*
G02X70236Y90910I-1J-1512D01*
G01Y90815D01*
X70227Y90731D01*
G02X68725Y89388I-1502J168D01*
G37*
G36*
G01X52892Y95760D02*
Y90665D01*
X52883Y90581D01*
G02X49870Y90750I-1502J169D01*
G01Y95750D01*
G02X52892Y95760I1511J0D01*
G37*
G36*
G01X1676372Y91718D02*
G03X1676946Y91514I374J142D01*
G02X1676339Y89802I703J-1213D01*
G03X1675765Y90006I-374J-142D01*
G02X1676372Y91718I-703J1213D01*
G37*
G36*
G01X733655Y89330D02*
G03X734242Y89312I302J263D01*
G02X734185Y87407I999J-983D01*
G03X733598Y87425I-302J-263D01*
G02X731603Y87422I-999J983D01*
G03X731034I-284J-282D01*
G02Y89394I-996J986D01*
G03X731603I285J282D01*
G02X733655Y89330I996J-986D01*
G37*
G36*
G01X1542878Y89123D02*
G03X1542807Y88580I253J-309D01*
G02X1540780Y88844I-1137J-820D01*
G03X1540851Y89387I-253J309D01*
G02X1540978Y91180I1137J820D01*
G03Y91734I-288J277D01*
G02X1543287Y93234I1010J973D01*
G03X1543774Y93002I371J151D01*
G02X1543857Y90296I406J-1342D01*
G03X1543370Y89973I-92J-389D01*
G02X1542878Y89123I-1383J233D01*
G37*
G36*
G01X1230845Y89103D02*
G03Y88525I277J-289D01*
G02X1228903I-971J-1011D01*
G03Y89103I-277J289D01*
G02X1230845I971J1011D01*
G37*
G36*
G01X1194034D02*
G03Y88525I277J-289D01*
G02X1192092I-971J-1011D01*
G03Y89103I-277J289D01*
G02X1194034I971J1011D01*
G37*
G36*
G01X1157223D02*
G03Y88525I277J-289D01*
G02X1155281I-971J-1011D01*
G03Y89103I-277J289D01*
G02X1157223I971J1011D01*
G37*
G36*
G01X1120411D02*
G03Y88525I277J-289D01*
G02X1118469I-971J-1011D01*
G03Y89103I-277J289D01*
G02X1120411I971J1011D01*
G37*
G36*
G01X939703D02*
G03Y88525I277J-289D01*
G02X937761I-971J-1011D01*
G03Y89103I-277J289D01*
G02X939703I971J1011D01*
G37*
G36*
G01X902892D02*
G03Y88525I277J-289D01*
G02X900950I-971J-1011D01*
G03Y89103I-277J289D01*
G02X902892I971J1011D01*
G37*
G36*
G01X866081D02*
G03Y88525I277J-289D01*
G02X864139I-971J-1011D01*
G03Y89103I-277J289D01*
G02X866081I971J1011D01*
G37*
G36*
G01X829270D02*
G03Y88525I277J-289D01*
G02X827328I-971J-1011D01*
G03Y89103I-277J289D01*
G02X829270I971J1011D01*
G37*
G36*
G01X792459D02*
G03Y88525I277J-289D01*
G02X790517I-971J-1011D01*
G03Y89103I-277J289D01*
G02X792459I971J1011D01*
G37*
G36*
G01X581237D02*
G03Y88525I277J-289D01*
G02X579295I-971J-1011D01*
G03Y89103I-277J289D01*
G02X581237I971J1011D01*
G37*
G36*
G01X544426D02*
G03Y88525I277J-289D01*
G02X542484I-971J-1011D01*
G03Y89103I-277J289D01*
G02X544426I971J1011D01*
G37*
G36*
G01X507615D02*
G03Y88525I277J-289D01*
G02X505673I-971J-1011D01*
G03Y89103I-277J289D01*
G02X507615I971J1011D01*
G37*
G36*
G01X470803D02*
G03Y88525I277J-289D01*
G02X468861I-971J-1011D01*
G03Y89103I-277J289D01*
G02X470803I971J1011D01*
G37*
G36*
G01X290095D02*
G03Y88525I277J-289D01*
G02X288153I-971J-1011D01*
G03Y89103I-277J289D01*
G02X290095I971J1011D01*
G37*
G36*
G01X253284D02*
G03Y88525I277J-289D01*
G02X251342I-971J-1011D01*
G03Y89103I-277J289D01*
G02X253284I971J1011D01*
G37*
G36*
G01X216473D02*
G03Y88525I277J-289D01*
G02X214531I-971J-1011D01*
G03Y89103I-277J289D01*
G02X216473I971J1011D01*
G37*
G36*
G01X179662D02*
G03Y88525I277J-289D01*
G02X177720I-971J-1011D01*
G03Y89103I-277J289D01*
G02X179662I971J1011D01*
G37*
G36*
G01X142851D02*
G03Y88525I277J-289D01*
G02X140909I-971J-1011D01*
G03Y89103I-277J289D01*
G02X142851I971J1011D01*
G37*
G36*
G01X1225745Y88889D02*
G03Y88311I277J-289D01*
G02X1223803I-971J-1011D01*
G03Y88889I-277J289D01*
G02X1225745I971J1011D01*
G37*
G36*
G01X1188934D02*
G03Y88311I277J-289D01*
G02X1186992I-971J-1011D01*
G03Y88889I-277J289D01*
G02X1188934I971J1011D01*
G37*
G36*
G01X1152123D02*
G03Y88311I277J-289D01*
G02X1150181I-971J-1011D01*
G03Y88889I-277J289D01*
G02X1152123I971J1011D01*
G37*
G36*
G01X1115311D02*
G03Y88311I277J-289D01*
G02X1113369I-971J-1011D01*
G03Y88889I-277J289D01*
G02X1115311I971J1011D01*
G37*
G36*
G01X934603D02*
G03Y88311I277J-289D01*
G02X932661I-971J-1011D01*
G03Y88889I-277J289D01*
G02X934603I971J1011D01*
G37*
G36*
G01X897792D02*
G03Y88311I277J-289D01*
G02X895850I-971J-1011D01*
G03Y88889I-277J289D01*
G02X897792I971J1011D01*
G37*
G36*
G01X860981D02*
G03Y88311I277J-289D01*
G02X859039I-971J-1011D01*
G03Y88889I-277J289D01*
G02X860981I971J1011D01*
G37*
G36*
G01X824170D02*
G03Y88311I277J-289D01*
G02X822228I-971J-1011D01*
G03Y88889I-277J289D01*
G02X824170I971J1011D01*
G37*
G36*
G01X787359D02*
G03Y88311I277J-289D01*
G02X785417I-971J-1011D01*
G03Y88889I-277J289D01*
G02X787359I971J1011D01*
G37*
G36*
G01X576137D02*
G03Y88311I277J-289D01*
G02X574195I-971J-1011D01*
G03Y88889I-277J289D01*
G02X576137I971J1011D01*
G37*
G36*
G01X539326D02*
G03Y88311I277J-289D01*
G02X537384I-971J-1011D01*
G03Y88889I-277J289D01*
G02X539326I971J1011D01*
G37*
G36*
G01X502515D02*
G03Y88311I277J-289D01*
G02X500573I-971J-1011D01*
G03Y88889I-277J289D01*
G02X502515I971J1011D01*
G37*
G36*
G01X465703D02*
G03Y88311I277J-289D01*
G02X463761I-971J-1011D01*
G03Y88889I-277J289D01*
G02X465703I971J1011D01*
G37*
G36*
G01X284995D02*
G03Y88311I277J-289D01*
G02X283053I-971J-1011D01*
G03Y88889I-277J289D01*
G02X284995I971J1011D01*
G37*
G36*
G01X248184D02*
G03Y88311I277J-289D01*
G02X246242I-971J-1011D01*
G03Y88889I-277J289D01*
G02X248184I971J1011D01*
G37*
G36*
G01X211373D02*
G03Y88311I277J-289D01*
G02X209431I-971J-1011D01*
G03Y88889I-277J289D01*
G02X211373I971J1011D01*
G37*
G36*
G01X174562D02*
G03Y88311I277J-289D01*
G02X172620I-971J-1011D01*
G03Y88889I-277J289D01*
G02X174562I971J1011D01*
G37*
G36*
G01X137751D02*
G03Y88311I277J-289D01*
G02X135809I-971J-1011D01*
G03Y88889I-277J289D01*
G02X137751I971J1011D01*
G37*
G36*
G01X1810887Y85685D02*
G03X1810347I-270J-295D01*
G02X1808049Y87908I-1080J1183D01*
G03Y88428I-304J260D01*
G02X1808084Y90548I1218J1040D01*
G03Y91088I-295J270D01*
G02Y93248I1183J1080D01*
G03Y93788I-295J270D01*
G02X1810347Y96051I1183J1080D01*
G03X1810887I270J295D01*
G02X1813047I1080J-1183D01*
G03X1813587I270J295D01*
G02X1815850Y93788I1080J-1183D01*
G03Y93248I295J-270D01*
G02Y91088I-1183J-1080D01*
G03Y90548I295J-270D01*
G02X1815885Y88428I-1183J-1080D01*
G03Y87908I304J-260D01*
G02X1813587Y85685I-1218J-1040D01*
G03X1813047I-270J-295D01*
G02X1810887I-1080J1183D01*
G37*
G36*
G01X1501386Y90491D02*
Y86596D01*
X1501377Y86512D01*
G02X1498364Y86681I-1502J169D01*
G01Y90481D01*
G02X1501386Y90491I1511J0D01*
G37*
G36*
G01X1598489Y83529D02*
G03X1597911I-289J-277D01*
G02Y85471I-1011J971D01*
G03X1598489I289J277D01*
G02X1600473Y85510I1011J-971D01*
G03X1601027I277J288D01*
G02Y83490I973J-1010D01*
G03X1600473I-277J-288D01*
G02X1598489Y83529I-973J1010D01*
G37*
G36*
G01X1953132Y85697D02*
G03X1953664Y85419I388J95D01*
G02X1952807Y83777I505J-1308D01*
G03X1952275Y84055I-388J-95D01*
G02X1950797Y84353I-505J1308D01*
G03X1950243I-277J-288D01*
G02X1948259Y84392I-973J1010D01*
G03X1947681I-289J-277D01*
G02X1945660Y86336I-1010J972D01*
G03Y86890I-288J277D01*
G02X1945623Y88795I1010J972D01*
G03X1945601Y89350I-299J266D01*
G02X1945560Y91336I969J1013D01*
G03Y91890I-288J277D01*
G02X1947581Y93834I1011J972D01*
G03X1948159I289J277D01*
G02X1948419Y94047I1012J-970D01*
G03X1948517Y94635I-214J338D01*
G02X1950583Y96523I1092J879D01*
G03X1951137I277J288D01*
G02X1953293Y96265I973J-1010D01*
G03X1953904Y96187I338J214D01*
G02X1955834Y96173I958J-1024D01*
G03X1956388I277J288D01*
G02X1958096Y93969I972J-1010D01*
G03X1957992Y93381I210J-340D01*
G02X1955918Y91503I-1100J-869D01*
G03X1955364I-277J-288D01*
G02X1953216Y91747I-973J1010D01*
G03X1952613Y91825I-335J-218D01*
G02X1952547Y91769I-940J1041D01*
G03Y91457I125J-156D01*
G02X1952717Y89431I-877J-1094D01*
G03X1952739Y88876I299J-266D01*
G02X1952780Y86890I-969J-1013D01*
G03Y86336I288J-277D01*
G02X1953132Y85697I-1010J-973D01*
G37*
G36*
G01X1025955Y85404D02*
G03Y84850I288J-277D01*
G02X1023935I-1010J-973D01*
G03Y85404I-288J277D01*
G02X1025955I1010J973D01*
G37*
G36*
G01X376347D02*
G03Y84850I288J-277D01*
G02X374327I-1010J-973D01*
G03Y85404I-288J277D01*
G02X376347I1010J973D01*
G37*
G36*
G01X753559Y85177D02*
G03X753577Y84578I274J-292D01*
G02X751721Y84523I-897J-1078D01*
G03X751703Y85122I-274J292D01*
G02X753559Y85177I897J1078D01*
G37*
G36*
G01X1491579Y84665D02*
G03X1491783Y84181I380J-125D01*
G02X1489789Y83197I-619J-1258D01*
G03X1489529Y83653I-392J78D01*
G02X1491579Y84665I528J1512D01*
G37*
G36*
G01X1664527Y80590D02*
G03X1663973I-277J-288D01*
G02Y82610I-973J1010D01*
G03X1664527I277J288D01*
G02X1666473I973J-1010D01*
G03X1667027I277J288D01*
G02X1668973I973J-1010D01*
G03X1669527I277J288D01*
G02X1671473I973J-1010D01*
G03X1672027I277J288D01*
G02X1673973I973J-1010D01*
G03X1674527I277J288D01*
G02X1676473I973J-1010D01*
G03X1677027I277J288D01*
G02Y80590I973J-1010D01*
G03X1676473I-277J-288D01*
G02X1674527I-973J1010D01*
G03X1673973I-277J-288D01*
G02X1672027I-973J1010D01*
G03X1671473I-277J-288D01*
G02X1669527I-973J1010D01*
G03X1668973I-277J-288D01*
G02X1667027I-973J1010D01*
G03X1666473I-277J-288D01*
G02X1664527I-973J1010D01*
G37*
G36*
G01X1540631Y78303D02*
G03X1540043Y78212I-253J-310D01*
G02X1539759Y80064I-1173J768D01*
G03X1540347Y80155I253J310D01*
G02X1540631Y78303I1173J-768D01*
G37*
G36*
G01X1695009Y79103D02*
G03X1695533Y79134I244J317D01*
G02Y76848I1122J-1143D01*
G03X1695009Y76879I-280J-286D01*
G02X1693182Y76981I-854J1112D01*
G03X1692628I-277J-288D01*
G02X1690682I-973J1010D01*
G03X1690128I-277J-288D01*
G02Y79001I-973J1010D01*
G03X1690682I277J288D01*
G02X1692628I973J-1010D01*
G03X1693182I277J288D01*
G02X1695009Y79103I973J-1010D01*
G37*
G36*
G01X1822075Y76146D02*
G03X1821535I-270J-295D01*
G02X1819255Y78390I-1079J1184D01*
G03X1819261Y78912I-300J264D01*
G02X1821568Y81126I1226J1032D01*
G03X1822108I270J295D01*
G02X1824388Y78882I1079J-1184D01*
G03X1824382Y78360I300J-264D01*
G02X1822075Y76146I-1226J-1032D01*
G37*
G36*
G01X1394060Y75160D02*
G03X1393524I-268J-297D01*
G02X1391612Y77211I-940J1040D01*
G03Y77787I-277J288D01*
G02X1393523Y79839I972J1011D01*
G03X1394059Y79840I267J297D01*
G02X1395934Y79846I941J-1040D01*
G03X1396466I266J298D01*
G02X1398371Y77789I934J-1045D01*
G03Y77211I277J-289D01*
G02X1396466Y75154I-971J-1012D01*
G03X1395934I-266J-298D01*
G02X1394060Y75160I-934J1046D01*
G37*
G36*
G01X1581396Y74870D02*
G03X1580818I-289J-277D01*
G02Y76812I-1011J971D01*
G03X1581396I289J277D01*
G02Y74870I1011J-971D01*
G37*
G36*
G01X1571535Y76354D02*
G03X1572104Y76339I292J273D01*
G02X1572052Y74370I972J-1011D01*
G03X1571483Y74385I-292J-273D01*
G02X1571535Y76354I-972J1011D01*
G37*
G36*
G01X732634Y74469D02*
G03X732024Y74447I-296J-270D01*
G02X731960Y76258I-1101J868D01*
G03X732570Y76280I296J270D01*
G02X732634Y74469I1101J-868D01*
G37*
G36*
G01X1622583Y74541D02*
G03X1622036Y74329I-175J-359D01*
G02X1621350Y76106I-1303J518D01*
G03X1621897Y76318I175J359D01*
G02X1622583Y74541I1303J-518D01*
G37*
G36*
G01X1675015Y75899D02*
G03X1675598Y75776I347J200D01*
G02X1675213Y73947I830J-1130D01*
G03X1674630Y74070I-347J-200D01*
G02X1675015Y75899I-830J1130D01*
G37*
G36*
G01X1680934Y75447D02*
G03X1681488Y75412I295J270D01*
G02X1681362Y73397I908J-1068D01*
G03X1680808Y73432I-295J-270D01*
G02X1680934Y75447I-908J1068D01*
G37*
G36*
G01X62027Y72990D02*
G03X61473I-277J-288D01*
G02X59490Y74973I-973J1010D01*
G03Y75527I-288J277D01*
G02Y77473I1010J973D01*
G03Y78027I-288J277D01*
G02Y79973I1010J973D01*
G03Y80527I-288J277D01*
G02X61473Y82510I1010J973D01*
G03X62027I277J288D01*
G02X64010Y80527I973J-1010D01*
G03Y79973I288J-277D01*
G02Y78027I-1010J-973D01*
G03Y77473I288J-277D01*
G02Y75527I-1010J-973D01*
G03Y74973I288J-277D01*
G02X62027Y72990I-1010J-973D01*
G37*
G36*
G01X1454277Y74673D02*
G03X1454869Y74662I301J263D01*
G02X1454833Y72777I1020J-962D01*
G03X1454241Y72788I-301J-263D01*
G02X1454277Y74673I-1020J962D01*
G37*
G36*
G01X1563646Y75326D02*
G03X1563707Y74752I306J-258D01*
G02X1561779Y74547I-857J-1110D01*
G03X1561718Y75121I-306J258D01*
G02X1563646Y75326I857J1110D01*
G37*
G36*
G01X1895824Y72653D02*
G03X1895156Y72632I-327J-230D01*
G02X1893701Y74743I-1195J733D01*
G03X1894010Y75250I-74J393D01*
G02X1896722Y75344I1344J400D01*
G03X1897081Y74858I390J-87D01*
G02X1895824Y72653I-111J-1398D01*
G37*
G36*
G01X76473Y71510D02*
G03X77027I277J288D01*
G02X77776Y71884I972J-1010D01*
G03X78109Y72328I-64J395D01*
G02X79724Y71116I1391J172D01*
G03X79391Y70672I64J-395D01*
G02X77027Y69490I-1391J-172D01*
G03X76473I-277J-288D01*
G02X74527I-973J1010D01*
G03X73973I-277J-288D01*
G02X72027I-973J1010D01*
G03X71473I-277J-288D01*
G02X69527I-973J1010D01*
G03X68973I-277J-288D01*
G02X67027I-973J1010D01*
G03X66473I-277J-288D01*
G02X64527I-973J1010D01*
G03X63973I-277J-288D01*
G02X62027I-973J1010D01*
G03X61473I-277J-288D01*
G02Y71510I-973J1010D01*
G03X62027I277J288D01*
G02X63973I973J-1010D01*
G03X64527I277J288D01*
G02X66473I973J-1010D01*
G03X67027I277J288D01*
G02X68973I973J-1010D01*
G03X69527I277J288D01*
G02X71473I973J-1010D01*
G03X72027I277J288D01*
G02X73973I973J-1010D01*
G03X74527I277J288D01*
G02X76473I973J-1010D01*
G37*
G36*
G01X1825167Y71302D02*
G03X1825191Y70703I276J-289D01*
G02X1823012Y68364I-1011J-1243D01*
G03X1822431Y68366I-291J-274D01*
G02X1820139Y70604I-1161J1104D01*
G03X1820099Y71206I-282J284D01*
G02X1822273Y73537I970J1275D01*
G03X1822871Y73533I301J264D01*
G02X1825167Y71302I1189J-1073D01*
G37*
G36*
G01X1795700Y70821D02*
G03X1796100Y70402I400J-19D01*
G01X1796101D01*
G02X1794500Y68877I-1J-1602D01*
G03X1794100Y69296I-400J19D01*
G01X1794099D01*
G02X1795700Y70821I1J1602D01*
G37*
G36*
G01X1225735Y70178D02*
G03X1225740Y69590I274J-292D01*
G02X1223839Y69571I-940J-1040D01*
G03X1223834Y70159I-274J292D01*
G02X1225735Y70178I940J1040D01*
G37*
G36*
G01X1188924D02*
G03X1188929Y69590I274J-292D01*
G02X1187028Y69571I-940J-1040D01*
G03X1187023Y70159I-274J292D01*
G02X1188924Y70178I940J1040D01*
G37*
G36*
G01X1152113D02*
G03X1152118Y69590I274J-292D01*
G02X1150217Y69571I-940J-1040D01*
G03X1150212Y70159I-274J292D01*
G02X1152113Y70178I940J1040D01*
G37*
G36*
G01X1115301D02*
G03X1115306Y69590I274J-292D01*
G02X1113405Y69571I-940J-1040D01*
G03X1113400Y70159I-274J292D01*
G02X1115301Y70178I940J1040D01*
G37*
G36*
G01X934593D02*
G03X934598Y69590I274J-292D01*
G02X932697Y69571I-940J-1040D01*
G03X932692Y70159I-274J292D01*
G02X934593Y70178I940J1040D01*
G37*
G36*
G01X897782D02*
G03X897787Y69590I274J-292D01*
G02X895886Y69571I-940J-1040D01*
G03X895881Y70159I-274J292D01*
G02X897782Y70178I940J1040D01*
G37*
G36*
G01X860971D02*
G03X860976Y69590I274J-292D01*
G02X859075Y69571I-940J-1040D01*
G03X859070Y70159I-274J292D01*
G02X860971Y70178I940J1040D01*
G37*
G36*
G01X824160D02*
G03X824165Y69590I274J-292D01*
G02X822264Y69571I-940J-1040D01*
G03X822259Y70159I-274J292D01*
G02X824160Y70178I940J1040D01*
G37*
G36*
G01X787349D02*
G03X787354Y69590I274J-292D01*
G02X785453Y69571I-940J-1040D01*
G03X785448Y70159I-274J292D01*
G02X787349Y70178I940J1040D01*
G37*
G36*
G01X576127D02*
G03X576132Y69590I274J-292D01*
G02X574231Y69571I-940J-1040D01*
G03X574226Y70159I-274J292D01*
G02X576127Y70178I940J1040D01*
G37*
G36*
G01X539316D02*
G03X539321Y69590I274J-292D01*
G02X537420Y69571I-940J-1040D01*
G03X537415Y70159I-274J292D01*
G02X539316Y70178I940J1040D01*
G37*
G36*
G01X502505D02*
G03X502510Y69590I274J-292D01*
G02X500609Y69571I-940J-1040D01*
G03X500604Y70159I-274J292D01*
G02X502505Y70178I940J1040D01*
G37*
G36*
G01X465693D02*
G03X465698Y69590I274J-292D01*
G02X463797Y69571I-940J-1040D01*
G03X463792Y70159I-274J292D01*
G02X465693Y70178I940J1040D01*
G37*
G36*
G01X284985D02*
G03X284990Y69590I274J-292D01*
G02X283089Y69571I-940J-1040D01*
G03X283084Y70159I-274J292D01*
G02X284985Y70178I940J1040D01*
G37*
G36*
G01X248174D02*
G03X248179Y69590I274J-292D01*
G02X246278Y69571I-940J-1040D01*
G03X246273Y70159I-274J292D01*
G02X248174Y70178I940J1040D01*
G37*
G36*
G01X211363D02*
G03X211368Y69590I274J-292D01*
G02X209467Y69571I-940J-1040D01*
G03X209462Y70159I-274J292D01*
G02X211363Y70178I940J1040D01*
G37*
G36*
G01X174552D02*
G03X174557Y69590I274J-292D01*
G02X172656Y69571I-940J-1040D01*
G03X172651Y70159I-274J292D01*
G02X174552Y70178I940J1040D01*
G37*
G36*
G01X137741D02*
G03X137746Y69590I274J-292D01*
G02X135845Y69571I-940J-1040D01*
G03X135840Y70159I-274J292D01*
G02X137741Y70178I940J1040D01*
G37*
G36*
G01X1230841Y69934D02*
G03Y69355I276J-289D01*
G02X1228907I-967J-1015D01*
G03Y69934I-276J290D01*
G02X1230841I967J1015D01*
G37*
G36*
G01X1194030D02*
G03Y69355I276J-289D01*
G02X1192096I-967J-1015D01*
G03Y69934I-276J290D01*
G02X1194030I967J1015D01*
G37*
G36*
G01X1157219D02*
G03Y69355I276J-289D01*
G02X1155285I-967J-1015D01*
G03Y69934I-276J290D01*
G02X1157219I967J1015D01*
G37*
G36*
G01X1120407D02*
G03Y69355I276J-289D01*
G02X1118473I-967J-1015D01*
G03Y69934I-276J290D01*
G02X1120407I967J1015D01*
G37*
G36*
G01X939699D02*
G03Y69355I276J-289D01*
G02X937765I-967J-1015D01*
G03Y69934I-276J290D01*
G02X939699I967J1015D01*
G37*
G36*
G01X902888D02*
G03Y69355I276J-289D01*
G02X900954I-967J-1015D01*
G03Y69934I-276J290D01*
G02X902888I967J1015D01*
G37*
G36*
G01X866077D02*
G03Y69355I276J-289D01*
G02X864143I-967J-1015D01*
G03Y69934I-276J290D01*
G02X866077I967J1015D01*
G37*
G36*
G01X829266D02*
G03Y69355I276J-289D01*
G02X827332I-967J-1015D01*
G03Y69934I-276J290D01*
G02X829266I967J1015D01*
G37*
G36*
G01X792455D02*
G03Y69355I276J-289D01*
G02X790521I-967J-1015D01*
G03Y69934I-276J290D01*
G02X792455I967J1015D01*
G37*
G36*
G01X581233D02*
G03Y69355I276J-289D01*
G02X579299I-967J-1015D01*
G03Y69934I-276J290D01*
G02X581233I967J1015D01*
G37*
G36*
G01X544422D02*
G03Y69355I276J-289D01*
G02X542488I-967J-1015D01*
G03Y69934I-276J290D01*
G02X544422I967J1015D01*
G37*
G36*
G01X507611D02*
G03Y69355I276J-289D01*
G02X505677I-967J-1015D01*
G03Y69934I-276J290D01*
G02X507611I967J1015D01*
G37*
G36*
G01X470799D02*
G03Y69355I276J-289D01*
G02X468865I-967J-1015D01*
G03Y69934I-276J290D01*
G02X470799I967J1015D01*
G37*
G36*
G01X290091D02*
G03Y69355I276J-289D01*
G02X288157I-967J-1015D01*
G03Y69934I-276J290D01*
G02X290091I967J1015D01*
G37*
G36*
G01X253280D02*
G03Y69355I276J-289D01*
G02X251346I-967J-1015D01*
G03Y69934I-276J290D01*
G02X253280I967J1015D01*
G37*
G36*
G01X216469D02*
G03Y69355I276J-289D01*
G02X214535I-967J-1015D01*
G03Y69934I-276J290D01*
G02X216469I967J1015D01*
G37*
G36*
G01X179658D02*
G03Y69355I276J-289D01*
G02X177724I-967J-1015D01*
G03Y69934I-276J290D01*
G02X179658I967J1015D01*
G37*
G36*
G01X142847D02*
G03Y69355I276J-289D01*
G02X140913I-967J-1015D01*
G03Y69934I-276J290D01*
G02X142847I967J1015D01*
G37*
G36*
G01X1845615Y66161D02*
G03X1845085I-265J-300D01*
G02X1842527Y67931I-1060J1201D01*
G03X1842226Y68466I-374J142D01*
G02X1841455Y68841I290J1576D01*
G03X1840925I-265J-300D01*
G02X1838834Y68816I-1060J1201D01*
G03X1838293Y68793I-258J-306D01*
G02X1835740Y69186I-1132J1133D01*
G03X1835120Y69301I-355J-185D01*
G02X1832973Y69324I-1061J1200D01*
G03X1832454Y69343I-271J-295D01*
G02X1830277Y71680I-994J1256D01*
G03Y72220I-295J270D01*
G02X1832643I1183J1080D01*
G03Y71680I295J-270D01*
G02X1832657Y71664I-1198J-1063D01*
G03X1832946Y71653I150J133D01*
G02X1835579Y71007I1113J-1152D01*
G03X1835923Y70943I190J63D01*
G02X1835930Y70951I1209J-1051D01*
G03X1835924Y71471I-307J256D01*
G02X1835592Y72979I1205J1056D01*
G03X1835310Y73479I-384J113D01*
G02X1835250Y76562I404J1550D01*
G03X1835522Y77042I-116J383D01*
G02X1838205Y78566I1555J387D01*
G03X1838786Y78585I282J284D01*
G02X1841073Y78698I1199J-1063D01*
G03X1841632Y78713I272J293D01*
G02X1844328Y77177I1151J-1114D01*
G03X1844581Y76695I386J-105D01*
G02X1845132Y76364I-533J-1511D01*
G03X1845655Y76348I271J294D01*
G02X1847024Y73544I1012J-1242D01*
G03X1846724Y73062I89J-390D01*
G02X1846366Y71632I-1559J-370D01*
G03Y71102I300J-265D01*
G02X1846663Y69473I-1201J-1061D01*
G03X1846964Y68938I374J-142D01*
G02X1847735Y68563I-290J-1576D01*
G03X1848265I265J300D01*
G02Y66161I1060J-1201D01*
G03X1847735I-265J-300D01*
G02X1845615I-1060J1201D01*
G37*
G36*
G01X1733Y66210D02*
G03X1351Y66698I-390J88D01*
G02X2749Y67790I31J1402D01*
G03X3131Y67302I390J-88D01*
G02X1733Y66210I-31J-1402D01*
G37*
G36*
G01X1045980Y103625D02*
X1050117Y107765D01*
G02X1050707Y108010I556J-506D01*
G01X1078615D01*
X1098290Y88352D01*
G02X1098510Y87821I-531J-531D01*
G01Y86675D01*
X1098649Y86630D01*
G02Y83962I-431J-1334D01*
G01X1098510Y83917D01*
Y74965D01*
X1098647Y74920D01*
G02X1099159Y72559I-440J-1331D01*
G03X1099170Y71962I271J-294D01*
G02X1099129Y69797I-911J-1066D01*
G03X1099124Y69174I249J-314D01*
G02X1098651Y66751I-889J-1084D01*
G01X1098510Y66707D01*
Y66375D01*
X1096348Y64210D01*
G02X1095817Y63990I-531J531D01*
G01X1048665D01*
X1048155Y64499D01*
X1048041Y64464D01*
G02X1046337Y66331I-404J1343D01*
G02X1046200Y66763I613J432D01*
G01Y71329D01*
X1045680Y71850D01*
G02X1045460Y72380I530J531D01*
G01Y74389D01*
X1044190Y75660D01*
G02X1043970Y76190I530J531D01*
G01Y86020D01*
X1043835Y86066D01*
G02Y88718I455J1326D01*
G01X1043970Y88764D01*
Y91621D01*
X1045980Y93631D01*
Y103625D01*
G37*
G36*
G01X1328429Y66950D02*
G03Y66350I265J-300D01*
G02X1326571I-929J-1050D01*
G03Y66950I-265J300D01*
G02X1326598Y69073I929J1050D01*
G03X1326591Y69692I-257J307D01*
G02X1328369Y69713I876J1094D01*
G03X1328376Y69094I257J-307D01*
G02X1328429Y66950I-876J-1094D01*
G37*
G36*
G01X1649871Y64260D02*
G03X1649293Y64256I-287J-279D01*
G02X1649281Y66198I-1017J965D01*
G03X1649859Y66202I287J279D01*
G02X1649871Y64260I1017J-965D01*
G37*
G36*
G01X734722Y65252D02*
G03X734742Y64719I308J-255D01*
G02X732775Y62723I-1010J-972D01*
G03X732242Y62735I-273J-292D01*
G02X730252Y64695I-910J1067D01*
G03X730232Y65228I-308J255D01*
G02X730180Y67115I1010J972D01*
G03X730171Y67648I-303J261D01*
G02X732157Y69624I1029J952D01*
G03X732690Y69612I273J292D01*
G02X734662Y67631I909J-1067D01*
G03X734671Y67098I303J-261D01*
G02X734722Y65252I-1029J-952D01*
G37*
G36*
G01X391405Y65711D02*
G02X384586Y67328I-3218J1617D01*
G01Y72228D01*
G02X389450Y75601I3602J0D01*
G03X389990Y75975I140J375D01*
G01Y82481D01*
G03X389450Y82855I-400J-1D01*
G02X384586Y86228I-1262J3373D01*
G01Y91128D01*
G02X389450Y94501I3602J0D01*
G03X389990Y94875I140J375D01*
G01Y99141D01*
X399640Y108790D01*
G02X400170Y109010I531J-530D01*
G01X430121D01*
X448003Y91128D01*
X448128Y91183D01*
G02X449500Y88754I564J-1284D01*
G01Y86379D01*
G02Y84213I-890J-1083D01*
G01Y74663D01*
G02Y72515I-901J-1074D01*
G01Y72012D01*
G02Y69780I-849J-1116D01*
G01Y69187D01*
G02Y66993I-873J-1097D01*
G01Y65379D01*
X446340Y62220D01*
G02X445810Y62000I-531J530D01*
G01X396170D01*
G02X395640Y62220I1J750D01*
G01X392045Y65815D01*
G03X391405Y65711I-282J-283D01*
G37*
G36*
G01X1785725Y65065D02*
G03X1786169Y64732I395J64D01*
G02X1784957Y63117I172J-1391D01*
G03X1784513Y63450I-395J-64D01*
G02X1785725Y65065I-172J1391D01*
G37*
G36*
G01X1610284Y62579D02*
G03X1609752Y62364I-162J-365D01*
G02X1607065Y63094I-1300J526D01*
G03X1606698Y63551I-396J58D01*
G02X1608184Y64745I99J1398D01*
G03X1608551Y64288I396J-58D01*
G02X1609021Y64172I-96J-1399D01*
G03X1609553Y64387I162J365D01*
G02X1610284Y62579I1300J-526D01*
G37*
G36*
G01X1734177Y57140D02*
G03X1733623I-277J-288D01*
G02X1731640Y59123I-973J1010D01*
G03Y59677I-288J277D01*
G02X1733660I1010J973D01*
G03Y59123I288J-277D01*
G02X1733744Y59027I-1012J-970D01*
G03X1734056I156J125D01*
G02X1734177Y57140I1094J-877D01*
G37*
G36*
G01X15614Y55240D02*
G03X15036I-289J-277D01*
G02Y57182I-1011J971D01*
G03X15614I289J277D01*
G02Y55240I1011J-971D01*
G37*
G36*
G01X60527Y54990D02*
G03X59973I-277J-288D01*
G02X57990Y56973I-973J1010D01*
G03Y57527I-288J277D01*
G02Y59473I1010J973D01*
G03Y60027I-288J277D01*
G02X59973Y62010I1010J973D01*
G03X60527I277J288D01*
G02X62510Y60027I973J-1010D01*
G03Y59473I288J-277D01*
G02Y57527I-1010J-973D01*
G03Y56973I288J-277D01*
G02X60527Y54990I-1010J-973D01*
G37*
G36*
G01X1009815Y53871D02*
G03X1009237I-289J-277D01*
G02Y55813I-1011J971D01*
G03X1009815I289J277D01*
G02Y53871I1011J-971D01*
G37*
G36*
G01X360207D02*
G03X359629I-289J-277D01*
G02Y55813I-1011J971D01*
G03X360207I289J277D01*
G02Y53871I1011J-971D01*
G37*
G36*
G01X1816718Y55668D02*
G03X1817330Y55663I308J255D01*
G02X1817315Y53859I1066J-911D01*
G03X1816703Y53864I-308J-255D01*
G02X1816718Y55668I-1066J911D01*
G37*
G36*
G01X1825893Y54749D02*
G03X1826068Y54496I193J-54D01*
G02X1824348Y53154I-138J-1596D01*
G03X1824033Y53610I-395J64D01*
G02X1823249Y56344I317J1570D01*
G03X1823261Y56913I-275J290D01*
G02X1823034Y58850I1149J1116D01*
G03X1822918Y59383I-344J204D01*
G02X1825206Y59880I912J1317D01*
G03X1825322Y59347I344J-204D01*
G02X1825980Y58351I-912J-1318D01*
G03X1826477Y58045I392J80D01*
G02X1826212Y55053I423J-1545D01*
G03X1825929Y54907I-86J-180D01*
G02X1825893Y54749I-1578J276D01*
G37*
G36*
G01X1668527Y50490D02*
G03X1667973I-277J-288D01*
G02Y52510I-973J1010D01*
G03X1668527I277J288D01*
G02Y50490I973J-1010D01*
G37*
G36*
G01X1230845Y51303D02*
G03Y50725I277J-289D01*
G02X1228903I-971J-1011D01*
G03Y51303I-277J289D01*
G02X1230845I971J1011D01*
G37*
G36*
G01X1194034D02*
G03Y50725I277J-289D01*
G02X1192092I-971J-1011D01*
G03Y51303I-277J289D01*
G02X1194034I971J1011D01*
G37*
G36*
G01X1157222D02*
G03Y50725I277J-289D01*
G02X1155280I-971J-1011D01*
G03Y51303I-277J289D01*
G02X1157222I971J1011D01*
G37*
G36*
G01X1120411D02*
G03Y50725I277J-289D01*
G02X1118469I-971J-1011D01*
G03Y51303I-277J289D01*
G02X1120411I971J1011D01*
G37*
G36*
G01X939703D02*
G03Y50725I277J-289D01*
G02X937761I-971J-1011D01*
G03Y51303I-277J289D01*
G02X939703I971J1011D01*
G37*
G36*
G01X902892D02*
G03Y50725I277J-289D01*
G02X900950I-971J-1011D01*
G03Y51303I-277J289D01*
G02X902892I971J1011D01*
G37*
G36*
G01X866081D02*
G03Y50725I277J-289D01*
G02X864139I-971J-1011D01*
G03Y51303I-277J289D01*
G02X866081I971J1011D01*
G37*
G36*
G01X829270D02*
G03Y50725I277J-289D01*
G02X827328I-971J-1011D01*
G03Y51303I-277J289D01*
G02X829270I971J1011D01*
G37*
G36*
G01X792459D02*
G03Y50725I277J-289D01*
G02X790517I-971J-1011D01*
G03Y51303I-277J289D01*
G02X792459I971J1011D01*
G37*
G36*
G01X581237D02*
G03Y50725I277J-289D01*
G02X579295I-971J-1011D01*
G03Y51303I-277J289D01*
G02X581237I971J1011D01*
G37*
G36*
G01X544426D02*
G03Y50725I277J-289D01*
G02X542484I-971J-1011D01*
G03Y51303I-277J289D01*
G02X544426I971J1011D01*
G37*
G36*
G01X507614D02*
G03Y50725I277J-289D01*
G02X505672I-971J-1011D01*
G03Y51303I-277J289D01*
G02X507614I971J1011D01*
G37*
G36*
G01X470803D02*
G03Y50725I277J-289D01*
G02X468861I-971J-1011D01*
G03Y51303I-277J289D01*
G02X470803I971J1011D01*
G37*
G36*
G01X290095D02*
G03Y50725I277J-289D01*
G02X288153I-971J-1011D01*
G03Y51303I-277J289D01*
G02X290095I971J1011D01*
G37*
G36*
G01X253284D02*
G03Y50725I277J-289D01*
G02X251342I-971J-1011D01*
G03Y51303I-277J289D01*
G02X253284I971J1011D01*
G37*
G36*
G01X216473D02*
G03Y50725I277J-289D01*
G02X214531I-971J-1011D01*
G03Y51303I-277J289D01*
G02X216473I971J1011D01*
G37*
G36*
G01X179662D02*
G03Y50725I277J-289D01*
G02X177720I-971J-1011D01*
G03Y51303I-277J289D01*
G02X179662I971J1011D01*
G37*
G36*
G01X142851D02*
G03Y50725I277J-289D01*
G02X140909I-971J-1011D01*
G03Y51303I-277J289D01*
G02X142851I971J1011D01*
G37*
G36*
G01X1225745Y51089D02*
G03Y50511I277J-289D01*
G02X1223803I-971J-1011D01*
G03Y51089I-277J289D01*
G02X1225745I971J1011D01*
G37*
G36*
G01X1188934D02*
G03Y50511I277J-289D01*
G02X1186992I-971J-1011D01*
G03Y51089I-277J289D01*
G02X1188934I971J1011D01*
G37*
G36*
G01X1152122D02*
G03Y50511I277J-289D01*
G02X1150180I-971J-1011D01*
G03Y51089I-277J289D01*
G02X1152122I971J1011D01*
G37*
G36*
G01X1115311D02*
G03Y50511I277J-289D01*
G02X1113369I-971J-1011D01*
G03Y51089I-277J289D01*
G02X1115311I971J1011D01*
G37*
G36*
G01X934603D02*
G03Y50511I277J-289D01*
G02X932661I-971J-1011D01*
G03Y51089I-277J289D01*
G02X934603I971J1011D01*
G37*
G36*
G01X897792D02*
G03Y50511I277J-289D01*
G02X895850I-971J-1011D01*
G03Y51089I-277J289D01*
G02X897792I971J1011D01*
G37*
G36*
G01X860981D02*
G03Y50511I277J-289D01*
G02X859039I-971J-1011D01*
G03Y51089I-277J289D01*
G02X860981I971J1011D01*
G37*
G36*
G01X824170D02*
G03Y50511I277J-289D01*
G02X822228I-971J-1011D01*
G03Y51089I-277J289D01*
G02X824170I971J1011D01*
G37*
G36*
G01X787359D02*
G03Y50511I277J-289D01*
G02X785417I-971J-1011D01*
G03Y51089I-277J289D01*
G02X787359I971J1011D01*
G37*
G36*
G01X576137D02*
G03Y50511I277J-289D01*
G02X574195I-971J-1011D01*
G03Y51089I-277J289D01*
G02X576137I971J1011D01*
G37*
G36*
G01X539326D02*
G03Y50511I277J-289D01*
G02X537384I-971J-1011D01*
G03Y51089I-277J289D01*
G02X539326I971J1011D01*
G37*
G36*
G01X502514D02*
G03Y50511I277J-289D01*
G02X500572I-971J-1011D01*
G03Y51089I-277J289D01*
G02X502514I971J1011D01*
G37*
G36*
G01X465703D02*
G03Y50511I277J-289D01*
G02X463761I-971J-1011D01*
G03Y51089I-277J289D01*
G02X465703I971J1011D01*
G37*
G36*
G01X284995D02*
G03Y50511I277J-289D01*
G02X283053I-971J-1011D01*
G03Y51089I-277J289D01*
G02X284995I971J1011D01*
G37*
G36*
G01X248184D02*
G03Y50511I277J-289D01*
G02X246242I-971J-1011D01*
G03Y51089I-277J289D01*
G02X248184I971J1011D01*
G37*
G36*
G01X211373D02*
G03Y50511I277J-289D01*
G02X209431I-971J-1011D01*
G03Y51089I-277J289D01*
G02X211373I971J1011D01*
G37*
G36*
G01X174562D02*
G03Y50511I277J-289D01*
G02X172620I-971J-1011D01*
G03Y51089I-277J289D01*
G02X174562I971J1011D01*
G37*
G36*
G01X137751D02*
G03Y50511I277J-289D01*
G02X135809I-971J-1011D01*
G03Y51089I-277J289D01*
G02X137751I971J1011D01*
G37*
G36*
G01X1744121Y46096D02*
G03X1743567I-277J-288D01*
G02Y48116I-973J1010D01*
G03X1744121I277J288D01*
G02Y46096I973J-1010D01*
G37*
G36*
G01X1012804Y46006D02*
G03X1012195I-305J-258D01*
G02Y47822I-1069J908D01*
G03X1012804I304J258D01*
G02Y46006I1069J-908D01*
G37*
G36*
G01X363196D02*
G03X362587I-305J-258D01*
G02Y47822I-1069J908D01*
G03X363196I305J258D01*
G02Y46006I1069J-908D01*
G37*
G36*
G01X1363531Y44948D02*
G03X1363481Y44361I244J-316D01*
G02X1361591Y44523I-1033J-948D01*
G03X1361641Y45110I-244J316D01*
G02X1363531Y44948I1033J948D01*
G37*
G36*
G01X1309627Y40490D02*
G03X1309073I-277J-288D01*
G02Y42510I-973J1010D01*
G03X1309627I277J288D01*
G02Y40490I973J-1010D01*
G37*
G36*
G01X1324989Y40468D02*
G03X1324411I-289J-277D01*
G02X1322354Y42373I-1012J971D01*
G03Y42905I-298J266D01*
G02X1324392Y44829I1047J933D01*
G03X1324982Y44855I283J283D01*
G02X1327038Y42954I1076J-898D01*
G03X1327025Y42395I280J-286D01*
G02X1324989Y40468I-1025J-956D01*
G37*
G36*
G01X1721758Y38368D02*
X1717958D01*
G02Y41392I0J1512D01*
G01X1721759D01*
G02X1723270Y39890I-1J-1512D01*
G01Y39795D01*
X1723260Y39711D01*
G02X1721758Y38368I-1502J169D01*
G37*
G36*
G01X1703073Y38168D02*
X1699273D01*
G02Y41190I0J1511D01*
G01X1703074D01*
G02X1704584Y39689I-1J-1511D01*
G01Y39594D01*
X1704575Y39510D01*
G02X1703073Y38168I-1502J169D01*
G37*
G36*
G01X1740556Y37975D02*
Y37965D01*
X1736654Y38080D01*
X1736483Y38104D01*
G02X1736742Y41111I217J1496D01*
G01Y41121D01*
X1740642Y41006D01*
X1740650Y40998D01*
X1740723Y40992D01*
G02X1742110Y39496I-125J-1506D01*
G01Y39401D01*
X1742100Y39317D01*
G02X1740556Y37975I-1502J169D01*
G37*
G36*
G01X1731183Y37954D02*
X1727383D01*
G02Y40976I0J1511D01*
G01X1731183D01*
G02X1732694Y39475I0J-1511D01*
G01Y39380D01*
X1732685Y39296D01*
G02X1731183Y37954I-1502J169D01*
G37*
G36*
G01X1694098Y37950D02*
X1689098D01*
G02Y40974I0J1512D01*
G01X1694098D01*
G02X1695610Y39472I0J-1512D01*
G01Y39377D01*
X1695600Y39293D01*
G02X1694098Y37950I-1502J169D01*
G37*
G36*
G01X1684648D02*
X1679648D01*
G02Y40974I0J1512D01*
G01X1684649D01*
G02X1686160Y39472I-1J-1512D01*
G01Y39377D01*
X1686150Y39293D01*
G02X1684648Y37950I-1502J169D01*
G37*
G36*
G01X1675198D02*
X1670198D01*
G02Y40974I0J1512D01*
G01X1675199D01*
G02X1676710Y39472I-1J-1512D01*
G01Y39377D01*
X1676700Y39293D01*
G02X1675198Y37950I-1502J169D01*
G37*
G36*
G01X1646848D02*
X1641848D01*
G02Y40974I0J1512D01*
G01X1646849D01*
G02X1648360Y39472I-1J-1512D01*
G01Y39377D01*
X1648350Y39293D01*
G02X1646848Y37950I-1502J169D01*
G37*
G36*
G01X1712308Y37838D02*
X1708508D01*
G02Y40862I0J1512D01*
G01X1712309D01*
G02X1713820Y39360I-1J-1512D01*
G01Y39265D01*
X1713810Y39181D01*
G02X1712308Y37838I-1502J168D01*
G37*
G36*
G01X1368689Y36829D02*
G03X1368111I-289J-277D01*
G02Y38771I-1011J971D01*
G03X1368689I289J277D01*
G02Y36829I1011J-971D01*
G37*
G36*
G01X1660748Y40974D02*
X1665749D01*
G02X1667260Y39472I-1J-1512D01*
G01Y39377D01*
X1667250Y39293D01*
G02X1665748Y37950I-1502J169D01*
G01X1662563D01*
G03X1662204Y37375I1J-400D01*
G02X1659887Y37682I-1260J-614D01*
G03X1659829Y38262I-302J263D01*
G02X1660748Y40974I919J1200D01*
G37*
G36*
G01X1651297D02*
X1656299D01*
G02X1657810Y39472I-1J-1512D01*
G01Y39377D01*
X1657800Y39293D01*
G02X1656298Y37950I-1502J169D01*
G01X1652864D01*
G03X1652506Y37373I0J-400D01*
G02X1650282Y37764I-1256J-623D01*
G03X1650276Y38348I-276J289D01*
G02X1651297Y40974I1022J1114D01*
G37*
G36*
G01X1009811Y34975D02*
G03X1009232I-290J-276D01*
G02Y36909I-1015J967D01*
G03X1009811I290J276D01*
G02Y34975I1015J-967D01*
G37*
G36*
G01X359663Y36966D02*
G03X360240Y36947I298J267D01*
G02X360174Y35007I978J-1004D01*
G03X359597Y35026I-298J-267D01*
G02X359663Y36966I-978J1004D01*
G37*
G36*
G01X1847503Y35441D02*
G03X1848058Y35439I279J287D01*
G02X1848051Y33420I969J-1013D01*
G03X1847496Y33422I-279J-287D01*
G02X1847503Y35441I-969J1013D01*
G37*
G36*
G01X655725Y30405D02*
G03X655151Y30327I-250J-312D01*
G02X652986Y30199I-1135J823D01*
G03X652415Y30215I-293J-272D01*
G02X650428Y30257I-973J1010D01*
G03X649856Y30264I-289J-276D01*
G02X649881Y32226I-989J994D01*
G03X650453Y32219I289J276D01*
G02X652472Y32176I989J-994D01*
G03X653043Y32160I293J272D01*
G02X654891Y32245I972J-1010D01*
G03X655465Y32323I250J312D01*
G02X655725Y30405I1135J-823D01*
G37*
G36*
G01X1225735Y32378D02*
G03X1225740Y31790I274J-292D01*
G02X1223839Y31771I-940J-1040D01*
G03X1223834Y32359I-274J292D01*
G02X1225735Y32378I940J1040D01*
G37*
G36*
G01X1188924D02*
G03X1188929Y31790I274J-292D01*
G02X1187028Y31771I-940J-1040D01*
G03X1187023Y32359I-274J292D01*
G02X1188924Y32378I940J1040D01*
G37*
G36*
G01X1152112D02*
G03X1152117Y31790I274J-292D01*
G02X1150216Y31771I-940J-1040D01*
G03X1150211Y32359I-274J292D01*
G02X1152112Y32378I940J1040D01*
G37*
G36*
G01X1115301D02*
G03X1115306Y31790I274J-292D01*
G02X1113405Y31771I-940J-1040D01*
G03X1113400Y32359I-274J292D01*
G02X1115301Y32378I940J1040D01*
G37*
G36*
G01X934593D02*
G03X934598Y31790I274J-292D01*
G02X932697Y31771I-940J-1040D01*
G03X932692Y32359I-274J292D01*
G02X934593Y32378I940J1040D01*
G37*
G36*
G01X897782D02*
G03X897787Y31790I274J-292D01*
G02X895886Y31771I-940J-1040D01*
G03X895881Y32359I-274J292D01*
G02X897782Y32378I940J1040D01*
G37*
G36*
G01X860971D02*
G03X860976Y31790I274J-292D01*
G02X859075Y31771I-940J-1040D01*
G03X859070Y32359I-274J292D01*
G02X860971Y32378I940J1040D01*
G37*
G36*
G01X824160D02*
G03X824165Y31790I274J-292D01*
G02X822264Y31771I-940J-1040D01*
G03X822259Y32359I-274J292D01*
G02X824160Y32378I940J1040D01*
G37*
G36*
G01X787349D02*
G03X787354Y31790I274J-292D01*
G02X785453Y31771I-940J-1040D01*
G03X785448Y32359I-274J292D01*
G02X787349Y32378I940J1040D01*
G37*
G36*
G01X576127D02*
G03X576132Y31790I274J-292D01*
G02X574231Y31771I-940J-1040D01*
G03X574226Y32359I-274J292D01*
G02X576127Y32378I940J1040D01*
G37*
G36*
G01X539316D02*
G03X539321Y31790I274J-292D01*
G02X537420Y31771I-940J-1040D01*
G03X537415Y32359I-274J292D01*
G02X539316Y32378I940J1040D01*
G37*
G36*
G01X502504D02*
G03X502509Y31790I274J-292D01*
G02X500608Y31771I-940J-1040D01*
G03X500603Y32359I-274J292D01*
G02X502504Y32378I940J1040D01*
G37*
G36*
G01X465693D02*
G03X465698Y31790I274J-292D01*
G02X463797Y31771I-940J-1040D01*
G03X463792Y32359I-274J292D01*
G02X465693Y32378I940J1040D01*
G37*
G36*
G01X284985D02*
G03X284990Y31790I274J-292D01*
G02X283089Y31771I-940J-1040D01*
G03X283084Y32359I-274J292D01*
G02X284985Y32378I940J1040D01*
G37*
G36*
G01X248174D02*
G03X248179Y31790I274J-292D01*
G02X246278Y31771I-940J-1040D01*
G03X246273Y32359I-274J292D01*
G02X248174Y32378I940J1040D01*
G37*
G36*
G01X211363D02*
G03X211368Y31790I274J-292D01*
G02X209467Y31771I-940J-1040D01*
G03X209462Y32359I-274J292D01*
G02X211363Y32378I940J1040D01*
G37*
G36*
G01X174552D02*
G03X174557Y31790I274J-292D01*
G02X172656Y31771I-940J-1040D01*
G03X172651Y32359I-274J292D01*
G02X174552Y32378I940J1040D01*
G37*
G36*
G01X137741D02*
G03X137746Y31790I274J-292D01*
G02X135845Y31771I-940J-1040D01*
G03X135840Y32359I-274J292D01*
G02X137741Y32378I940J1040D01*
G37*
G36*
G01X1311586Y30712D02*
G03X1311131Y30400I-64J-395D01*
G02X1309983Y32075I-1371J291D01*
G03X1310438Y32387I64J395D01*
G02X1313179Y32393I1371J-292D01*
G03X1313653Y32086I391J84D01*
G02X1314428Y32029I289J-1372D01*
G03X1314952Y32295I139J375D01*
G02X1317220Y32969I1348J-384D01*
G03X1317752Y32976I262J302D01*
G02X1319816Y32791I948J-1033D01*
G03X1320427Y32760I319J242D01*
G02X1320336Y30955I1025J-956D01*
G03X1319725Y30986I-319J-242D01*
G02X1317780Y30885I-1025J957D01*
G03X1317248Y30878I-262J-302D01*
G02X1315814Y30596I-948J1033D01*
G03X1315290Y30330I-139J-375D01*
G02X1312572Y30417I-1348J384D01*
G03X1312098Y30724I-391J-84D01*
G02X1311586Y30712I-288J1372D01*
G37*
G36*
G01X1230841Y32134D02*
G03Y31555I276J-289D01*
G02X1228907I-967J-1015D01*
G03Y32134I-276J289D01*
G02X1230841I967J1015D01*
G37*
G36*
G01X1194030D02*
G03Y31555I276J-289D01*
G02X1192096I-967J-1015D01*
G03Y32134I-276J289D01*
G02X1194030I967J1015D01*
G37*
G36*
G01X1157218D02*
G03Y31555I276J-289D01*
G02X1155284I-967J-1015D01*
G03Y32134I-276J289D01*
G02X1157218I967J1015D01*
G37*
G36*
G01X1120407D02*
G03Y31555I276J-289D01*
G02X1118473I-967J-1015D01*
G03Y32134I-276J289D01*
G02X1120407I967J1015D01*
G37*
G36*
G01X939699D02*
G03Y31555I276J-289D01*
G02X937765I-967J-1015D01*
G03Y32134I-276J289D01*
G02X939699I967J1015D01*
G37*
G36*
G01X902888D02*
G03Y31555I276J-289D01*
G02X900954I-967J-1015D01*
G03Y32134I-276J289D01*
G02X902888I967J1015D01*
G37*
G36*
G01X866077D02*
G03Y31555I276J-289D01*
G02X864143I-967J-1015D01*
G03Y32134I-276J289D01*
G02X866077I967J1015D01*
G37*
G36*
G01X829266D02*
G03Y31555I276J-289D01*
G02X827332I-967J-1015D01*
G03Y32134I-276J289D01*
G02X829266I967J1015D01*
G37*
G36*
G01X792455D02*
G03Y31555I276J-289D01*
G02X790521I-967J-1015D01*
G03Y32134I-276J289D01*
G02X792455I967J1015D01*
G37*
G36*
G01X581233D02*
G03Y31555I276J-289D01*
G02X579299I-967J-1015D01*
G03Y32134I-276J289D01*
G02X581233I967J1015D01*
G37*
G36*
G01X544422D02*
G03Y31555I276J-289D01*
G02X542488I-967J-1015D01*
G03Y32134I-276J289D01*
G02X544422I967J1015D01*
G37*
G36*
G01X507610D02*
G03Y31555I276J-289D01*
G02X505676I-967J-1015D01*
G03Y32134I-276J289D01*
G02X507610I967J1015D01*
G37*
G36*
G01X470799D02*
G03Y31555I276J-289D01*
G02X468865I-967J-1015D01*
G03Y32134I-276J289D01*
G02X470799I967J1015D01*
G37*
G36*
G01X290091D02*
G03Y31555I276J-289D01*
G02X288157I-967J-1015D01*
G03Y32134I-276J289D01*
G02X290091I967J1015D01*
G37*
G36*
G01X253280D02*
G03Y31555I276J-289D01*
G02X251346I-967J-1015D01*
G03Y32134I-276J289D01*
G02X253280I967J1015D01*
G37*
G36*
G01X216469D02*
G03Y31555I276J-289D01*
G02X214535I-967J-1015D01*
G03Y32134I-276J289D01*
G02X216469I967J1015D01*
G37*
G36*
G01X179658D02*
G03Y31555I276J-289D01*
G02X177724I-967J-1015D01*
G03Y32134I-276J289D01*
G02X179658I967J1015D01*
G37*
G36*
G01X142847D02*
G03Y31555I276J-289D01*
G02X140913I-967J-1015D01*
G03Y32134I-276J289D01*
G02X142847I967J1015D01*
G37*
G36*
G01X1758406Y34262D02*
Y30367D01*
X1758397Y30283D01*
G02X1755384Y30452I-1502J169D01*
G01Y34252D01*
G02X1758406Y34262I1511J0D01*
G37*
G36*
G01X683076Y27208D02*
G03X682476I-300J-265D01*
G02Y29066I-1050J929D01*
G03X683076I300J265D01*
G02Y27208I1050J-929D01*
G37*
G36*
G01X1523780Y27567D02*
G03X1523280Y27252I-106J-386D01*
G02X1522274Y28851I-1380J248D01*
G03X1522774Y29166I106J386D01*
G02X1523780Y27567I1380J-248D01*
G37*
G36*
G01X1509078Y30563D02*
G03X1508559Y30154I-120J-381D01*
G02X1507596Y32459I-3893J-273D01*
G03X1508253Y32540I301J264D01*
G02X1509078Y30563I1247J-640D01*
G37*
G36*
G01X1808288Y27703D02*
G03X1808887Y27629I332J224D01*
G02X1808661Y25800I935J-1044D01*
G03X1808062Y25874I-332J-224D01*
G02X1808288Y27703I-935J1044D01*
G37*
G36*
G01X1380536Y27426D02*
G03X1381078Y27181I381J121D01*
G02X1380306Y25472I564J-1284D01*
G03X1379764Y25717I-381J-121D01*
G02X1380536Y27426I-564J1284D01*
G37*
G36*
G01X14801Y25749D02*
G03X15397Y25723I310J253D01*
G02X15315Y23856I1003J-979D01*
G03X14719Y23882I-310J-253D01*
G02X14801Y25749I-1003J979D01*
G37*
G36*
G01X1767069Y22498D02*
X1763360D01*
G02Y25522I0J1512D01*
G01X1767069D01*
G02X1768580Y24020I-1J-1512D01*
G01Y23925D01*
X1768571Y23841D01*
G02X1767069Y22498I-1502J169D01*
G37*
G36*
G01X1550861Y22846D02*
G03X1550307I-277J-288D01*
G02Y24866I-973J1010D01*
G03X1550861I277J288D01*
G02X1552845Y24827I973J-1010D01*
G03X1553423I289J277D01*
G02Y22885I1011J-971D01*
G03X1552845I-289J-277D01*
G02X1550861Y22846I-1011J971D01*
G37*
G36*
G01X1748152Y21686D02*
X1743152D01*
G02Y24708I0J1511D01*
G01X1748153D01*
G02X1749664Y23207I0J-1512D01*
G01Y23112D01*
X1749654Y23028D01*
G02X1748152Y21686I-1502J169D01*
G37*
G36*
G01X655327Y21790D02*
G03X654773I-277J-288D01*
G02Y23810I-973J1010D01*
G03X655327I277J288D01*
G02Y21790I973J-1010D01*
G37*
G36*
G01X1738168Y20800D02*
X1733168D01*
G02Y23824I0J1512D01*
G01X1738169D01*
G02X1739680Y22322I-1J-1512D01*
G01Y22227D01*
X1739670Y22143D01*
G02X1738168Y20800I-1502J169D01*
G37*
G36*
G01X1532430Y23307D02*
G02Y24629I3693J661D01*
G02Y23307I3693J-661D01*
G37*
G36*
G01X1824343Y22637D02*
G03X1824913Y22612I297J267D01*
G02X1824827Y20650I957J-1025D01*
G03X1824257Y20675I-297J-267D01*
G02X1824343Y22637I-957J1025D01*
G37*
G36*
G01X691427Y19790D02*
G03X690873I-277J-288D01*
G02Y21810I-973J1010D01*
G03X691427I277J288D01*
G02Y19790I973J-1010D01*
G37*
G36*
G01X1760709Y18534D02*
X1757009Y18496D01*
G02X1756976Y21518I-16J1511D01*
G01X1760677Y21556D01*
G02X1762198Y20189I16J-1511D01*
G01X1762204Y20130D01*
X1762205Y20071D01*
G02Y20019I-1512J-26D01*
G01X1762204Y20017D01*
Y20007D01*
G02X1760709Y18534I-1511J38D01*
G37*
G36*
G01X373192Y18898D02*
G03X373437Y19395I-136J376D01*
G02X375251Y18501I1336J424D01*
G03X375006Y18004I136J-376D01*
G02X373192Y18898I-1336J-424D01*
G37*
G36*
G01X1013899Y16081D02*
G03X1013311Y16074I-291J-275D01*
G02X1013290Y17975I-1041J939D01*
G03X1013878Y17982I291J275D01*
G02X1015930Y18013I1040J-940D01*
G03X1016508I289J277D01*
G02Y16071I1011J-971D01*
G03X1015930I-289J-277D01*
G02X1013899Y16081I-1011J971D01*
G37*
G36*
G01X364291D02*
G03X363703Y16074I-291J-275D01*
G02X363682Y17975I-1041J939D01*
G03X364270Y17982I291J275D01*
G02X366322Y18013I1040J-940D01*
G03X366900I289J277D01*
G02Y16071I1011J-971D01*
G03X366322I-289J-277D01*
G02X364291Y16081I-1011J971D01*
G37*
G36*
G01X1047394Y15661D02*
G03X1046925Y15287I-70J-394D01*
G02X1045768Y16738I-1400J70D01*
G03X1046237Y17112I70J394D01*
G02X1047394Y15661I1400J-70D01*
G37*
G36*
G01X1375911Y14137D02*
G03X1375375Y14134I-266J-299D01*
G02X1373408Y14211I-944J1036D01*
G03X1372860Y14245I-292J-273D01*
G02X1370835Y16459I-959J1156D01*
G03Y16741I-142J141D01*
G02X1370857Y18881I1065J1059D01*
G03X1370863Y19163I-139J144D01*
G02X1370888Y21263I1087J1037D01*
G03X1370887Y21547I-141J142D01*
G02X1373003Y21554I1054J1070D01*
G03X1373004Y21270I141J-142D01*
G02X1372993Y19119I-1054J-1070D01*
G03X1372987Y18837I139J-144D01*
G02X1372965Y16741I-1087J-1037D01*
G03Y16459I142J-141D01*
G02X1373053Y16363I-1062J-1062D01*
G03X1373598Y16297I307J256D01*
G02X1375362Y16218I833J-1127D01*
G03X1375898Y16221I266J299D01*
G02X1375911Y14137I944J-1036D01*
G37*
G36*
G01X1577048Y10994D02*
X1573048D01*
G02Y14018I0J1512D01*
G01X1577049D01*
G02X1578560Y12516I-1J-1512D01*
G01Y12421D01*
X1578550Y12337D01*
G02X1577048Y10994I-1502J169D01*
G37*
G36*
G01X1567498D02*
X1563498D01*
G02Y14018I0J1512D01*
G01X1567499D01*
G02X1569010Y12516I-1J-1512D01*
G01Y12421D01*
X1569000Y12337D01*
G02X1567498Y10994I-1502J169D01*
G37*
G36*
G01X1548698D02*
X1544698D01*
G02Y14018I0J1512D01*
G01X1548699D01*
G02X1550210Y12516I-1J-1512D01*
G01Y12421D01*
X1550200Y12337D01*
G02X1548698Y10994I-1502J169D01*
G37*
G36*
G01X1554148Y13818D02*
X1558148D01*
G02X1559660Y12316I0J-1512D01*
G01Y12221D01*
X1559650Y12137D01*
G02X1558148Y10794I-1502J169D01*
G01X1554148D01*
G02Y13818I0J1512D01*
G37*
G36*
G01X1230845Y13503D02*
G03Y12925I277J-289D01*
G02X1228903I-971J-1011D01*
G03Y13503I-277J289D01*
G02X1230845I971J1011D01*
G37*
G36*
G01X1194034D02*
G03Y12925I277J-289D01*
G02X1192092I-971J-1011D01*
G03Y13503I-277J289D01*
G02X1194034I971J1011D01*
G37*
G36*
G01X1157223D02*
G03Y12925I277J-289D01*
G02X1155281I-971J-1011D01*
G03Y13503I-277J289D01*
G02X1157223I971J1011D01*
G37*
G36*
G01X1120411D02*
G03Y12925I277J-289D01*
G02X1118469I-971J-1011D01*
G03Y13503I-277J289D01*
G02X1120411I971J1011D01*
G37*
G36*
G01X939703D02*
G03Y12925I277J-289D01*
G02X937761I-971J-1011D01*
G03Y13503I-277J289D01*
G02X939703I971J1011D01*
G37*
G36*
G01X902892D02*
G03Y12925I277J-289D01*
G02X900950I-971J-1011D01*
G03Y13503I-277J289D01*
G02X902892I971J1011D01*
G37*
G36*
G01X866081D02*
G03Y12925I277J-289D01*
G02X864139I-971J-1011D01*
G03Y13503I-277J289D01*
G02X866081I971J1011D01*
G37*
G36*
G01X829270D02*
G03Y12925I277J-289D01*
G02X827328I-971J-1011D01*
G03Y13503I-277J289D01*
G02X829270I971J1011D01*
G37*
G36*
G01X792459D02*
G03Y12925I277J-289D01*
G02X790517I-971J-1011D01*
G03Y13503I-277J289D01*
G02X792459I971J1011D01*
G37*
G36*
G01X581237D02*
G03Y12925I277J-289D01*
G02X579295I-971J-1011D01*
G03Y13503I-277J289D01*
G02X581237I971J1011D01*
G37*
G36*
G01X544426D02*
G03Y12925I277J-289D01*
G02X542484I-971J-1011D01*
G03Y13503I-277J289D01*
G02X544426I971J1011D01*
G37*
G36*
G01X507615D02*
G03Y12925I277J-289D01*
G02X505673I-971J-1011D01*
G03Y13503I-277J289D01*
G02X507615I971J1011D01*
G37*
G36*
G01X470803D02*
G03Y12925I277J-289D01*
G02X468861I-971J-1011D01*
G03Y13503I-277J289D01*
G02X470803I971J1011D01*
G37*
G36*
G01X290095D02*
G03Y12925I277J-289D01*
G02X288153I-971J-1011D01*
G03Y13503I-277J289D01*
G02X290095I971J1011D01*
G37*
G36*
G01X253284D02*
G03Y12925I277J-289D01*
G02X251342I-971J-1011D01*
G03Y13503I-277J289D01*
G02X253284I971J1011D01*
G37*
G36*
G01X216473D02*
G03Y12925I277J-289D01*
G02X214531I-971J-1011D01*
G03Y13503I-277J289D01*
G02X216473I971J1011D01*
G37*
G36*
G01X179662D02*
G03Y12925I277J-289D01*
G02X177720I-971J-1011D01*
G03Y13503I-277J289D01*
G02X179662I971J1011D01*
G37*
G36*
G01X142851D02*
G03Y12925I277J-289D01*
G02X140909I-971J-1011D01*
G03Y13503I-277J289D01*
G02X142851I971J1011D01*
G37*
G36*
G01X1225745Y13289D02*
G03Y12711I277J-289D01*
G02X1223803I-971J-1011D01*
G03Y13289I-277J289D01*
G02X1225745I971J1011D01*
G37*
G36*
G01X1188934D02*
G03Y12711I277J-289D01*
G02X1186992I-971J-1011D01*
G03Y13289I-277J289D01*
G02X1188934I971J1011D01*
G37*
G36*
G01X1152123D02*
G03Y12711I277J-289D01*
G02X1150181I-971J-1011D01*
G03Y13289I-277J289D01*
G02X1152123I971J1011D01*
G37*
G36*
G01X1115311D02*
G03Y12711I277J-289D01*
G02X1113369I-971J-1011D01*
G03Y13289I-277J289D01*
G02X1115311I971J1011D01*
G37*
G36*
G01X934603D02*
G03Y12711I277J-289D01*
G02X932661I-971J-1011D01*
G03Y13289I-277J289D01*
G02X934603I971J1011D01*
G37*
G36*
G01X897792D02*
G03Y12711I277J-289D01*
G02X895850I-971J-1011D01*
G03Y13289I-277J289D01*
G02X897792I971J1011D01*
G37*
G36*
G01X860981D02*
G03Y12711I277J-289D01*
G02X859039I-971J-1011D01*
G03Y13289I-277J289D01*
G02X860981I971J1011D01*
G37*
G36*
G01X824170D02*
G03Y12711I277J-289D01*
G02X822228I-971J-1011D01*
G03Y13289I-277J289D01*
G02X824170I971J1011D01*
G37*
G36*
G01X787359D02*
G03Y12711I277J-289D01*
G02X785417I-971J-1011D01*
G03Y13289I-277J289D01*
G02X787359I971J1011D01*
G37*
G36*
G01X576137D02*
G03Y12711I277J-289D01*
G02X574195I-971J-1011D01*
G03Y13289I-277J289D01*
G02X576137I971J1011D01*
G37*
G36*
G01X539326D02*
G03Y12711I277J-289D01*
G02X537384I-971J-1011D01*
G03Y13289I-277J289D01*
G02X539326I971J1011D01*
G37*
G36*
G01X502515D02*
G03Y12711I277J-289D01*
G02X500573I-971J-1011D01*
G03Y13289I-277J289D01*
G02X502515I971J1011D01*
G37*
G36*
G01X465703D02*
G03Y12711I277J-289D01*
G02X463761I-971J-1011D01*
G03Y13289I-277J289D01*
G02X465703I971J1011D01*
G37*
G36*
G01X284995D02*
G03Y12711I277J-289D01*
G02X283053I-971J-1011D01*
G03Y13289I-277J289D01*
G02X284995I971J1011D01*
G37*
G36*
G01X248184D02*
G03Y12711I277J-289D01*
G02X246242I-971J-1011D01*
G03Y13289I-277J289D01*
G02X248184I971J1011D01*
G37*
G36*
G01X211373D02*
G03Y12711I277J-289D01*
G02X209431I-971J-1011D01*
G03Y13289I-277J289D01*
G02X211373I971J1011D01*
G37*
G36*
G01X174562D02*
G03Y12711I277J-289D01*
G02X172620I-971J-1011D01*
G03Y13289I-277J289D01*
G02X174562I971J1011D01*
G37*
G36*
G01X137751D02*
G03Y12711I277J-289D01*
G02X135809I-971J-1011D01*
G03Y13289I-277J289D01*
G02X137751I971J1011D01*
G37*
G36*
G01X1484135Y10052D02*
X1479135D01*
G02Y13074I0J1511D01*
G01X1484136D01*
G02X1485646Y11573I-1J-1511D01*
G01Y11478D01*
X1485637Y11394D01*
G02X1484135Y10052I-1502J169D01*
G37*
G36*
G01X1465237D02*
X1460237D01*
G02Y13074I0J1511D01*
G01X1465238D01*
G02X1466748Y11573I-1J-1511D01*
G01Y11478D01*
X1466739Y11394D01*
G02X1465237Y10052I-1502J169D01*
G37*
G36*
G01X1441340Y13074D02*
X1446341D01*
G02X1447852Y11573I0J-1512D01*
G01Y11478D01*
X1447842Y11394D01*
G02X1446340Y10052I-1502J169D01*
G01X1441340D01*
G02Y13074I1J1511D01*
G37*
G36*
G01X1427442Y10052D02*
X1422442D01*
G02Y13074I0J1511D01*
G01X1427443D01*
G02X1428954Y11573I0J-1512D01*
G01Y11478D01*
X1428944Y11394D01*
G02X1427442Y10052I-1502J169D01*
G37*
G36*
G01X1728678Y9870D02*
X1723678D01*
G02Y12892I0J1511D01*
G01X1728679D01*
G02X1730190Y11391I0J-1512D01*
G01Y11296D01*
X1730180Y11212D01*
G02X1728678Y9870I-1502J169D01*
G37*
G36*
G01X1681428D02*
X1676428D01*
G02Y12892I0J1511D01*
G01X1681429D01*
G02X1682940Y11391I0J-1512D01*
G01Y11296D01*
X1682930Y11212D01*
G02X1681428Y9870I-1502J169D01*
G37*
G36*
G01X1605898Y9844D02*
X1600898D01*
G02Y12866I0J1511D01*
G01X1605899D01*
G02X1607410Y11365I0J-1512D01*
G01Y11270D01*
X1607400Y11186D01*
G02X1605898Y9844I-1502J169D01*
G37*
G36*
G01X1586998D02*
X1581998D01*
G02Y12866I0J1511D01*
G01X1586999D01*
G02X1588510Y11365I0J-1512D01*
G01Y11270D01*
X1588500Y11186D01*
G02X1586998Y9844I-1502J169D01*
G37*
G36*
G01X1700200Y9806D02*
X1695200D01*
G02Y12828I0J1511D01*
G01X1700201D01*
G02X1701712Y11327I0J-1512D01*
G01Y11232D01*
X1701702Y11148D01*
G02X1700200Y9806I-1502J170D01*
G37*
G36*
G01X1709771Y9750D02*
X1704771D01*
G02Y12772I0J1511D01*
G01X1709772D01*
G02X1711282Y11271I-1J-1511D01*
G01Y11176D01*
X1711273Y11092D01*
G02X1709771Y9750I-1502J169D01*
G37*
G36*
G01X1719297Y9668D02*
X1714297D01*
G02Y12692I0J1512D01*
G01X1719298D01*
G02X1720808Y11190I-1J-1512D01*
G01Y11095D01*
X1720799Y11011D01*
G02X1719297Y9668I-1502J169D01*
G37*
G36*
G01X1643865Y9594D02*
X1638865D01*
G02Y12616I0J1511D01*
G01X1643866D01*
G02X1645376Y11115I-1J-1511D01*
G01Y11020D01*
X1645367Y10936D01*
G02X1643865Y9594I-1502J169D01*
G37*
G36*
G01X1690948Y9214D02*
X1685948D01*
G02Y12236I0J1511D01*
G01X1690949D01*
G02X1692460Y10735I0J-1512D01*
G01Y10640D01*
X1692450Y10556D01*
G02X1690948Y9214I-1502J169D01*
G37*
G36*
G01X1302990Y9175D02*
G03X1302368I-311J-252D01*
G02X1300259Y11020I-1089J883D01*
G03X1300242Y11587I-291J275D01*
G02X1300225Y13618I958J1024D01*
G03Y14192I-278J287D01*
G02X1302289Y16083I976J1007D01*
G03X1302911I311J252D01*
G02X1305089I1089J-883D01*
G03X1305711I311J252D01*
G02X1307775Y14192I1088J-884D01*
G03Y13618I278J-287D01*
G02X1307820Y11648I-975J-1008D01*
G03X1307837Y11081I291J-275D01*
G02X1305790Y9175I-957J-1024D01*
G03X1305168I-311J-252D01*
G02X1302990I-1089J883D01*
G37*
G36*
G01X1663884Y10164D02*
Y10069D01*
X1663875Y9985D01*
G02X1662342Y8643I-1502J169D01*
G01X1657338Y8747D01*
G02X1657400Y11769I31J1511D01*
G01X1662403Y11665D01*
G02X1663884Y10164I-30J-1511D01*
G37*
G36*
G01X1401627Y8990D02*
G03X1401073I-277J-288D01*
G02Y11010I-973J1010D01*
G03X1401627I277J288D01*
G02X1403573I973J-1010D01*
G03X1404127I277J288D01*
G02Y8990I973J-1010D01*
G03X1403573I-277J-288D01*
G02X1401627I-973J1010D01*
G37*
G36*
G01X665011Y9117D02*
G03X664389I-311J-252D01*
G02Y10883I-1089J883D01*
G03X665011I311J252D01*
G02Y9117I1089J-883D01*
G37*
G36*
G01X82642Y10684D02*
G03X82629Y10122I278J-288D01*
G02X80364Y8516I-1019J-963D01*
G03X79806Y8677I-355J-184D01*
G02X78085Y10857I-710J1209D01*
G03X78089Y11406I-289J277D01*
G02X78229Y13446I1027J954D01*
G03X78285Y14009I-253J309D01*
G02X80652Y15467I1087J886D01*
G03X81238Y15297I365J164D01*
G02X82894Y13038I775J-1168D01*
G03X82817Y12497I251J-312D01*
G02X82642Y10684I-1148J-804D01*
G37*
G36*
G01X1259473Y10130D02*
G03X1260036Y10118I288J278D01*
G02X1259991Y8127I964J-1018D01*
G03X1259428Y8139I-288J-278D01*
G02X1259473Y10130I-964J1018D01*
G37*
G36*
G01X1754065Y10273D02*
G03X1754640Y10183I330J226D01*
G02X1754343Y8284I860J-1107D01*
G03X1753768Y8374I-330J-226D01*
G02X1754065Y10273I-860J1107D01*
G37*
G36*
G01X1591848Y12918D02*
X1595849D01*
G02X1597360Y11416I-1J-1512D01*
G01Y11321D01*
X1597350Y11237D01*
G02X1595848Y9894I-1502J169D01*
G01X1593957D01*
G03X1593623Y9274I0J-400D01*
G02X1591378Y9402I-1170J-772D01*
G03X1591234Y10025I-306J257D01*
G02X1591848Y12918I614J1381D01*
G37*
G36*
G01X1436025Y6244D02*
X1431025D01*
G02Y9268I0J1512D01*
G01X1436026D01*
G02X1437536Y7766I-1J-1512D01*
G01Y7671D01*
X1437527Y7587D01*
G02X1436025Y6244I-1502J169D01*
G37*
G36*
G01X1493770Y5398D02*
X1488770D01*
G02Y8420I0J1511D01*
G01X1493771D01*
G02X1495282Y6919I0J-1512D01*
G01Y6824D01*
X1495272Y6740D01*
G02X1493770Y5398I-1502J169D01*
G37*
G36*
G01X1634148Y5314D02*
X1629148D01*
G02Y8336I0J1511D01*
G01X1634149D01*
G02X1635660Y6835I0J-1512D01*
G01Y6740D01*
X1635650Y6656D01*
G02X1634148Y5314I-1502J169D01*
G37*
G36*
G01X1653748Y4814D02*
X1648748D01*
G02Y7836I0J1511D01*
G01X1653749D01*
G02X1655260Y6335I0J-1512D01*
G01Y6240D01*
X1655250Y6156D01*
G02X1653748Y4814I-1502J169D01*
G37*
G36*
G01X1671979Y4724D02*
X1666979D01*
G02Y7748I0J1512D01*
G01X1671979D01*
G02X1673490Y6246I-1J-1512D01*
G01Y6151D01*
X1673481Y6067D01*
G02X1671979Y4724I-1502J168D01*
G37*
G36*
G01X1368378Y4805D02*
G03X1367800I-289J-277D01*
G02Y6747I-1011J971D01*
G03X1368378I289J277D01*
G02Y4805I1011J-971D01*
G37*
G36*
G01X1474388Y4078D02*
X1469388D01*
G02Y7100I0J1511D01*
G01X1474389D01*
G02X1475900Y5599I0J-1512D01*
G01Y5504D01*
X1475890Y5420D01*
G02X1474388Y4078I-1502J169D01*
G37*
G36*
G01X1454991D02*
X1449991D01*
G02Y7100I0J1511D01*
G01X1454992D01*
G02X1456502Y5599I-1J-1511D01*
G01Y5504D01*
X1456493Y5420D01*
G02X1454991Y4078I-1502J169D01*
G37*
G36*
G01X1614833Y3914D02*
X1609833D01*
G02Y6936I0J1511D01*
G01X1614834D01*
G02X1616344Y5435I-1J-1511D01*
G01Y5340D01*
X1616335Y5256D01*
G02X1614833Y3914I-1502J169D01*
G37*
G36*
G01X665442Y3406D02*
G03X664944Y3216I-143J-374D01*
G02X664199Y5171I-1245J645D01*
G03X664697Y5361I143J374D01*
G02X665442Y3406I1245J-645D01*
G37*
G36*
G01X115022Y5064D02*
G03X115000Y4483I263J-301D01*
G02X113078Y4556I-1000J-983D01*
G03X113100Y5137I-263J301D01*
G02X115022Y5064I1000J983D01*
G37*
G36*
G01X1381205Y4584D02*
G03X1381223Y3999I282J-284D01*
G02X1379314Y3941I-923J-1055D01*
G03X1379296Y4526I-282J284D01*
G02X1381205Y4584I923J1055D01*
G37*
G36*
G01X1328965Y4380D02*
G03X1329273Y3898I389J-91D01*
G02X1327952Y1579I-286J-1373D01*
G03X1327378Y1596I-295J-270D01*
G02X1325311Y1717I-978J1004D01*
G03X1324689I-311J-252D01*
G02X1322511I-1089J883D01*
G03X1321889I-311J-252D01*
G02X1319672Y1768I-1089J883D01*
G03X1319028I-322J-238D01*
G02X1316783Y1753I-1128J832D01*
G03X1316140Y1745I-319J-242D01*
G02X1313907Y1694I-1136J822D01*
G03X1313306Y1724I-314J-248D01*
G02X1311211Y1817I-1006J976D01*
G03X1310589I-311J-252D01*
G02X1308411I-1089J883D01*
G03X1307789I-311J-252D01*
G02X1305611I-1089J883D01*
G03X1304989I-311J-252D01*
G02X1302811I-1089J883D01*
G03X1302189I-311J-252D01*
G02X1300664Y4033I-1089J883D01*
G03X1300931Y4499I-124J380D01*
G02X1303389Y5683I1369J301D01*
G03X1304011I311J252D01*
G02X1306189I1089J-883D01*
G03X1306811I311J252D01*
G02X1308989I1089J-883D01*
G03X1309611I311J252D01*
G02X1311789I1089J-883D01*
G03X1312411I311J252D01*
G02X1314621Y5642I1089J-883D01*
G03X1315242Y5620I319J241D01*
G02X1317428Y5532I1058J-920D01*
G03X1318072I322J238D01*
G02X1320289Y5583I1128J-832D01*
G03X1320911I311J252D01*
G02X1323089I1089J-883D01*
G03X1323711I311J252D01*
G02X1325889I1089J-883D01*
G03X1326511I311J252D01*
G02X1328965Y4380I1089J-883D01*
G37*
G36*
G01X1825803Y2785D02*
G03X1825972Y2243I354J-187D01*
G02X1824085Y1656I-648J-1243D01*
G03X1823916Y2198I-354J187D01*
G02X1825803Y2785I648J1243D01*
G37*
G36*
G01X752985Y1288D02*
G03X753584Y1266I309J254D01*
G02X753515Y-588I1016J-966D01*
G03X752916Y-566I-309J-254D01*
G02X752985Y1288I-1016J966D01*
G37*
G36*
G01X1600129Y-1610D02*
G03X1599575I-277J-288D01*
G02Y410I-973J1010D01*
G03X1600129I277J288D01*
G02Y-1610I973J-1010D01*
G37*
G36*
G01X63074Y-533D02*
G03X63194Y-1141I308J-255D01*
G02X61456Y-1484I-659J-1238D01*
G03X61336Y-876I-308J255D01*
G02X63074Y-533I659J1238D01*
G37*
G36*
G01X1381410Y-3782D02*
G03X1381885Y-4168I400J7D01*
G02X1380749Y-5568I266J-1377D01*
G03X1380274Y-5182I-400J-7D01*
G02X1381410Y-3782I-266J1377D01*
G37*
G36*
G01X718771Y-5838D02*
G03X718316Y-6193I-57J-396D01*
G02X717125Y-4661I-1395J145D01*
G03X717580Y-4306I57J396D01*
G02X718771Y-5838I1395J-145D01*
G37*
G36*
G01X1225735Y-5422D02*
G03X1225740Y-6010I274J-292D01*
G02X1223839Y-6029I-940J-1040D01*
G03X1223834Y-5441I-274J292D01*
G02X1225735Y-5422I940J1040D01*
G37*
G36*
G01X1188924D02*
G03X1188929Y-6010I274J-292D01*
G02X1187028Y-6029I-940J-1040D01*
G03X1187023Y-5441I-274J292D01*
G02X1188924Y-5422I940J1040D01*
G37*
G36*
G01X1152113D02*
G03X1152118Y-6010I274J-292D01*
G02X1150217Y-6029I-940J-1040D01*
G03X1150212Y-5441I-274J292D01*
G02X1152113Y-5422I940J1040D01*
G37*
G36*
G01X1115301D02*
G03X1115306Y-6010I274J-292D01*
G02X1113405Y-6029I-940J-1040D01*
G03X1113400Y-5441I-274J292D01*
G02X1115301Y-5422I940J1040D01*
G37*
G36*
G01X934593D02*
G03X934598Y-6010I274J-292D01*
G02X932697Y-6029I-940J-1040D01*
G03X932692Y-5441I-274J292D01*
G02X934593Y-5422I940J1040D01*
G37*
G36*
G01X897782D02*
G03X897787Y-6010I274J-292D01*
G02X895886Y-6029I-940J-1040D01*
G03X895881Y-5441I-274J292D01*
G02X897782Y-5422I940J1040D01*
G37*
G36*
G01X860971D02*
G03X860976Y-6010I274J-292D01*
G02X859075Y-6029I-940J-1040D01*
G03X859070Y-5441I-274J292D01*
G02X860971Y-5422I940J1040D01*
G37*
G36*
G01X824160D02*
G03X824165Y-6010I274J-292D01*
G02X822264Y-6029I-940J-1040D01*
G03X822259Y-5441I-274J292D01*
G02X824160Y-5422I940J1040D01*
G37*
G36*
G01X787349D02*
G03X787354Y-6010I274J-292D01*
G02X785453Y-6029I-940J-1040D01*
G03X785448Y-5441I-274J292D01*
G02X787349Y-5422I940J1040D01*
G37*
G36*
G01X576127D02*
G03X576132Y-6010I274J-292D01*
G02X574231Y-6029I-940J-1040D01*
G03X574226Y-5441I-274J292D01*
G02X576127Y-5422I940J1040D01*
G37*
G36*
G01X539316D02*
G03X539321Y-6010I274J-292D01*
G02X537420Y-6029I-940J-1040D01*
G03X537415Y-5441I-274J292D01*
G02X539316Y-5422I940J1040D01*
G37*
G36*
G01X502505D02*
G03X502510Y-6010I274J-292D01*
G02X500609Y-6029I-940J-1040D01*
G03X500604Y-5441I-274J292D01*
G02X502505Y-5422I940J1040D01*
G37*
G36*
G01X465693D02*
G03X465698Y-6010I274J-292D01*
G02X463797Y-6029I-940J-1040D01*
G03X463792Y-5441I-274J292D01*
G02X465693Y-5422I940J1040D01*
G37*
G36*
G01X284985D02*
G03X284990Y-6010I274J-292D01*
G02X283089Y-6029I-940J-1040D01*
G03X283084Y-5441I-274J292D01*
G02X284985Y-5422I940J1040D01*
G37*
G36*
G01X248174D02*
G03X248179Y-6010I274J-292D01*
G02X246278Y-6029I-940J-1040D01*
G03X246273Y-5441I-274J292D01*
G02X248174Y-5422I940J1040D01*
G37*
G36*
G01X211363D02*
G03X211368Y-6010I274J-292D01*
G02X209467Y-6029I-940J-1040D01*
G03X209462Y-5441I-274J292D01*
G02X211363Y-5422I940J1040D01*
G37*
G36*
G01X174552D02*
G03X174557Y-6010I274J-292D01*
G02X172656Y-6029I-940J-1040D01*
G03X172651Y-5441I-274J292D01*
G02X174552Y-5422I940J1040D01*
G37*
G36*
G01X137741D02*
G03X137746Y-6010I274J-292D01*
G02X135845Y-6029I-940J-1040D01*
G03X135840Y-5441I-274J292D01*
G02X137741Y-5422I940J1040D01*
G37*
G36*
G01X1230841Y-5666D02*
G03Y-6245I276J-290D01*
G02X1228907I-967J-1015D01*
G03Y-5666I-276J290D01*
G02X1230841I967J1015D01*
G37*
G36*
G01X1194030D02*
G03Y-6245I276J-290D01*
G02X1192096I-967J-1015D01*
G03Y-5666I-276J290D01*
G02X1194030I967J1015D01*
G37*
G36*
G01X1157219D02*
G03Y-6245I276J-290D01*
G02X1155285I-967J-1015D01*
G03Y-5666I-276J290D01*
G02X1157219I967J1015D01*
G37*
G36*
G01X1120407D02*
G03Y-6245I276J-290D01*
G02X1118473I-967J-1015D01*
G03Y-5666I-276J290D01*
G02X1120407I967J1015D01*
G37*
G36*
G01X939699D02*
G03Y-6245I276J-290D01*
G02X937765I-967J-1015D01*
G03Y-5666I-276J290D01*
G02X939699I967J1015D01*
G37*
G36*
G01X902888D02*
G03Y-6245I276J-290D01*
G02X900954I-967J-1015D01*
G03Y-5666I-276J290D01*
G02X902888I967J1015D01*
G37*
G36*
G01X866077D02*
G03Y-6245I276J-290D01*
G02X864143I-967J-1015D01*
G03Y-5666I-276J290D01*
G02X866077I967J1015D01*
G37*
G36*
G01X829266D02*
G03Y-6245I276J-290D01*
G02X827332I-967J-1015D01*
G03Y-5666I-276J290D01*
G02X829266I967J1015D01*
G37*
G36*
G01X792455D02*
G03Y-6245I276J-290D01*
G02X790521I-967J-1015D01*
G03Y-5666I-276J290D01*
G02X792455I967J1015D01*
G37*
G36*
G01X581233D02*
G03Y-6245I276J-290D01*
G02X579299I-967J-1015D01*
G03Y-5666I-276J290D01*
G02X581233I967J1015D01*
G37*
G36*
G01X544422D02*
G03Y-6245I276J-290D01*
G02X542488I-967J-1015D01*
G03Y-5666I-276J290D01*
G02X544422I967J1015D01*
G37*
G36*
G01X507611D02*
G03Y-6245I276J-290D01*
G02X505677I-967J-1015D01*
G03Y-5666I-276J290D01*
G02X507611I967J1015D01*
G37*
G36*
G01X470799D02*
G03Y-6245I276J-290D01*
G02X468865I-967J-1015D01*
G03Y-5666I-276J290D01*
G02X470799I967J1015D01*
G37*
G36*
G01X290091D02*
G03Y-6245I276J-290D01*
G02X288157I-967J-1015D01*
G03Y-5666I-276J290D01*
G02X290091I967J1015D01*
G37*
G36*
G01X253280D02*
G03Y-6245I276J-290D01*
G02X251346I-967J-1015D01*
G03Y-5666I-276J290D01*
G02X253280I967J1015D01*
G37*
G36*
G01X216469D02*
G03Y-6245I276J-290D01*
G02X214535I-967J-1015D01*
G03Y-5666I-276J290D01*
G02X216469I967J1015D01*
G37*
G36*
G01X179658D02*
G03Y-6245I276J-290D01*
G02X177724I-967J-1015D01*
G03Y-5666I-276J290D01*
G02X179658I967J1015D01*
G37*
G36*
G01X142847D02*
G03Y-6245I276J-290D01*
G02X140913I-967J-1015D01*
G03Y-5666I-276J290D01*
G02X142847I967J1015D01*
G37*
G36*
G01X647971Y-10511D02*
G03Y-11089I277J-289D01*
G02X646029I-971J-1011D01*
G03Y-10511I-277J289D01*
G02X646208Y-8343I971J1011D01*
G03X646297Y-7766I-226J330D01*
G02X648192Y-8057I1103J866D01*
G03X648103Y-8634I226J-330D01*
G02X647971Y-10511I-1103J-866D01*
G37*
G36*
G01X64936Y-12238D02*
G03X65464Y-12420I357J180D01*
G02X64808Y-14317I597J-1268D01*
G03X64280Y-14135I-357J-180D01*
G02X64936Y-12238I-597J1268D01*
G37*
G36*
G01X730372Y-16258D02*
G03X729818Y-16331I-240J-320D01*
G02X727466Y-16100I-1102J866D01*
G03X726936Y-15921I-356J-181D01*
G02X725354Y-15668I-609J1263D01*
G03X724800I-277J-288D01*
G02Y-13648I-973J1010D01*
G03X725354I277J288D01*
G02X726891Y-13374I973J-1010D01*
G03X727448Y-12954I161J366D01*
G02X729716Y-13856I1389J191D01*
G03X729689Y-14455I250J-311D01*
G02X729693Y-14460I-1084J-871D01*
G03X730004Y-14418I139J144D01*
G02X730372Y-16258I1206J-716D01*
G37*
G36*
G01X1585527Y-17110D02*
G03X1584973I-277J-288D01*
G02Y-15090I-973J1010D01*
G03X1585527I277J288D01*
G02Y-17110I973J-1010D01*
G37*
G36*
G01X41289Y-16225D02*
G03X41102Y-15669I-351J191D01*
G02X42908Y-15061I575J1279D01*
G03X43095Y-15617I351J-191D01*
G02X41289Y-16225I-575J-1279D01*
G37*
G36*
G01X1375736Y-17802D02*
G03X1375155Y-17824I-280J-285D01*
G02X1373099Y-17881I-1054J924D01*
G03X1372569Y-17844I-286J-280D01*
G02X1370533Y-15654I-916J1190D01*
G03X1370522Y-15110I-299J266D01*
G02X1370449Y-13110I1083J1041D01*
G03X1370447Y-12598I-308J255D01*
G02X1370460Y-10653I1151J965D01*
G03X1370467Y-10139I-303J261D01*
G02X1372770Y-10171I1165J948D01*
G03X1372763Y-10685I303J-261D01*
G02X1372754Y-12592I-1165J-948D01*
G03X1372756Y-13104I308J-255D01*
G02X1372725Y-15069I-1151J-965D01*
G03X1372736Y-15613I299J-266D01*
G02X1372788Y-15670I-1083J-1041D01*
G03X1373314Y-15739I302J262D01*
G02X1375083Y-15900I786J-1161D01*
G03X1375664Y-15878I280J285D01*
G02X1375736Y-17802I1055J-924D01*
G37*
G36*
G01X1316783Y-17747D02*
G03X1316140Y-17755I-319J-242D01*
G02X1313907Y-17806I-1136J822D01*
G03X1313306Y-17776I-314J-248D01*
G02X1311211Y-17683I-1006J976D01*
G03X1310589I-311J-252D01*
G02X1308411I-1089J883D01*
G03X1307789I-311J-252D01*
G02X1306264Y-15467I-1089J883D01*
G03X1306531Y-15001I-124J380D01*
G02X1308989Y-13817I1369J301D01*
G03X1309611I311J252D01*
G02X1311789I1089J-883D01*
G03X1312411I311J252D01*
G02X1314621Y-13858I1089J-883D01*
G03X1315242Y-13880I319J241D01*
G02X1317428Y-13968I1058J-920D01*
G03X1318072I322J238D01*
G02X1320289Y-13917I1128J-832D01*
G03X1320911I311J252D01*
G02X1321879Y-13403I1089J-883D01*
G03X1322234Y-12915I-35J398D01*
G02X1324577Y-11595I1366J315D01*
G03X1325110Y-11617I279J287D01*
G02X1327089Y-11817I890J-1083D01*
G03X1327711I311J252D01*
G02X1329236Y-14033I1089J-883D01*
G03X1328969Y-14499I124J-380D01*
G02X1328036Y-16133I-1369J-302D01*
G03X1327769Y-16599I124J-380D01*
G02X1325311Y-17783I-1369J-301D01*
G03X1324689I-311J-252D01*
G02X1322511I-1089J883D01*
G03X1321889I-311J-252D01*
G02X1319672Y-17732I-1089J883D01*
G03X1319028I-322J-238D01*
G02X1316783Y-17747I-1128J832D01*
G37*
G36*
G01X1606531Y-18356D02*
G03X1605977I-277J-288D01*
G02Y-16336I-973J1010D01*
G03X1606531I277J288D01*
G02X1608477I973J-1010D01*
G03X1609031I277J288D01*
G02Y-18356I973J-1010D01*
G03X1608477I-277J-288D01*
G02X1606531I-973J1010D01*
G37*
G36*
G01X1596531D02*
G03X1595977I-277J-288D01*
G02Y-16336I-973J1010D01*
G03X1596531I277J288D01*
G02X1598477I973J-1010D01*
G03X1599031I277J288D01*
G02Y-18356I973J-1010D01*
G03X1598477I-277J-288D01*
G02X1596531I-973J1010D01*
G37*
G36*
G01X661185Y-16750D02*
G03X661784Y-16839I338J214D01*
G02X661515Y-18650I916J-1062D01*
G03X660916Y-18561I-338J-214D01*
G02X661185Y-16750I-916J1062D01*
G37*
G36*
G01X1300366Y-16666D02*
G03X1300430Y-17281I284J-281D01*
G02X1298511Y-17399I-881J-1338D01*
G03X1298500Y-16780I-259J305D01*
G02X1300366Y-16666I869J1100D01*
G37*
G36*
G01X21111Y-18129D02*
G03X21683Y-18241I339J213D01*
G02X21312Y-20127I816J-1140D01*
G03X20740Y-20015I-339J-213D01*
G02X21111Y-18129I-816J1140D01*
G37*
G36*
G01X709720Y-17986D02*
G03X710115Y-18437I397J-51D01*
G02X708717Y-19659I-8J-1402D01*
G03X708322Y-19208I-397J51D01*
G02X709720Y-17986I8J1402D01*
G37*
G36*
G01X1902168Y-18425D02*
G02X1901892Y-20014I992J-991D01*
G03X1901248Y-19902I-361J-171D01*
G02X1901524Y-18313I-992J991D01*
G03X1902168Y-18425I361J171D01*
G37*
G36*
G01X714334Y-17027D02*
G02X712514Y-17832I-510J-1306D01*
G03X712286Y-17317I-373J143D01*
G02X711398Y-16115I510J1306D01*
G03X710836Y-15780I-399J-30D01*
G02X709291Y-13490I-573J1280D01*
G03X709305Y-12928I-277J288D01*
G02X711299Y-12978I1022J960D01*
G03X711285Y-13540I277J-288D01*
G02X711661Y-14396I-1022J-960D01*
G03X712223Y-14731I399J30D01*
G02X714106Y-16512I573J-1280D01*
G03X714334Y-17027I373J-143D01*
G37*
G36*
G01X1674935Y-17561D02*
G02X1674904Y-16078I-1435J712D01*
G03X1675602Y-16084I351J193D01*
G02X1675632Y-17526I1217J-696D01*
G03X1674935Y-17561I-339J-213D01*
G37*
G36*
G01X1280343Y-15495D02*
G02X1280321Y-14060I-1443J696D01*
G03X1281025Y-14068I354J186D01*
G02X1283184Y-13700I1227J-679D01*
G03X1283763Y-13650I266J299D01*
G02X1283927Y-15571I1096J-874D01*
G03X1283348Y-15621I-266J-299D01*
G02X1281047Y-15464I-1096J874D01*
G03X1280343Y-15495I-344J-205D01*
G37*
G36*
G01X1498611Y-11287D02*
G02X1497445Y-12317I189J-1389D01*
G03X1496979Y-11822I-387J103D01*
G02X1498178Y-10763I-319J1570D01*
G03X1498611Y-11287I379J-127D01*
G37*
G36*
G01X90170Y-10745D02*
G02X88916Y-9191I-1393J159D01*
G03X89311Y-8609I40J398D01*
G02X90822Y-10483I5373J2786D01*
G03X90170Y-10745I-255J-308D01*
G37*
G36*
G01X735454Y-7525D02*
G02X734182Y-7734I-434J-1333D01*
G03X734066Y-7033I-239J320D01*
G02X733101Y-5790I434J1333D01*
G03X732588Y-5432I-399J-25D01*
G02X731232Y-3064I-397J1345D01*
G03X731260Y-2509I-273J292D01*
G02X733327Y-616I1056J922D01*
G03X733905I289J277D01*
G02Y-2558I1011J-971D01*
G03X733327I-289J-277D01*
G02X733275Y-2610I-1017J965D01*
G03X733247Y-3165I273J-292D01*
G02X733590Y-3997I-1056J-922D01*
G03X734103Y-4355I399J25D01*
G02X735338Y-6824I397J-1345D01*
G03X735454Y-7525I239J-320D01*
G37*
G36*
G01X1606667Y-4377D02*
G02Y-2823I-1167J777D01*
G03X1607333I333J222D01*
G02Y-4377I1167J-777D01*
G03X1606667I-333J-222D01*
G37*
G36*
G01X1837406Y-2254D02*
G02X1836404Y-3467I394J-1346D01*
G03X1835894Y-3046I-398J37D01*
G02X1836896Y-1833I-394J1346D01*
G03X1837406Y-2254I398J-37D01*
G37*
G36*
G01X624333Y-2565D02*
G02X623044Y-1599I-1333J-435D01*
G03X623437Y-1075I13J400D01*
G02X624726Y-2041I1333J435D01*
G03X624333Y-2565I-13J-400D01*
G37*
G36*
G01X1689167Y2223D02*
G02Y3777I-1167J777D01*
G03X1689833I333J222D01*
G02Y2223I1167J-777D01*
G03X1689167I-333J-222D01*
G37*
G36*
G01X1547967Y2623D02*
G02Y4177I-1167J777D01*
G03X1548633I333J222D01*
G02X1550773Y4410I1167J-777D01*
G03X1551327I277J288D01*
G02X1553273I973J-1010D01*
G03X1553827I277J288D01*
G02X1556045Y4045I973J-1010D01*
G03X1556755I355J184D01*
G02X1558973Y4410I1245J-645D01*
G03X1559527I277J288D01*
G02X1561550Y4329I973J-1010D01*
G03X1562150I300J265D01*
G02X1564289Y4283I1050J-929D01*
G03X1564911I311J252D01*
G02X1567167Y4177I1089J-883D01*
G03X1567833I333J222D01*
G02Y2623I1167J-777D01*
G03X1567167I-333J-222D01*
G02X1564911Y2517I-1167J777D01*
G03X1564289I-311J-252D01*
G02X1562150Y2471I-1089J883D01*
G03X1561550I-300J-265D01*
G02X1559527Y2390I-1050J929D01*
G03X1558973I-277J-288D01*
G02X1556755Y2755I-973J1010D01*
G03X1556045I-355J-184D01*
G02X1553827Y2390I-1245J645D01*
G03X1553273I-277J-288D01*
G02X1551327I-973J1010D01*
G03X1550773I-277J-288D01*
G02X1548633Y2623I-973J1010D01*
G03X1547967I-333J-222D01*
G37*
G36*
G01X1510373Y2490D02*
G02Y4510I-973J1010D01*
G03X1510927I277J288D01*
G02X1512873I973J-1010D01*
G03X1513427I277J288D01*
G02X1515373I973J-1010D01*
G03X1515927I277J288D01*
G02X1518145Y4145I973J-1010D01*
G03X1518855I355J184D01*
G02Y2855I1245J-645D01*
G03X1518145I-355J-184D01*
G02X1515927Y2490I-1245J645D01*
G03X1515373I-277J-288D01*
G02X1513427I-973J1010D01*
G03X1512873I-277J-288D01*
G02X1510927I-973J1010D01*
G03X1510373I-277J-288D01*
G37*
G36*
G01X1525889Y2617D02*
G02Y4383I-1089J883D01*
G03X1526511I311J252D01*
G02X1528845Y4145I1089J-883D01*
G03X1529555I355J184D01*
G02X1532045I1245J-645D01*
G03X1532755I355J184D01*
G02Y2855I1245J-645D01*
G03X1532045I-355J-184D01*
G02X1529555I-1245J645D01*
G03X1528845I-355J-184D01*
G02X1526511Y2617I-1245J645D01*
G03X1525889I-311J-252D01*
G37*
G36*
G01X1786560Y7365D02*
G02X1786549Y8852I-1194J735D01*
G03X1787227Y8857I337J215D01*
G02X1787238Y7370I1194J-735D01*
G03X1786560Y7365I-337J-215D01*
G37*
G36*
G01X649581Y7600D02*
G02X647784Y9724I-1031J950D01*
G03X647773Y10401I-218J335D01*
G02X649474Y12608I727J1199D01*
G03X650051Y12630I278J288D01*
G02X651847Y10513I1049J-931D01*
G03Y9837I213J-338D01*
G02X650147Y7622I-747J-1186D01*
G03X649581Y7600I-272J-293D01*
G37*
G36*
G01X356449Y9800D02*
G02X356446Y8434I1223J-686D01*
G03X355748Y8436I-350J-194D01*
G02X355751Y9802I-1223J686D01*
G03X356449Y9800I350J194D01*
G37*
G36*
G01X1006057D02*
G02X1006054Y8434I1223J-686D01*
G03X1005356Y8436I-350J-194D01*
G02X1005359Y9802I-1223J686D01*
G03X1006057Y9800I350J194D01*
G37*
G36*
G01X1809523Y10358D02*
G02X1807832Y10471I-920J-1058D01*
G03X1807875Y11107I-220J334D01*
G02X1809566Y10994I920J1058D01*
G03X1809523Y10358I220J-334D01*
G37*
G36*
G01X1619797Y12266D02*
X1624799D01*
G02X1626310Y10765I0J-1512D01*
G01Y10670D01*
X1626300Y10586D01*
G02X1624798Y9244I-1502J169D01*
G01X1619796D01*
G02X1618983Y9482I1J1511D01*
G03X1618375Y9224I-216J-336D01*
G02X1617708Y10710I-1375J276D01*
G03X1618305Y10992I202J345D01*
G02X1619797Y12266I1493J-237D01*
G37*
G36*
G01X1842292Y10352D02*
G02X1842206Y8838I1134J-824D01*
G03X1841534Y8876I-348J-197D01*
G02X1839427Y8690I-1134J824D01*
G03X1838873I-277J-288D01*
G02Y10710I-973J1010D01*
G03X1839427I277J288D01*
G02X1841620Y10390I972J-1010D01*
G03X1842292Y10352I348J197D01*
G37*
G36*
G01X1323621Y8939D02*
G02X1321743Y10981I-1089J883D01*
G03X1321733Y11650I-224J331D01*
G02X1321660Y13969I750J1184D01*
G03X1321666Y14613I-234J324D01*
G02X1323597Y16617I842J1121D01*
G03X1324219I311J252D01*
G02X1326340Y16682I1089J-883D01*
G03X1326948Y16704I295J271D01*
G02X1328789Y14643I1097J-873D01*
G03X1328806Y13954I212J-339D01*
G02X1328959Y11604I-683J-1224D01*
G03X1328950Y10968I238J-321D01*
G02X1327028Y8944I-865J-1103D01*
G03X1326417Y8934I-301J-263D01*
G02X1324243Y8939I-1085J888D01*
G03X1323621I-311J-252D01*
G37*
G36*
G01X1833522Y11557D02*
G02X1831621Y9726I-622J-1257D01*
G03X1830952Y9822I-365J-164D01*
G02X1831167Y11309I-1064J913D01*
G03X1831836Y11213I365J164D01*
G02X1832233Y11533I1064J-913D01*
G03X1832220Y12243I-190J352D01*
G02X1833509Y12267I621J1257D01*
G03X1833522Y11557I190J-352D01*
G37*
G36*
G01X63880Y12677D02*
G02X62764Y11443I279J-1374D01*
G03X62287Y11875I-398J40D01*
G02X63403Y13109I-279J1374D01*
G03X63880Y12677I398J-40D01*
G37*
G36*
G01X1847352Y13735D02*
G02X1847035Y12168I970J-1012D01*
G03X1846390Y12298I-368J-158D01*
G02X1846707Y13865I-970J1012D01*
G03X1847352Y13735I368J158D01*
G37*
G36*
G01X1869503Y12151D02*
G02X1869308Y13808I-1217J697D01*
G03X1869946Y13883I291J274D01*
G02X1870141Y12226I1217J-697D01*
G03X1869503Y12151I-291J-274D01*
G37*
G36*
G01X1414946Y12458D02*
G02Y13820I-1225J681D01*
G03X1415646I350J194D01*
G02Y12458I1225J-681D01*
G03X1414946I-350J-194D01*
G37*
G36*
G01X25301Y17595D02*
G02X23782Y16791I-241J-1381D01*
G03X23487Y17350I-364J165D01*
G02X25006Y18154I241J1381D01*
G03X25301Y17595I364J-165D01*
G37*
G36*
G01X63377Y18524D02*
G02X62881Y16915I823J-1135D01*
G03X62269Y17103I-376J-135D01*
G02X62765Y18712I-823J1135D01*
G03X63377Y18524I376J135D01*
G37*
G36*
G01X1025003Y18760D02*
G02X1023684Y19551I-1263J-610D01*
G03X1024028Y20124I-16J399D01*
G02X1025347Y19333I1263J610D01*
G03X1025003Y18760I16J-399D01*
G37*
G36*
G01X35905Y18708D02*
G02X35882Y20238I-1186J747D01*
G03X36553Y20248I332J223D01*
G02X38615Y20596I1186J-747D01*
G03X39234Y20755I250J312D01*
G02X39654Y19125I1296J-535D01*
G03X39035Y18966I-250J-312D01*
G02X36576Y18718I-1296J535D01*
G03X35905Y18708I-332J-223D01*
G37*
G36*
G01X702306Y18872D02*
G02X700071Y18689I-1186J747D01*
G03X699483Y18700I-299J-266D01*
G02X699519Y20599I-1013J969D01*
G03X700107Y20588I299J266D01*
G02X702291Y20390I1013J-969D01*
G03X702964Y20397I334J220D01*
G02X702979Y18879I1186J-747D01*
G03X702306Y18872I-334J-220D01*
G37*
G36*
G01X1853676Y20417D02*
G02X1850883Y21976I-1441J700D01*
G03X1850644Y22578I-338J214D01*
G02X1850313Y25557I396J1552D01*
G03X1850492Y26087I-182J357D01*
G02X1853336Y27558I1444J693D01*
G03X1854036I350J194D01*
G02X1856876Y27481I1400J-778D01*
G03X1857596I360J175D01*
G02X1860476I1440J-701D01*
G03X1861196I360J175D01*
G02X1864207Y26465I1440J-701D01*
G03X1864483Y26004I392J-78D01*
G02X1865565Y24045I-463J-1534D01*
G03X1865850Y23551I385J-107D01*
G02X1864840Y20519I-399J-1551D01*
G03X1864338Y20342I-152J-370D01*
G02X1861536Y20340I-1402J776D01*
G03X1860836I-350J-194D01*
G02X1857996Y20417I-1400J778D01*
G03X1857276I-360J-175D01*
G02X1854396I-1440J701D01*
G03X1853676I-360J-175D01*
G37*
G36*
G01X1839505Y20731D02*
G02X1836897Y20443I-1405J769D01*
G03X1836301Y20449I-301J-264D01*
G02X1833901Y20494I-1180J1083D01*
G03X1833291I-305J-259D01*
G02Y22570I-1220J1038D01*
G03X1833901I305J259D01*
G02X1836324Y22589I1220J-1038D01*
G03X1836920Y22583I301J264D01*
G02X1839437Y22382I1180J-1083D01*
G03X1840108Y22387I334J220D01*
G02X1840174Y20781I1181J-756D01*
G03X1839505Y20731I-318J-242D01*
G37*
G36*
G01X755559Y23924D02*
G02X755505Y22420I1155J-794D01*
G03X754830Y22445I-345J-202D01*
G02X754884Y23949I-1155J794D01*
G03X755559Y23924I345J202D01*
G37*
G36*
G01X713670Y24408D02*
G02X713617Y22895I1153J-798D01*
G03X712944Y22918I-344J-204D01*
G02X712997Y24431I-1153J798D01*
G03X713670Y24408I344J204D01*
G37*
G36*
G01X1871884Y25563D02*
G02X1869964Y26249I-1284J-563D01*
G03X1870029Y26921I-181J357D01*
G02X1872259Y26123I2314J2953D01*
G03X1871884Y25563I-8J-400D01*
G37*
G36*
G01X69167Y25215D02*
G02X66831Y25218I-1167J777D01*
G03X66165Y25220I-334J-221D01*
G02X63833Y25223I-1165J780D01*
G03X63167I-333J-222D01*
G02X61027Y24990I-1167J777D01*
G03X60473I-277J-288D01*
G02X58490Y26973I-973J1010D01*
G03Y27527I-288J277D01*
G02X60473Y29510I1010J973D01*
G03X61027I277J288D01*
G02X63167Y29277I973J-1010D01*
G03X63833I333J222D01*
G02X66167I1167J-777D01*
G03X66833I333J222D01*
G02X69167I1167J-777D01*
G03X69833I333J222D01*
G02X72167I1167J-777D01*
G03X72833I333J222D01*
G02X75167I1167J-777D01*
G03X75833I333J222D01*
G02X78043Y29436I1167J-777D01*
G03X78709Y29547I298J267D01*
G02X80777Y27833I1291J-547D01*
G03Y27167I222J-333D01*
G02X78835Y25220I-777J-1167D01*
G03X78169Y25218I-332J-223D01*
G02X75833Y25215I-1169J774D01*
G03X75167I-333J-222D01*
G02X72833I-1167J777D01*
G03X72167I-333J-222D01*
G02X69833I-1167J777D01*
G03X69167I-333J-222D01*
G37*
G36*
G01X1837663Y27859D02*
G02X1837514Y25561I1037J-1221D01*
G03X1836958Y25597I-297J-268D01*
G02X1834661Y25829I-1037J1221D01*
G03X1834031I-315J-247D01*
G02X1831458Y25901I-1260J989D01*
G03X1830798Y25896I-328J-229D01*
G02X1830725Y27563I-1162J784D01*
G03X1831382Y27616I310J252D01*
G02X1834031Y27807I1389J-798D01*
G03X1834661I315J247D01*
G02X1837107Y27895I1260J-989D01*
G03X1837663Y27859I297J268D01*
G37*
G36*
G01X643566Y30162D02*
G02X643831Y32385I-5773J1815D01*
G03X644497Y32113I399J26D01*
G02X644277Y30270I933J-1046D01*
G03X643566Y30162I-329J-228D01*
G37*
G36*
G01X1855356Y35523D02*
G02X1855081Y33888I977J-1005D01*
G03X1854444Y33995I-358J-180D01*
G02X1854719Y35630I-977J1005D01*
G03X1855356Y35523I358J180D01*
G37*
G36*
G01X702098Y36889D02*
G02X700469Y36532I-573J-1279D01*
G03X700331Y37160I-302J263D01*
G02X701960Y37517I573J1279D01*
G03X702098Y36889I302J-263D01*
G37*
G36*
G01X3401Y37588D02*
G02X2221Y36451I199J-1388D01*
G03X1771Y36919I-393J72D01*
G02X2951Y38056I-199J1388D01*
G03X3401Y37588I393J-72D01*
G37*
G36*
G01X1818049Y38126D02*
G02X1816526Y38042I-697J-1217D01*
G03X1816489Y38712I-236J323D01*
G02X1818012Y38796I697J1217D01*
G03X1818049Y38126I236J-323D01*
G37*
G36*
G01X1879863Y38648D02*
G02X1877978Y38508I-866J-1102D01*
G03X1877934Y39098I-291J275D01*
G02X1878027Y41370I866J1102D01*
G03Y42037I-220J334D01*
G02X1879573I773J1170D01*
G03Y41370I220J-333D01*
G02X1879819Y39238I-773J-1169D01*
G03X1879863Y38648I291J-275D01*
G37*
G36*
G01X717821Y39557D02*
G02X715736Y37718I-921J-1057D01*
G03X715097Y37752I-332J-223D01*
G02X712873Y37851I-1074J901D01*
G03X712224Y37862I-328J-228D01*
G02X710054Y39634I-1123J839D01*
G03Y40166I-298J266D01*
G02X712250Y41902I1046J933D01*
G03X712899Y41891I328J228D01*
G02X713154Y42154I1126J-836D01*
G03X713149Y42786I-247J314D01*
G02X713067Y44947I851J1114D01*
G03X712995Y45595I-266J298D01*
G02X714647Y47831I679J1227D01*
G03X715203I278J288D01*
G02X717077Y47896I973J-1009D01*
G03X717615Y47918I257J307D01*
G02X718193Y48263I987J-996D01*
G03X718471Y48718I-115J383D01*
G02X720796Y50005I1379J252D01*
G03X721342Y50011I270J295D01*
G02X723690Y48740I970J-1012D01*
G03X723976Y48280I393J-75D01*
G02X722657Y45894I-373J-1351D01*
G03X722111Y45888I-270J-295D01*
G02X720144Y45914I-970J1012D01*
G03X719580Y45919I-285J-281D01*
G02X717699Y45847I-980J1002D01*
G03X717161Y45825I-257J-307D01*
G02X717105Y45772I-991J991D01*
G03X717222Y45101I265J-299D01*
G02X717628Y42749I-522J-1301D01*
G03X717637Y42141I264J-300D01*
G02X717786Y40126I-895J-1079D01*
G03X717821Y39557I298J-267D01*
G37*
G36*
G01X1825416Y39145D02*
G02X1824999Y40803I-1286J558D01*
G03X1825614Y40958I248J314D01*
G02X1826031Y39300I1286J-558D01*
G03X1825416Y39145I-248J-314D01*
G37*
G36*
G01X1637398Y38350D02*
X1632398D01*
G02X1630896Y39694I0J1512D01*
G03X1630473Y40049I-398J-44D01*
G02X1629531Y40337I-87J1399D01*
G03X1629211Y40150I-122J-159D01*
G02X1629219Y40082I-1497J-211D01*
G01X1629226Y40019D01*
X1629227Y39956D01*
G02Y39911I-1512J-23D01*
G01X1629226Y39910D01*
Y39900D01*
G02X1627725Y38423I-1511J34D01*
G01X1622645Y38389D01*
G02X1622625Y41411I-10J1511D01*
G01X1627704Y41445D01*
G02X1628410Y41277I13J-1512D01*
G03X1628991Y41591I183J355D01*
G02X1631767Y41690I1395J-143D01*
G03X1632211Y41362I394J69D01*
G02X1632398Y41374I190J-1500D01*
G01X1637399D01*
G02X1638910Y39872I-1J-1512D01*
G01Y39777D01*
X1638900Y39693D01*
G02X1637398Y38350I-1502J169D01*
G37*
G36*
G01X1868660Y40718D02*
G02X1867396Y41163I-1041J-939D01*
G03X1867629Y41826I-64J395D01*
G02X1868893Y41381I1041J939D01*
G03X1868660Y40718I64J-395D01*
G37*
G36*
G01X685717Y41085D02*
G02X684243Y41179I-813J-1142D01*
G03X684287Y41858I-188J353D01*
G02X685761Y41764I813J1142D01*
G03X685717Y41085I188J-353D01*
G37*
G36*
G01X1350135Y39522D02*
G02X1350061Y41113I-1190J742D01*
G03X1350718Y41144I318J243D01*
G02X1350792Y39553I1190J-742D01*
G03X1350135Y39522I-318J-243D01*
G37*
G36*
G01X1856584Y40050D02*
G02X1856393Y41790I-1184J751D01*
G03X1857014Y41858I283J282D01*
G02X1859170Y42118I1184J-750D01*
G03X1859745Y42139I277J288D01*
G02X1859814Y40190I1041J-939D01*
G03X1859239Y40169I-277J-288D01*
G02X1857205Y40118I-1041J939D01*
G03X1856584Y40050I-283J-282D01*
G37*
G36*
G01X59973Y42490D02*
G02X58223Y44667I-972J1010D01*
G03Y45333I-222J333D01*
G02Y47667I777J1167D01*
G03Y48333I-222J333D01*
G02X59973Y50510I778J1167D01*
G03X60527I277J288D01*
G02X62667Y50277I973J-1010D01*
G03X63333I333J222D01*
G02X65667I1167J-777D01*
G03X66333I333J222D01*
G02X68667I1167J-777D01*
G03X69333I333J222D01*
G02X71667I1167J-777D01*
G03X72333I333J222D01*
G02X74667I1167J-777D01*
G03X75333I333J222D01*
G02X77667I1167J-777D01*
G03X78333I333J222D01*
G02X80277Y48333I1167J-777D01*
G03Y47667I222J-333D01*
G02Y45333I-777J-1167D01*
G03Y44667I222J-333D01*
G02X78333Y42723I-777J-1167D01*
G03X77667I-333J-222D01*
G02X75333I-1167J777D01*
G03X74667I-333J-222D01*
G02X72333I-1167J777D01*
G03X71667I-333J-222D01*
G02X69333I-1167J777D01*
G03X68667I-333J-222D01*
G02X66333I-1167J777D01*
G03X65667I-333J-222D01*
G02X63333I-1167J777D01*
G03X62667I-333J-222D01*
G02X60527Y42490I-1167J777D01*
G03X59973I-277J-288D01*
G37*
G36*
G01X657040Y43629D02*
G02X655290Y45806I-972J1010D01*
G03Y46472I-222J333D01*
G02X657040Y48649I778J1167D01*
G03X657594I277J288D01*
G02X659344Y46472I972J-1010D01*
G03Y45806I222J-333D01*
G02X657594Y43629I-778J-1167D01*
G03X657040I-277J-288D01*
G37*
G36*
G01X1378856Y46412D02*
G02X1377714Y45162I254J-1379D01*
G03X1377243Y45592I-398J37D01*
G02X1378385Y46842I-254J1379D01*
G03X1378856Y46412I398J-37D01*
G37*
G36*
G01X1019435Y47600D02*
G02X1019429Y46211I1215J-700D01*
G03X1018734Y46214I-348J-196D01*
G02X1018740Y47603I-1215J700D01*
G03X1019435Y47600I348J196D01*
G37*
G36*
G01X1266336Y46199D02*
G02X1266158Y47939I-1179J758D01*
G03X1266780Y48003I285J280D01*
G02X1266958Y46263I1179J-758D01*
G03X1266336Y46199I-285J-280D01*
G37*
G36*
G01X12467Y48308D02*
G02X10328Y48015I-928J-1181D01*
G03X10270Y48551I-323J236D01*
G02X10187Y48631I931J1049D01*
G03X9632Y48653I-289J-277D01*
G02X9713Y50669I-932J1047D01*
G03X10268Y50647I289J277D01*
G02X12303Y50466I932J-1047D01*
G03X12926Y50459I314J247D01*
G02X12773Y48910I1084J-889D01*
G03X12422Y48913I-176J-94D01*
G02X12378Y48840I-1222J687D01*
G03X12467Y48308I336J-217D01*
G37*
G36*
G01X-8844Y50087D02*
G02X-8845Y51712I-1143J812D01*
G03X-8193I326J232D01*
G02X-8192Y50087I1143J-812D01*
G03X-8844I-326J-232D01*
G37*
G36*
G01X114508Y56436D02*
G02X112892Y55842I-426J-1336D01*
G03X112674Y56434I-339J211D01*
G02X114290Y57028I426J1336D01*
G03X114508Y56436I339J-211D01*
G37*
G36*
G01X1393023Y54549D02*
G02X1391273Y56726I-972J1010D01*
G03Y57392I-222J333D01*
G02X1393023Y59569I778J1167D01*
G03X1393577I277J288D01*
G02X1395523I973J-1010D01*
G03X1396077I277J288D01*
G02X1397827Y57392I972J-1010D01*
G03Y56726I222J-333D01*
G02X1396077Y54549I-778J-1167D01*
G03X1395523I-277J-288D01*
G02X1393577I-973J1010D01*
G03X1393023I-277J-288D01*
G37*
G36*
G01X2629Y57596D02*
G02X1052Y57616I-803J-1149D01*
G03X1060Y58277I-221J333D01*
G02X2637Y58257I803J1149D01*
G03X2629Y57596I221J-333D01*
G37*
G36*
G01X81777Y59667D02*
G02X80223I-777J-1167D01*
G03Y60333I-222J333D01*
G02X81777I777J1167D01*
G03Y59667I222J-333D01*
G37*
G36*
G01X-7239Y59518D02*
G02X-9396Y60971I-1371J292D01*
G03X-9343Y61590I-224J331D01*
G02X-9771Y62657I973J1010D01*
G03X-10237Y63068I-400J16D01*
G02X-11672Y63728I-234J1382D01*
G03X-12369Y63708I-343J-206D01*
G02X-12408Y65082I-1241J652D01*
G03X-11711Y65102I343J206D01*
G02X-10689Y65835I1241J-652D01*
G03X-10449Y66492I-62J395D01*
G02X-9171Y66025I1060J918D01*
G03X-9411Y65368I62J-395D01*
G02X-9069Y64393I-1059J-919D01*
G03X-8603Y63982I400J-16D01*
G02X-6972Y62710I233J-1382D01*
G03X-6449Y62362I398J32D01*
G02X-6662Y59789I439J-1332D01*
G03X-7239Y59518I-186J-354D01*
G37*
G36*
G01X381727Y61396D02*
G02X380164Y61350I-747J-1186D01*
G03X380145Y62014I-233J326D01*
G02X381708Y62060I747J1186D01*
G03X381727Y61396I233J-326D01*
G37*
G36*
G01X1875282Y59842D02*
G02X1875079Y61138I-1326J456D01*
G03X1875777Y61248I320J240D01*
G02X1875980Y59952I1326J-456D01*
G03X1875282Y59842I-320J-240D01*
G37*
G36*
G01X314490Y72157D02*
G03X314300Y72357I-200J0D01*
G02Y75157I68J1400D01*
G03X314490Y75357I-10J200D01*
G01Y85792D01*
G03X314300Y85992I-200J0D01*
G02Y88792I68J1400D01*
G03X314490Y88992I-10J200D01*
G01Y91057D01*
G03X314300Y91257I-200J0D01*
G02X315687Y93133I68J1400D01*
G03X316346Y92986I376J136D01*
G01X319140Y95780D01*
G02X319670Y96000I531J-530D01*
G01X358621D01*
X361230Y93390D01*
G02X361311Y93294I-530J-530D01*
G03X361638Y93297I162J116D01*
G02X363887Y93375I1153J-797D01*
G03X364512I313J250D01*
G02X366659Y93427I1095J-875D01*
G03X367259I300J264D01*
G02Y91573I1052J-927D01*
G03X366659I-300J-264D01*
G02X364512Y91625I-1052J927D01*
G03X363887I-312J-250D01*
G02X362059Y91305I-1095J875D01*
G03X361450Y90964I-209J-341D01*
G01Y89204D01*
G03X361980Y88826I400J0D01*
G02X363524Y88383I455J-1326D01*
G03X364145I310J252D01*
G02X366275Y88439I1089J-883D01*
G03X366870I298J267D01*
G02Y86561I1041J-939D01*
G03X366275I-297J-267D01*
G02X364145Y86617I-1041J939D01*
G03X363524I-311J-252D01*
G02X361980Y86174I-1089J883D01*
G03X361450Y85796I-130J-378D01*
G01Y64819D01*
X359840Y63210D01*
G02X359310Y62990I-531J530D01*
G01X316869D01*
X315191Y64668D01*
X315058Y64594D01*
G02X314300Y67214I-691J1220D01*
G03X314490Y67414I-10J200D01*
G01Y72157D01*
G37*
G36*
G01X1007760Y93891D02*
X1007822Y93880D01*
G02X1008953Y92749I-249J-1380D01*
G01X1008964Y92687D01*
X1011020Y90631D01*
Y89191D01*
G03X1011558Y88816I400J0D01*
G02X1013132Y88383I485J-1316D01*
G03X1013753I310J252D01*
G02X1015883Y88439I1089J-883D01*
G03X1016478I298J267D01*
G02Y86561I1041J-939D01*
G03X1015883I-297J-267D01*
G02X1013753Y86617I-1041J939D01*
G03X1013132I-311J-252D01*
G02X1011558Y86184I-1089J883D01*
G03X1011020Y85809I-138J-375D01*
G01Y65200D01*
G02X1010800Y64670I-750J1D01*
G01X1009621Y63490D01*
X970200D01*
G02X969670Y63710I1J750D01*
G01X968437Y64942D01*
X968296Y64806D01*
G02X966313Y66788I-975J1008D01*
G01X966450Y66929D01*
X965490Y67889D01*
Y72341D01*
G03X964843Y72655I-400J0D01*
G02Y74859I-867J1102D01*
G03X965490Y75173I247J314D01*
G01Y85976D01*
G03X964843Y86290I-400J0D01*
G02Y88494I-867J1102D01*
G03X965490Y88808I247J314D01*
G01Y89206D01*
G02X965709Y89736I751J0D01*
G01X965918Y89945D01*
X965921Y90023D01*
G02X967261Y91365I1401J-59D01*
G01X967339Y91368D01*
X969500Y93531D01*
X969510Y93547D01*
G02X969878Y93915I1158J-790D01*
G01X969894Y93925D01*
X970259Y94291D01*
G02X970790Y94511I531J-531D01*
G01X1006794D01*
G02X1007384Y94267I35J-751D01*
G01X1007760Y93891D01*
G37*
G36*
G01X1393350Y64127D02*
G02X1391442Y66175I-1011J971D01*
G03X1391400Y66821I-256J308D01*
G02X1393262Y68858I749J1185D01*
G03X1393906Y68870I318J243D01*
G02X1396023Y69069I1144J-811D01*
G03X1396577I277J288D01*
G02X1398345Y66904I972J-1011D01*
G03X1398342Y66247I227J-330D01*
G02X1396528Y64127I-802J-1149D01*
G03X1395950I-289J-277D01*
G02X1393928I-1011J971D01*
G03X1393350I-289J-277D01*
G37*
G36*
G01X656573Y65090D02*
G02X654823Y67267I-972J1010D01*
G03Y67933I-222J333D01*
G02X656573Y70110I778J1167D01*
G03X657127I277J288D01*
G02X658877Y67933I972J-1010D01*
G03Y67267I222J-333D01*
G02X657127Y65090I-778J-1167D01*
G03X656573I-277J-288D01*
G37*
G36*
G01X1665360Y70935D02*
G02X1663340I-1010J-973D01*
G03Y71489I-288J277D01*
G02X1663233Y71615I1013J969D01*
G03X1662885Y71561I-159J-121D01*
G02X1661123Y70697I-1322J467D01*
G03X1660598Y70311I-125J-380D01*
G02X1659636Y71622I-1402J-20D01*
G03X1660161Y72008I125J380D01*
G02X1660178Y72245I1402J19D01*
G03X1659870Y72443I-198J31D01*
G02X1658127Y72604I-771J1171D01*
G03X1657573I-277J-288D01*
G02Y74624I-973J1010D01*
G03X1658127I277J288D01*
G02X1660500Y73684I973J-1010D01*
G03X1661047Y73332I399J20D01*
G02X1662513Y73059I516J-1304D01*
G03X1663132Y73155I271J294D01*
G02X1665360Y71489I1219J-693D01*
G03Y70935I288J-277D01*
G37*
G36*
G01X1767991Y71341D02*
G02X1767899Y69490I1259J-990D01*
G03X1767268Y69547I-338J-215D01*
G02X1767358Y71346I-1028J953D01*
G03X1767991Y71341I318J242D01*
G37*
G36*
G01X1931270Y69302D02*
G02X1928934Y71490I-1119J1146D01*
G03X1928897Y72050I-303J261D01*
G02X1928674Y72293I1062J1199D01*
G03X1928028Y72288I-321J-239D01*
G02X1927949Y74025I-1138J819D01*
G03X1928592Y74080I301J263D01*
G02X1931043Y74429I1369J-833D01*
G03X1931596Y74441I270J295D01*
G02X1933807Y74496I1134J-1131D01*
G03X1934331Y74483I269J296D01*
G02X1934965Y74802I1019J-1236D01*
G03X1935236Y75350I-96J388D01*
G02X1937806Y77151I1470J637D01*
G03X1938359Y77154I275J291D01*
G02X1940623Y77112I1111J-1154D01*
G03X1941207Y77120I288J277D01*
G02X1943433Y77256I1183J-1080D01*
G03X1943959Y77260I261J303D01*
G02X1946524Y75509I1061J-1200D01*
G03X1946790Y74987I376J-137D01*
G02X1947390Y74665I-440J-1540D01*
G03X1947910Y74666I259J304D01*
G02X1947911Y72230I1041J-1218D01*
G03X1947391Y72229I-259J-304D01*
G02X1945271Y72263I-1041J1218D01*
G03X1944711Y72243I-270J-295D01*
G02X1944641Y72174I-1159J1106D01*
G03X1944663Y71863I136J-147D01*
G02X1942630Y69402I-913J-1316D01*
G03X1942070I-280J-286D01*
G02X1939871Y69363I-1120J1145D01*
G03X1939311Y69343I-270J-295D01*
G02X1937110Y69229I-1161J1104D01*
G03X1936590I-260J-304D01*
G02X1934510I-1040J1218D01*
G03X1933990I-260J-304D01*
G02X1931830Y69302I-1040J1218D01*
G03X1931270I-280J-286D01*
G37*
G36*
G01X1613948Y71562D02*
G02X1613859Y70164I1167J-776D01*
G03X1613167Y70208I-359J-178D01*
G02X1613256Y71606I-1167J776D01*
G03X1613948Y71562I359J178D01*
G37*
G36*
G01X1585945Y70110D02*
G02X1585874Y71675I-1197J730D01*
G03X1586537Y71704I322J238D01*
G02X1586608Y70139I1197J-730D01*
G03X1585945Y70110I-322J-238D01*
G37*
G36*
G01X650973Y71290D02*
G02X649223Y73467I-972J1010D01*
G03Y74133I-222J333D01*
G02X650973Y76310I778J1167D01*
G03X651527I277J288D01*
G02X653277Y74133I972J-1010D01*
G03Y73467I222J-333D01*
G02X651527Y71290I-778J-1167D01*
G03X650973I-277J-288D01*
G37*
G36*
G01X657473D02*
G02X655723Y73467I-972J1010D01*
G03Y74133I-222J333D01*
G02X657473Y76310I778J1167D01*
G03X658027I277J288D01*
G02X659777Y74133I972J-1010D01*
G03Y73467I222J-333D01*
G02X658027Y71290I-778J-1167D01*
G03X657473I-277J-288D01*
G37*
G36*
G01X1592905Y76213D02*
G02X1590493Y74840I-1305J-513D01*
G03X1589907Y74890I-316J-245D01*
G02X1590069Y76786I-945J1036D01*
G03X1590655Y76736I316J245D01*
G02X1591385Y77085I944J-1037D01*
G03X1591695Y77627I-62J395D01*
G02X1593215Y76755I1305J513D01*
G03X1592905Y76213I62J-395D01*
G37*
G36*
G01X80403Y77220D02*
G02X78872Y77105I-678J-1227D01*
G03X78822Y77773I-243J318D01*
G02X78723Y80167I678J1227D01*
G03Y80833I-222J333D01*
G02X80277I777J1167D01*
G03Y80167I222J-333D01*
G02X80353Y77888I-777J-1167D01*
G03X80403Y77220I243J-318D01*
G37*
G36*
G01X1408457Y76508D02*
G02X1406582Y78504I-1157J792D01*
G03X1406729Y79037I-205J343D01*
G02X1406651Y79208I1234J666D01*
G03X1406277I-187J-70D01*
G02X1403617Y80088I-1313J492D01*
G03X1403239Y80598I-385J110D01*
G02X1404431Y82777I25J1402D01*
G03X1405097I333J222D01*
G02X1407431I1167J-777D01*
G03X1408097I333J222D01*
G02X1409588Y80636I1167J-777D01*
G03X1409300Y80126I93J-389D01*
G02X1408682Y78496I-1336J-426D01*
G03X1408535Y77963I205J-343D01*
G02X1408549Y77938I-1216J-697D01*
G03X1408911Y77950I178J91D01*
G02X1409100Y76530I1289J-551D01*
G03X1408457Y76508I-313J-248D01*
G37*
G36*
G01X6314Y78585D02*
G02X4763Y78637I-815J-1141D01*
G03X4786Y79303I-210J341D01*
G02X6337Y79251I815J1141D01*
G03X6314Y78585I210J-341D01*
G37*
G36*
G01X96484Y77755D02*
G02X93632Y77689I-1443J696D01*
G03X92932Y77695I-352J-191D01*
G02X92945Y79243I-1396J786D01*
G03X93645Y79237I352J191D01*
G02X96472Y79171I1396J-786D01*
G03X97190Y79177I358J179D01*
G02X97202Y77761I1443J-696D01*
G03X96484Y77755I-358J-179D01*
G37*
G36*
G01X764202Y79450D02*
G02X762559Y79422I-802J-1150D01*
G03X762548Y80070I-240J320D01*
G02X764191Y80098I802J1150D01*
G03X764202Y79450I240J-320D01*
G37*
G36*
G01X12726Y79724D02*
G02X10804Y79558I-862J-1230D01*
G03X10767Y80158I-282J284D01*
G02X10652Y80257I856J1111D01*
G03X10098I-277J-288D01*
G02X8520Y82532I-972J1010D01*
G03X8543Y83242I-172J361D01*
G02X8187Y83524I681J1226D01*
G03X7583Y83509I-296J-269D01*
G02X7538Y85343I-1083J891D01*
G03X8142Y85358I296J269D01*
G02X10198Y85477I1083J-891D01*
G03X10752I277J288D01*
G02X12330Y83202I972J-1010D01*
G03X12307Y82492I172J-361D01*
G02X12660Y80321I-682J-1225D01*
G03X12726Y79724I295J-269D01*
G37*
G36*
G01X1518409Y78143D02*
G02X1518368Y79500I-1247J641D01*
G03X1519067Y79521I344J204D01*
G02X1519077Y79539I1230J-672D01*
G03X1518914Y80079I-353J188D01*
G02X1520817Y80654I666J1234D01*
G03X1520980Y80114I353J-188D01*
G02X1519108Y78164I-666J-1234D01*
G03X1518409Y78143I-344J-204D01*
G37*
G36*
G01X-10313Y78490D02*
G02X-12501Y78378I-1139J818D01*
G03X-13089Y78389I-299J-266D01*
G02X-15075Y78348I-1013J969D01*
G03X-15629I-277J-288D01*
G02X-17612Y80331I-973J1010D01*
G03Y80885I-288J277D01*
G02X-15629Y82868I1010J973D01*
G03X-15075I277J288D01*
G02X-13053Y82788I973J-1010D01*
G03X-12465Y82777I299J266D01*
G02X-10342Y82665I1013J-969D01*
G03X-9701Y82676I316J244D01*
G02X-9678Y82707I1137J-820D01*
G03X-9733Y83251I-318J243D01*
G02X-7669Y85121I922J1057D01*
G03X-7026Y85109I326J232D01*
G02X-4846Y83347I1114J-852D01*
G03X-4835Y82814I304J-260D01*
G02X-4878Y80857I-1025J-956D01*
G03X-4894Y80302I280J-286D01*
G02X-6954Y78400I-1036J-944D01*
G03X-7538I-292J-273D01*
G02X-9672Y78501I-1024J958D01*
G03X-10313Y78490I-316J-244D01*
G37*
G36*
G01X733908Y81859D02*
G02X733868Y83450I-1174J766D01*
G03X734526Y83467I323J236D01*
G02X734566Y81876I1174J-766D01*
G03X733908Y81859I-323J-236D01*
G37*
G36*
G01X99998Y84565D02*
G02X98747Y83325I142J-1395D01*
G03X98122Y83698I-398J44D01*
G02X99631Y85193I-3439J4980D01*
G03X99998Y84565I327J-230D01*
G37*
G36*
G01X1574210Y83318D02*
G02X1574165Y84982I-1150J802D01*
G03X1574809Y85000I315J246D01*
G02X1574854Y83336I1150J-802D01*
G03X1574210Y83318I-315J-246D01*
G37*
G36*
G01X648982Y84439D02*
G02X646223Y84462I-1382J-239D01*
G03X645912Y84928I-393J74D01*
G02X645190Y87273I288J1372D01*
G03Y87827I-288J277D01*
G02X647367Y89577I1010J972D01*
G03X648033I333J222D01*
G02X648721Y90117I1166J-778D01*
G03X648943Y90668I-137J376D01*
G02X648914Y90733I1266J604D01*
G03X648270Y90866I-368J-157D01*
G02X646161Y91070I-966J1016D01*
G03X645628Y91181I-326J-231D01*
G02X646047Y93194I-724J1201D01*
G03X646580Y93083I326J231D01*
G02X648594Y92431I724J-1201D01*
G03X649238Y92298I368J157D01*
G02X651486Y91850I966J-1016D01*
G03X652063Y91672I366J162D01*
G02X651522Y89914I741J-1190D01*
G03X650945Y90092I-366J-162D01*
G02X650683Y89965I-739J1191D01*
G03X650461Y89414I137J-376D01*
G02X650210Y87827I-1261J-614D01*
G03Y87273I288J-277D01*
G02X649337Y84905I-1010J-973D01*
G03X648982Y84439I39J-398D01*
G37*
G36*
G01X1318622Y84134D02*
G02X1316250Y85529I-1322J466D01*
G03X1316227Y86084I-299J266D01*
G02X1316228Y88114I968J1015D01*
G03X1316252Y88669I-275J290D01*
G02X1318267Y88584I1049J931D01*
G03X1318243Y88029I275J-290D01*
G02X1318245Y86169I-1048J-931D01*
G03X1318268Y85614I299J-266D01*
G02X1318278Y85605I-933J-1047D01*
G03X1318615Y85717I140J143D01*
G02X1319222Y84334I1385J-217D01*
G03X1318622Y84134I-222J-333D01*
G37*
G36*
G01X768798Y85914D02*
G02X768120Y84453I702J-1214D01*
G03X767526Y84729I-394J-70D01*
G02X765913Y84877I-702J1214D01*
G03X765271Y84690I-260J-304D01*
G02X764841Y86166I-1341J410D01*
G03X765483Y86353I260J304D01*
G02X768204Y86190I1341J-410D01*
G03X768798Y85914I394J70D01*
G37*
G36*
G01X1758640Y84149D02*
G02X1758460Y85705I-1245J644D01*
G03X1759119Y85781I304J260D01*
G02X1759299Y84225I1245J-644D01*
G03X1758640Y84149I-304J-260D01*
G37*
G36*
G01X714182Y87090D02*
G02X712274Y86956I-882J-1090D01*
G03X712233Y87539I-293J272D01*
G02X714330Y89329I882J1090D01*
G03X715030Y89341I347J199D01*
G02X715053Y87983I1238J-658D01*
G03X714353Y87971I-347J-199D01*
G02X714141Y87673I-1239J657D01*
G03X714182Y87090I293J-272D01*
G37*
G36*
G01X707312Y87073D02*
G02X704606Y86976I-1340J-413D01*
G03X704134Y87458I-389J91D01*
G02X705211Y88514I-289J1372D01*
G03X705683Y88032I389J-91D01*
G02X705688Y88033I277J-1374D01*
G03X705989Y88542I-81J392D01*
G02X707613Y87582I1340J413D01*
G03X707312Y87073I81J-392D01*
G37*
G36*
G01X1676511Y87846D02*
G02X1676437Y86108I1062J-916D01*
G03X1675811Y86134I-323J-235D01*
G02X1675885Y87872I-1062J916D01*
G03X1676511Y87846I323J235D01*
G37*
G36*
G01X7750Y87098D02*
G02X7648Y88832I-1150J802D01*
G03X8275Y88869I299J265D01*
G02X10398Y89077I1150J-802D01*
G03X10952I277J288D01*
G02Y87057I973J-1010D01*
G03X10398I-277J-288D01*
G02X8377Y87135I-973J1010D01*
G03X7750Y87098I-299J-265D01*
G37*
G36*
G01X1312558Y92415D02*
G02X1310554Y92409I-999J-984D01*
G03X1310552Y92968I-287J278D01*
G02X1310472Y93057I1002J981D01*
G03X1310152Y93039I-153J-128D01*
G02X1308161Y94950I-1168J775D01*
G03X1308159Y95600I-234J324D01*
G02X1309794Y95606I813J1142D01*
G03X1309796Y94956I234J-324D01*
G02X1309929Y94848I-815J-1140D01*
G03X1310499Y94879I270J295D01*
G02X1312556Y92974I1052J-927D01*
G03X1312558Y92415I287J-278D01*
G37*
G36*
G01X1377332Y92806D02*
G02X1377230Y91313I1132J-827D01*
G03X1376554Y91358I-352J-190D01*
G02X1376656Y92853I-1142J829D01*
G03X1377332Y92806I353J189D01*
G37*
G36*
G01X1455416Y93465D02*
G02X1454081Y92667I-69J-1400D01*
G03X1453740Y93239I-361J172D01*
G02X1455075Y94037I69J1400D01*
G03X1455416Y93465I361J-172D01*
G37*
G36*
G01X692056Y93537D02*
G02X691687Y92008I944J-1037D01*
G03X691044Y92163I-374J-141D01*
G02X691413Y93692I-944J1037D01*
G03X692056Y93537I374J141D01*
G37*
G36*
G01X1013495Y91625D02*
G02Y93375I-1095J875D01*
G03X1014120I312J250D01*
G02X1016267Y93427I1095J-875D01*
G03X1016867I300J264D01*
G02Y91573I1052J-927D01*
G03X1016267I-300J-264D01*
G02X1014120Y91625I-1052J927D01*
G03X1013495I-313J-250D01*
G37*
G36*
G01X110302Y92129D02*
G02X110107Y93703I-1245J645D01*
G03X110762Y93784I300J265D01*
G02X110957Y92210I1245J-645D01*
G03X110302Y92129I-300J-265D01*
G37*
G36*
G01X733219Y93291D02*
G02X732024Y94187I-1309J-501D01*
G03X732431Y94729I33J399D01*
G02X733626Y93833I1309J501D01*
G03X733219Y93291I-33J-399D01*
G37*
G36*
G01X1296358Y95487D02*
G02X1294804I-777J-1167D01*
G03Y96153I-222J333D01*
G02X1296358I777J1167D01*
G03Y95487I222J-333D01*
G37*
G36*
G01X1693483Y93884D02*
G02X1693432Y95418I-1198J728D01*
G03X1694102Y95440I328J229D01*
G02X1696313Y95681I1198J-728D01*
G03X1696868Y95659I289J277D01*
G02X1696787Y93643I932J-1047D01*
G03X1696232Y93665I-289J-277D01*
G02X1694153Y93906I-932J1047D01*
G03X1693483Y93884I-328J-229D01*
G37*
G36*
G01X1363012Y95261D02*
G02X1360588Y96453I-1378J258D01*
G03Y96985I-298J266D01*
G02X1362680I1046J934D01*
G03Y96453I298J-266D01*
G02X1362959Y95976I-1047J-932D01*
G03X1363342Y96091I189J64D01*
G02X1363693Y95465I1358J350D01*
G03X1363012Y95261I-288J-278D01*
G37*
G36*
G01X1573433Y96756D02*
G02X1571776Y96784I-848J-1117D01*
G03X1571787Y97429I-231J327D01*
G02X1573444Y97401I848J1117D01*
G03X1573433Y96756I231J-327D01*
G37*
G36*
G01X1746712Y97034D02*
G02X1745151Y95238I-221J-1384D01*
G03X1744487Y95404I-382J-118D01*
G02X1743575Y97800I-987J996D01*
G03X1743989Y98277I22J399D01*
G02X1746462Y97678I1375J273D01*
G03X1746712Y97034I313J-249D01*
G37*
G36*
G01X1289548Y96543D02*
G02Y98097I-1167J777D01*
G03X1290214I333J222D01*
G02Y96543I1167J-777D01*
G03X1289548I-333J-222D01*
G37*
G36*
G01X1945567Y98870D02*
G02X1945553Y97453I1203J-720D01*
G03X1944863Y97460I-347J-199D01*
G02X1944877Y98877I-1203J720D01*
G03X1945567Y98870I347J199D01*
G37*
G36*
G01X1723995Y99775D02*
G02X1722633I-681J-1225D01*
G03Y100475I-194J350D01*
G02Y102925I681J1225D01*
G03Y103625I-194J350D01*
G02X1722089Y104169I681J1225D01*
G03X1721389I-350J-194D01*
G02X1718939I-1225J681D01*
G03X1718239I-350J-194D01*
G02Y105531I-1225J681D01*
G03X1718939I350J194D01*
G02X1719483Y106075I1225J-681D01*
G03Y106775I-194J350D01*
G02X1721389Y108681I681J1225D01*
G03X1722089I350J194D01*
G02X1723995Y106775I1225J-681D01*
G03Y106075I194J-350D01*
G02Y103625I-681J-1225D01*
G03Y102925I194J-350D01*
G02Y100475I-681J-1225D01*
G03Y99775I194J-350D01*
G37*
G36*
G01X1736595Y102925D02*
G02X1735233I-681J-1225D01*
G03Y103625I-194J350D01*
G02Y106075I681J1225D01*
G03Y106775I-194J350D01*
G02X1736595I681J1225D01*
G03Y106075I194J-350D01*
G02Y103625I-681J-1225D01*
G03Y102925I194J-350D01*
G37*
G36*
G01X1269667Y101323D02*
G02X1267570Y103149I-1167J777D01*
G03X1267592Y103726I-266J299D01*
G02X1269724Y105538I1008J975D01*
G03X1270366I321J239D01*
G02X1272465Y103692I1124J-839D01*
G03X1272467Y103115I278J-288D01*
G02X1270333Y101323I-967J-1015D01*
G03X1269667I-333J-222D01*
G37*
G36*
G01X1875618Y103538D02*
G02X1874255Y104598I-1360J-342D01*
G03X1874641Y105096I-2J400D01*
G02X1876004Y104036I1360J342D01*
G03X1875618Y103538I2J-400D01*
G37*
G36*
G01X74915Y103760D02*
G02Y106240I-2115J1240D01*
G03X75606I346J202D01*
G02X79837Y106239I2115J-1240D01*
G03X80527I345J202D01*
G02X84758Y106240I2116J-1239D01*
G03X85449I345J202D01*
G02X89679I2115J-1240D01*
G03X90370I346J202D01*
G02X94600I2115J-1240D01*
G03X95291I345J202D01*
G02X99522Y106239I2115J-1240D01*
G03X100212I345J202D01*
G02X104443Y106240I2116J-1239D01*
G03X105134I345J202D01*
G02Y103760I2115J-1240D01*
G03X104443I-345J-202D01*
G02X100212Y103761I-2115J1240D01*
G03X99522I-345J-202D01*
G02X95291Y103760I-2116J1239D01*
G03X94600I-345J-202D01*
G02X90370I-2115J1240D01*
G03X89679I-345J-202D01*
G02X85449I-2115J1240D01*
G03X84758I-345J-202D01*
G02X80527Y103761I-2115J1240D01*
G03X79837I-345J-202D01*
G02X75606Y103760I-2116J1239D01*
G03X74915I-345J-202D01*
G37*
G36*
G01X1345919Y105559D02*
G02X1344470Y105798I-919J-1059D01*
G03X1344581Y106470I-151J370D01*
G02X1346030Y106231I919J1059D01*
G03X1345919Y105559I151J-370D01*
G37*
G36*
G01X121118Y107644D02*
G02X119537Y107824I-921J-1057D01*
G03X119612Y108478I-188J353D01*
G02X121193Y108298I921J1057D01*
G03X121118Y107644I188J-353D01*
G37*
G36*
G01X1392517Y107705D02*
G02X1392488Y109327I-1158J791D01*
G03X1393140Y109339I322J237D01*
G02X1393502Y109702I1157J-792D01*
G03X1393504Y110359I-227J329D01*
G02X1395106Y110352I806J1147D01*
G03X1395104Y109695I227J-329D01*
G02X1393169Y107717I-806J-1147D01*
G03X1392517Y107705I-322J-237D01*
G37*
G36*
G01X1452447Y110885D02*
G02X1451038Y110235I-215J-1385D01*
G03X1450758Y110840I-341J210D01*
G02X1452167Y111490I215J1385D01*
G03X1452447Y110885I341J-210D01*
G37*
G36*
G01X1512424Y120143D02*
G02X1515446Y120153I1511J0D01*
G01Y116258D01*
X1515437Y116174D01*
G02X1514779Y115089I-1502J169D01*
G03X1514753Y114445I224J-332D01*
G02X1513046Y114477I-874J-1096D01*
G03X1513044Y115122I-237J322D01*
G02X1512424Y116343I892J1221D01*
G01Y120143D01*
G37*
G36*
G01X1258565Y115056D02*
G02X1257135I-715J-1206D01*
G03Y115744I-204J344D01*
G02X1258565I715J1206D01*
G03Y115056I204J-344D01*
G37*
G36*
G01X619388Y115330D02*
G02X618655Y114188I666J-1234D01*
G03X618066Y114566I-399J26D01*
G02X618799Y115708I-666J1234D01*
G03X619388Y115330I399J-26D01*
G37*
G36*
G01X1286893Y117099D02*
G02X1285339I-777J-1167D01*
G03Y117765I-222J333D01*
G02X1286893I777J1167D01*
G03Y117099I222J-333D01*
G37*
G36*
G01X1398444Y117893D02*
G02X1397340Y117114I156J-1393D01*
G03X1396936Y117687I-360J175D01*
G02X1398040Y118466I-156J1393D01*
G03X1398444Y117893I360J-175D01*
G37*
G36*
G01X1727145Y118675D02*
G02X1725783I-681J-1225D01*
G03Y119375I-194J350D01*
G02X1725238Y119919I680J1226D01*
G03X1724539I-350J-194D01*
G02X1722632Y121826I-1225J682D01*
G03Y122525I-194J350D01*
G02X1722089Y123069I683J1224D01*
G03X1721389I-350J-194D01*
G02Y124431I-1225J681D01*
G03X1722089I350J194D01*
G02X1722633Y124975I1225J-681D01*
G03Y125675I-194J350D01*
G02Y128125I681J1225D01*
G03Y128825I-194J350D01*
G02Y131275I681J1225D01*
G03Y131975I-194J350D01*
G02X1724539Y133881I681J1225D01*
G03X1725239I350J194D01*
G02Y132519I1225J-681D01*
G03X1724539I-350J-194D01*
G02X1723995Y131975I-1225J681D01*
G03Y131275I194J-350D01*
G02Y128825I-681J-1225D01*
G03Y128125I194J-350D01*
G02Y125675I-681J-1225D01*
G03Y124975I194J-350D01*
G02X1724539Y124431I-681J-1225D01*
G03X1725239I350J194D01*
G02X1727145Y122525I1225J-681D01*
G03Y121825I194J-350D01*
G02Y119375I-681J-1225D01*
G03Y118675I194J-350D01*
G37*
G36*
G01X1737139Y116769D02*
G02Y118131I-1225J681D01*
G03X1737839I350J194D01*
G02X1738383Y118675I1225J-681D01*
G03Y119375I-194J350D01*
G02Y121825I681J1225D01*
G03Y122525I-194J350D01*
G02X1737838Y123070I681J1226D01*
G03X1737138I-350J-194D01*
G02Y124430I-1226J680D01*
G03X1737838I350J194D01*
G02X1738383Y124975I1226J-681D01*
G03Y125675I-194J350D01*
G02Y128125I681J1225D01*
G03Y128825I-194J350D01*
G02X1740289Y130731I681J1225D01*
G03X1740989I350J194D01*
G02Y129369I1225J-681D01*
G03X1740289I-350J-194D01*
G02X1739745Y128825I-1225J681D01*
G03Y128125I194J-350D01*
G02Y125675I-681J-1225D01*
G03Y124975I194J-350D01*
G02X1740289Y124431I-681J-1225D01*
G03X1740989I350J194D01*
G02X1743439I1225J-681D01*
G03X1744139I350J194D01*
G02Y123069I1225J-681D01*
G03X1743439I-350J-194D01*
G02X1742895Y122525I-1225J681D01*
G03Y121825I194J-350D01*
G02X1740989Y119919I-681J-1225D01*
G03X1740289I-350J-194D01*
G02X1739745Y119375I-1225J681D01*
G03Y118675I194J-350D01*
G02X1737839Y116769I-681J-1225D01*
G03X1737139I-350J-194D01*
G37*
G36*
G01X1677567Y121263D02*
G02X1676205I-681J-1225D01*
G03Y121963I-194J350D01*
G02X1677567I681J1225D01*
G03Y121263I194J-350D01*
G37*
G36*
G01X1554838Y121420D02*
G02X1554273Y122169I-1337J-421D01*
G03X1554545Y122454I111J167D01*
G02X1554398Y122705I1130J830D01*
G03X1553883Y122911I-364J-164D01*
G02X1554631Y124787I-530J1298D01*
G03X1555146Y124581I364J164D01*
G02X1556219Y124576I530J-1298D01*
G03X1556757Y124830I155J369D01*
G02X1557557Y123134I1343J-403D01*
G03X1557019Y122880I-155J-369D01*
G02X1555321Y121927I-1343J403D01*
G03X1554838Y121420I-102J-387D01*
G37*
G36*
G01X1928184Y121747D02*
G02X1926314Y122480I-1292J-544D01*
G03X1926518Y123000I-165J365D01*
G02X1926888Y124600I1292J544D01*
G03X1926912Y125180I-263J301D01*
G02X1927962Y127557I1006J976D01*
G03X1928366Y128041I13J400D01*
G02X1928815Y129394I1370J296D01*
G03X1928820Y129994I-262J302D01*
G02X1930677Y129980I936J1043D01*
G03X1930672Y129380I262J-302D01*
G02X1929692Y126936I-936J-1043D01*
G03X1929288Y126452I-13J-400D01*
G02X1928840Y125100I-1370J-296D01*
G03X1928816Y124520I263J-301D01*
G02X1928388Y122267I-1006J-976D01*
G03X1928184Y121747I165J-365D01*
G37*
G36*
G01X1401422Y122341D02*
G02X1399879Y122837I-1122J-841D01*
G03X1400078Y123459I-121J381D01*
G02X1399817Y124532I1122J841D01*
G03X1399418Y124998I-394J66D01*
G02X1400783Y126168I-18J1402D01*
G03X1401182Y125702I394J-66D01*
G02X1401621Y122963I18J-1402D01*
G03X1401422Y122341I121J-381D01*
G37*
G36*
G01X1392867Y122173D02*
G02X1390923Y124117I-1167J777D01*
G03Y124783I-222J333D01*
G02Y127117I777J1167D01*
G03Y127783I-222J333D01*
G02X1392867Y129727I777J1167D01*
G03X1393533I333J222D01*
G02X1395477Y127783I1167J-777D01*
G03Y127117I222J-333D01*
G02Y124783I-777J-1167D01*
G03Y124117I222J-333D01*
G02X1393533Y122173I-777J-1167D01*
G03X1392867I-333J-222D01*
G37*
G36*
G01X1525319Y122826D02*
G02X1524803Y124449I-1319J474D01*
G03X1525409Y124642I229J328D01*
G02X1525925Y123019I1319J-474D01*
G03X1525319Y122826I-229J-328D01*
G37*
G36*
G01X3938Y126754D02*
G03X5205Y127157I-2J2199D01*
G02X9264Y125823I1488J-2314D01*
G03X10004Y125805I374J143D01*
G02Y123881I2201J-962D01*
G03X9264Y123863I-366J-161D01*
G02X5221Y122519I-2571J980D01*
G03X3967Y122932I-1283J-1786D01*
G01X3936D01*
G03X2669Y122529I2J-2199D01*
G02X2653Y127167I-1488J2314D01*
G03X3907Y126754I1283J1786D01*
G01X3938D01*
G37*
G36*
G01X1864351Y125131D02*
G02X1864331Y123808I1226J-680D01*
G03X1863626Y123819I-355J-183D01*
G02X1863646Y125142I-1226J680D01*
G03X1864351Y125131I355J183D01*
G37*
G36*
G01X1643312Y124259D02*
G02Y125621I-1225J681D01*
G03X1644012I350J194D01*
G02Y124259I1225J-681D01*
G03X1643312I-350J-194D01*
G37*
G36*
G01X1857797Y127786D02*
G02X1856243I-777J-1167D01*
G03Y128452I-222J333D01*
G02X1857797I777J1167D01*
G03Y127786I222J-333D01*
G37*
G36*
G01X1513634Y127666D02*
G02X1513388Y125945I966J-1016D01*
G03X1512766Y126034I-346J-201D01*
G02X1513012Y127755I-966J1016D01*
G03X1513634Y127666I346J201D01*
G37*
G36*
G01X1473905Y130098D02*
G02X1472295I-805J-1148D01*
G03Y130752I-230J327D01*
G02X1473905I805J1148D01*
G03Y130098I230J-327D01*
G37*
G36*
G01X1678067Y130863D02*
G02X1676705I-681J-1225D01*
G03Y131563I-194J350D01*
G02X1678067I681J1225D01*
G03Y130863I194J-350D01*
G37*
G36*
G01X1861800Y131977D02*
G02X1860194Y131952I-785J-1162D01*
G03X1860184Y132607I-234J324D01*
G02X1859998Y134780I785J1162D01*
G03Y135358I-277J289D01*
G02X1861940I971J1011D01*
G03Y134780I277J-289D01*
G02X1861790Y132632I-971J-1011D01*
G03X1861800Y131977I234J-324D01*
G37*
G36*
G01X1608070Y132487D02*
G02X1606565Y132587I-831J-1129D01*
G03X1606610Y133260I-192J351D01*
G02X1606216Y133707I831J1129D01*
G03X1605517I-349J-195D01*
G02X1603611Y135613I-1225J681D01*
G03Y136313I-194J350D01*
G02X1605517Y138220I681J1225D01*
G03X1606216I350J194D01*
G02X1608666Y138219I1225J-682D01*
G03X1609366I350J194D01*
G02X1609910Y138763I1225J-681D01*
G03Y139463I-194J350D01*
G02X1609894Y141905I681J1226D01*
G03X1609906Y142592I-199J347D01*
G02X1611342Y142566I740J1191D01*
G03X1611330Y141879I199J-347D01*
G02X1611816Y141369I-739J-1191D01*
G03X1612516I350J194D01*
G02X1614422Y139463I1225J-681D01*
G03Y138763I194J-350D01*
G02X1614423Y136313I-681J-1225D01*
G03Y135614I194J-350D01*
G02X1612516Y133708I-682J-1225D01*
G03X1611816I-350J-194D01*
G02X1609366I-1225J681D01*
G03X1608666I-350J-194D01*
G02X1608115Y133160I-1225J681D01*
G03X1608070Y132487I192J-351D01*
G37*
G36*
G01X1746868Y132851D02*
G02X1745510I-679J-1227D01*
G03Y133550I-194J350D01*
G02X1746868I679J1227D01*
G03Y132851I194J-350D01*
G37*
G36*
G01X1531353Y133302D02*
G02X1530076Y134073I-1252J-631D01*
G03X1530426Y134653I-7J400D01*
G02X1530308Y135583I1252J631D01*
G03X1529813Y136054I-391J85D01*
G02X1530819Y137109I-364J1354D01*
G03X1531314Y136638I391J-85D01*
G02X1531703Y133882I364J-1354D01*
G03X1531353Y133302I7J-400D01*
G37*
G36*
G01X1324193Y132546D02*
G02Y134100I-1167J777D01*
G03X1324859I333J222D01*
G02Y132546I1167J-777D01*
G03X1324193I-333J-222D01*
G37*
G36*
G01X1262697Y134362D02*
G02X1262517Y132923I1101J-868D01*
G03X1261838Y133008I-365J-163D01*
G02X1262018Y134447I-1101J868D01*
G03X1262697Y134362I365J163D01*
G37*
G36*
G01X1621265Y133707D02*
G02Y135069I-1225J681D01*
G03X1621965I350J194D01*
G02Y133707I1225J-681D01*
G03X1621265I-350J-194D01*
G37*
G36*
G01X1590927Y135783D02*
G02X1588569Y134355I-1047J-932D01*
G03X1588067Y134592I-374J-142D01*
G02X1588931Y136417I-447J1329D01*
G03X1589433Y136180I374J142D01*
G02X1589549Y136213I441J-1331D01*
G03X1589753Y136868I-95J389D01*
G02X1591850Y138729I1047J932D01*
G03X1592450I300J265D01*
G02Y136871I1050J-929D01*
G03X1591850I-300J-265D01*
G02X1591131Y136438I-1050J929D01*
G03X1590927Y135783I95J-389D01*
G37*
G36*
G01X1695917Y137013D02*
G02X1694555I-681J-1225D01*
G03Y137713I-194J350D01*
G02X1695917I681J1225D01*
G03Y137013I194J-350D01*
G37*
G36*
G01X1739745Y137575D02*
G02X1738383I-681J-1225D01*
G03Y138275I-194J350D01*
G02X1737839Y138819I681J1225D01*
G03X1737139I-350J-194D01*
G02Y140181I-1225J681D01*
G03X1737839I350J194D01*
G02X1738383Y140725I1225J-681D01*
G03Y141425I-194J350D01*
G02Y143875I681J1225D01*
G03Y144575I-194J350D01*
G02X1740289Y146481I681J1225D01*
G03X1740989I350J194D01*
G02X1742895Y144575I1225J-681D01*
G03Y143875I194J-350D01*
G02X1743439Y143331I-681J-1225D01*
G03X1744139I350J194D01*
G02Y141969I1225J-681D01*
G03X1743439I-350J-194D01*
G02X1740989I-1225J681D01*
G03X1740289I-350J-194D01*
G02X1739745Y141425I-1225J681D01*
G03Y140725I194J-350D01*
G02Y138275I-681J-1225D01*
G03Y137575I194J-350D01*
G37*
G36*
G01X1568792Y137816D02*
G02X1567154Y137824I-825J-1134D01*
G03X1567157Y138473I-232J326D01*
G02X1568795Y138465I825J1134D01*
G03X1568792Y137816I232J-326D01*
G37*
G36*
G01X1513514Y139046D02*
G02X1513185Y137327I911J-1065D01*
G03X1512571Y137444I-354J-187D01*
G02X1512900Y139163I-911J1065D01*
G03X1513514Y139046I354J187D01*
G37*
G36*
G01X1721389Y138819D02*
G02Y140181I-1225J681D01*
G03X1722089I350J194D01*
G02X1722633Y140725I1225J-681D01*
G03Y141425I-194J350D01*
G02X1722650Y143885I681J1225D01*
G03X1722639Y144595I-190J352D01*
G02X1722070Y145116I626J1255D01*
G03X1721381Y145105I-341J-209D01*
G02X1721358Y146534I-1217J695D01*
G03X1722047Y146545I341J209D01*
G02X1724519Y146475I1217J-695D01*
G03X1725229Y146464I358J179D01*
G02X1725209Y145175I1235J-664D01*
G03X1724499Y145186I-358J-179D01*
G02X1723928Y144615I-1235J664D01*
G03X1723939Y143905I190J-352D01*
G02X1723995Y141425I-625J-1255D01*
G03Y140725I194J-350D01*
G02X1722089Y138819I-681J-1225D01*
G03X1721389I-350J-194D01*
G37*
G36*
G01X1621265Y140006D02*
G02Y141368I-1225J681D01*
G03X1621965I350J194D01*
G02Y140006I1225J-681D01*
G03X1621265I-350J-194D01*
G37*
G36*
G01X1952235Y142296D02*
G02X1950569Y141828I-535J-1296D01*
G03X1950399Y142434I-323J236D01*
G02X1952065Y142902I535J1296D01*
G03X1952235Y142296I323J-236D01*
G37*
G36*
G01X1240805Y142936D02*
G02X1239229Y142929I-783J-1163D01*
G03X1239227Y143591I-226J330D01*
G02X1240803Y143598I783J1163D01*
G03X1240805Y142936I226J-330D01*
G37*
G36*
G01X1822623Y142854D02*
G02X1822532Y144188I-1275J583D01*
G03X1823234Y144236I338J214D01*
G02X1823325Y142902I1275J-583D01*
G03X1822623Y142854I-338J-214D01*
G37*
G36*
G01X1608134Y145056D02*
G02X1606717Y145038I-693J-1219D01*
G03X1606708Y145728I-206J342D01*
G02X1608634Y147615I693J1219D01*
G03X1609342Y147624I352J190D01*
G02X1609910Y148212I1248J-638D01*
G03Y148912I-194J350D01*
G02X1609909Y151362I681J1225D01*
G03Y152061I-194J350D01*
G02X1609366Y152605I683J1224D01*
G03X1608666I-350J-194D01*
G02X1606760Y154511I-1225J681D01*
G03Y155211I-194J350D01*
G02Y157661I681J1225D01*
G03Y158360I-195J350D01*
G02Y160810I682J1225D01*
G03Y161509I-194J350D01*
G02X1608666Y163416I681J1226D01*
G03X1609366I350J194D01*
G02X1609910Y163960I1225J-681D01*
G03Y164660I-194J350D01*
G02X1611816Y166566I681J1225D01*
G03X1612516I350J194D01*
G02X1614966I1225J-681D01*
G03X1615666I350J194D01*
G02X1618116I1225J-681D01*
G03X1618816I350J194D01*
G02X1619294Y167071I1225J-681D01*
G03X1619286Y167753I-213J339D01*
G02X1620753Y167770I720J1203D01*
G03X1620761Y167088I213J-339D01*
G02X1618816Y165204I-720J-1203D01*
G03X1618116I-350J-194D01*
G02X1617572Y164659I-1226J680D01*
G03Y163960I194J-350D01*
G02X1617571Y161510I-682J-1225D01*
G03Y160810I194J-350D01*
G02X1618115Y160266I-681J-1225D01*
G03X1618815I350J194D01*
G02X1621265Y160267I1225J-681D01*
G03X1621964I350J194D01*
G02X1622452Y160778I1225J-682D01*
G03X1622465Y161449I-211J340D01*
G02X1622606Y163856I785J1162D01*
G03X1622611Y164564I-184J355D01*
G02X1624447Y166569I665J1234D01*
G03X1625127Y166588I334J220D01*
G02X1627564Y166565I1212J-704D01*
G03X1628264I350J194D01*
G02X1630171Y164659I1225J-681D01*
G03Y163960I194J-350D01*
G02X1630170Y161510I-682J-1225D01*
G03Y160810I194J-350D01*
G02X1628264Y158904I-681J-1225D01*
G03X1627564I-350J-194D01*
G02X1625114I-1225J681D01*
G03X1624414I-350J-194D01*
G02X1621964Y158903I-1225J681D01*
G03X1621265I-349J-194D01*
G02X1618815Y158904I-1225J682D01*
G03X1618115I-350J-194D01*
G02X1615665Y158903I-1225J681D01*
G03X1614966I-349J-194D01*
G02X1614423Y158360I-1225J682D01*
G03Y157661I194J-349D01*
G02X1614422Y155211I-682J-1225D01*
G03Y154511I194J-350D01*
G02X1614423Y152061I-681J-1225D01*
G03Y151362I194J-350D01*
G02X1614966Y150818I-683J-1224D01*
G03X1615666I350J194D01*
G02Y149456I1225J-681D01*
G03X1614966I-350J-194D01*
G02X1614422Y148912I-1225J681D01*
G03Y148212I194J-350D01*
G02X1612516Y146306I-681J-1225D01*
G03X1611816I-350J-194D01*
G02X1609358Y146319I-1225J681D01*
G03X1608650Y146310I-352J-190D01*
G02X1608125Y145746I-1249J637D01*
G03X1608134Y145056I206J-342D01*
G37*
G36*
G01X1937365Y144773D02*
G02X1935661Y145312I-1178J-760D01*
G03X1935828Y145926I-151J371D01*
G02X1935705Y146112I1272J975D01*
G03X1935056Y146178I-348J-197D01*
G02X1935166Y147879I-1056J922D01*
G03X1935818Y147861I332J222D01*
G02X1937581Y145372I1282J-961D01*
G03X1937365Y144773I120J-382D01*
G37*
G36*
G01X1621265Y146306D02*
G02Y147668I-1225J681D01*
G03X1621965I350J194D01*
G02Y146306I1225J-681D01*
G03X1621265I-350J-194D01*
G37*
G36*
G01X1600850Y149794D02*
G02X1599487Y149780I-669J-1232D01*
G03X1599480Y150479I-198J348D01*
G02X1600843Y150493I669J1232D01*
G03X1600850Y149794I198J-348D01*
G37*
G36*
G01X1595532Y149735D02*
G02X1594240Y150084I-967J-1015D01*
G03X1594423Y150763I-93J389D01*
G02X1595715Y150414I967J1015D01*
G03X1595532Y149735I93J-389D01*
G37*
G36*
G01X1715242Y148118D02*
G02Y149782I-1128J832D01*
G03X1715886I322J238D01*
G02Y148118I1128J-832D01*
G03X1715242I-322J-238D01*
G37*
G36*
G01X1542460Y150283D02*
G02X1540828Y150010I-629J-1253D01*
G03X1540722Y150647I-286J280D01*
G02X1542354Y150920I629J1253D01*
G03X1542460Y150283I286J-280D01*
G37*
G36*
G01X1914684Y148614D02*
G02X1914504Y150391I-1292J767D01*
G03X1915135Y150441I296J269D01*
G02X1917581Y150267I1175J-765D01*
G03X1918286Y150228I363J169D01*
G02X1918213Y148909I1198J-728D01*
G03X1917508Y148948I-363J-169D01*
G02X1915312Y148691I-1198J728D01*
G03X1914684Y148614I-284J-281D01*
G37*
G36*
G01X1578563Y150675D02*
G02X1577117Y150760I-793J-1156D01*
G03X1577157Y151444I-186J354D01*
G02X1576957Y153590I793J1156D01*
G03X1576901Y154201I-283J282D01*
G02X1578693Y154363I799J1152D01*
G03X1578749Y153752I283J-282D01*
G02X1578603Y151359I-799J-1152D01*
G03X1578563Y150675I186J-354D01*
G37*
G36*
G01X1829274Y151006D02*
G02X1827889Y151287I-933J-1046D01*
G03X1828026Y151964I-129J379D01*
G02X1829411Y151683I933J1046D01*
G03X1829274Y151006I129J-379D01*
G37*
G36*
G01X1626991Y151377D02*
G02X1625666Y151366I-652J-1241D01*
G03X1625661Y152071I-192J351D01*
G02X1625150Y152530I653J1241D01*
G03X1624459Y152482I-332J-224D01*
G02X1621948Y152468I-1259J618D01*
G03X1621260Y152513I-357J-180D01*
G02X1620815Y152094I-1160J787D01*
G03Y151406I204J-344D01*
G02X1619385I-715J-1206D01*
G03Y152094I-204J344D01*
G02X1621352Y153932I715J1206D01*
G03X1622040Y153887I357J180D01*
G02X1624363Y153882I1160J-787D01*
G03X1625054Y153930I332J224D01*
G02X1627554Y153964I1259J-618D01*
G03X1628259Y153959I354J187D01*
G02X1630714Y153968I1230J-673D01*
G03X1631413I350J194D01*
G02X1633863Y153967I1225J-682D01*
G03X1634563I350J194D01*
G02Y152605I1225J-681D01*
G03X1633863I-350J-194D01*
G02X1631413Y152604I-1225J681D01*
G03X1630714I-349J-194D01*
G02X1628248Y152634I-1225J682D01*
G03X1627543Y152639I-354J-187D01*
G02X1626986Y152082I-1230J673D01*
G03X1626991Y151377I192J-351D01*
G37*
G36*
G01X1655367Y151363D02*
G02X1654005I-681J-1225D01*
G03Y152063I-194J350D01*
G02X1654003Y154513I681J1226D01*
G03Y155211I-194J349D01*
G02X1653461Y155754I684J1224D01*
G03X1652762I-349J-194D01*
G02X1650311I-1225J681D01*
G03X1649611I-350J-194D01*
G02X1649066Y155209I-1226J681D01*
G03X1649068Y154509I194J-349D01*
G02X1647713Y154506I-675J-1229D01*
G03X1647711Y155206I-194J349D01*
G02X1647705Y157661I675J1229D01*
G03Y158360I-194J350D01*
G02X1647162Y158904I683J1224D01*
G03X1646462I-350J-194D01*
G02X1644012I-1225J681D01*
G03X1643312I-350J-194D01*
G02X1640862Y158903I-1225J681D01*
G03X1640163I-349J-194D01*
G02X1637713Y158904I-1225J682D01*
G03X1637013I-350J-194D01*
G02X1635107Y160810I-1225J681D01*
G03Y161510I-194J350D01*
G02Y163960I681J1225D01*
G03Y164660I-194J350D01*
G02X1637014Y166566I681J1225D01*
G03X1637713I350J194D01*
G02X1640163I1225J-682D01*
G03X1640862I350J194D01*
G02X1643313I1225J-681D01*
G03X1644012I349J195D01*
G02X1646462I1225J-682D01*
G03X1647161I350J195D01*
G02X1649612I1225J-681D01*
G03X1650311I350J194D01*
G02X1652218Y164659I1225J-682D01*
G03Y163960I194J-350D01*
G02X1652761Y163417I-682J-1225D01*
G03X1653460I350J194D01*
G02X1655910Y163416I1225J-682D01*
G03X1656610I350J194D01*
G02X1657153Y163960I1226J-680D01*
G03Y164659I-194J350D01*
G02X1659060Y166566I682J1225D01*
G03X1659759I350J194D01*
G02X1661666Y164660I1226J-681D01*
G03Y163960I194J-350D01*
G02Y161510I-681J-1225D01*
G03Y160810I194J-350D01*
G02Y158360I-681J-1225D01*
G03Y157660I194J-350D01*
G02X1662210Y157117I-680J-1226D01*
G03X1662909I350J195D01*
G02X1664816Y155211I1225J-681D01*
G03Y154512I194J-349D01*
G02X1663453Y154511I-681J-1226D01*
G03Y155210I-194J350D01*
G02X1662909Y155754I681J1225D01*
G03X1662210I-350J-195D01*
G02X1659759I-1225J681D01*
G03X1659060I-349J-194D01*
G02X1658518Y155212I-1225J683D01*
G03Y154513I195J-349D01*
G02X1656611Y152607I-682J-1225D01*
G03X1655911I-350J-194D01*
G02X1655367Y152063I-1225J681D01*
G03Y151363I194J-350D01*
G37*
G36*
G01X1906106Y151138D02*
G02X1904426Y151404I-1014J-968D01*
G03X1904526Y152032I-190J352D01*
G02X1906206Y151766I1014J968D01*
G03X1906106Y151138I190J-352D01*
G37*
G36*
G01X1493400Y154196D02*
G02X1491916Y153632I-331J-1362D01*
G03X1491682Y154248I-329J227D01*
G02X1493166Y154812I331J1362D01*
G03X1493400Y154196I329J-227D01*
G37*
G36*
G01X1263621Y155695D02*
G02X1263522Y154039I1079J-895D01*
G03X1262879Y154078I-336J-217D01*
G02X1262978Y155734I-1079J895D01*
G03X1263621Y155695I336J217D01*
G37*
G36*
G01X1808218Y163430D02*
G02X1806662I-778J-1400D01*
G03Y164130I-194J350D01*
G02Y166930I778J1400D01*
G03Y167630I-194J350D01*
G02X1808218I778J1400D01*
G03Y166930I194J-350D01*
G02Y164130I-778J-1400D01*
G03Y163430I194J-350D01*
G37*
G36*
G01X-14373Y161787D02*
G02X-14902Y163024I-1395J135D01*
G03X-14256Y163300I248J315D01*
G02X-13727Y162063I1395J-135D01*
G03X-14373Y161787I-248J-315D01*
G37*
G36*
G01X1455114Y164296D02*
G02X1453485Y164634I-1044J-936D01*
G03X1453616Y165264I-167J363D01*
G02X1455245Y164926I1044J936D01*
G03X1455114Y164296I167J-363D01*
G37*
G36*
G01X1929290Y171119D02*
G02X1929132Y169372I1010J-972D01*
G03X1928510Y169428I-333J-221D01*
G02X1928668Y171175I-1010J972D01*
G03X1929290Y171119I333J221D01*
G37*
G36*
G01X1452032Y171551D02*
G02X1450714Y171560I-667J-1233D01*
G03X1450719Y172266I-185J354D01*
G02X1450374Y174469I667J1233D01*
G03X1450369Y175027I-289J276D01*
G02X1450089Y176595I996J987D01*
G03X1449904Y177118I-364J165D01*
G02X1451808Y177791I628J1254D01*
G03X1451993Y177268I364J-165D01*
G02X1452377Y175044I-628J-1254D01*
G03X1452382Y174486I289J-276D01*
G02X1452037Y172257I-996J-987D01*
G03X1452032Y171551I185J-354D01*
G37*
G36*
G01X1675688Y171990D02*
G02X1675669Y173359I-1233J668D01*
G03X1676367Y173368I346J200D01*
G02X1676386Y171999I1233J-668D01*
G03X1675688Y171990I-346J-200D01*
G37*
G36*
G01X1623864Y173803D02*
G02X1623715Y172303I1102J-867D01*
G03X1623044Y172370I-357J-180D01*
G02X1623193Y173870I-1102J867D01*
G03X1623864Y173803I357J180D01*
G37*
G36*
G01X1929349Y174614D02*
G02X1927318Y176518I-1131J829D01*
G03X1927325Y177125I-257J307D01*
G02X1929149Y177104I924J1054D01*
G03X1929142Y176497I257J-307D01*
G02X1929302Y176332I-923J-1055D01*
G03X1929934Y176349I309J253D01*
G02X1930489Y176798I1130J-830D01*
G03X1930617Y177437I-164J365D01*
G02X1932215Y177118I1022J959D01*
G03X1932087Y176479I164J-365D01*
G02X1929981Y174631I-1022J-959D01*
G03X1929349Y174614I-309J-253D01*
G37*
G36*
G01X1720013Y177316D02*
G02X1718316Y177397I-913J-1316D01*
G03X1718371Y178058I-195J349D01*
G02X1720021Y177979I879J1092D01*
G03X1720013Y177316I220J-334D01*
G37*
G36*
G01X1752390Y178036D02*
X1757391D01*
G02X1758902Y176535I0J-1512D01*
G01Y176440D01*
X1758892Y176356D01*
G02X1757390Y175014I-1502J169D01*
G01X1752390D01*
G02X1751337Y175442I1J1511D01*
G03X1750706Y175345I-279J-287D01*
G02X1750451Y177213I-1411J759D01*
G03X1751086Y177288I289J276D01*
G02X1752390Y178036I1304J-763D01*
G37*
G36*
G01X1884675Y177325D02*
G02X1883084Y177255I-745J-1188D01*
G03X1883055Y177912I-242J318D01*
G02X1884957Y179892I745J1188D01*
G03X1885534Y179803I330J226D01*
G02X1885243Y177908I866J-1103D01*
G03X1884666Y177997I-330J-226D01*
G02X1884646Y177982I-851J1114D01*
G03X1884675Y177325I242J-318D01*
G37*
G36*
G01X63421Y177506D02*
G02X62786Y176279I766J-1174D01*
G03X62168Y176599I-400J-15D01*
G02X62803Y177826I-766J1174D01*
G03X63421Y177506I400J15D01*
G37*
G36*
G01X1489739Y177922D02*
G02X1488381Y177890I-650J-1242D01*
G03X1488364Y178590I-202J345D01*
G02X1489722Y178622I650J1242D01*
G03X1489739Y177922I202J-345D01*
G37*
G36*
G01X1227947Y178203D02*
G02X1226003Y180147I-1167J777D01*
G03Y180813I-222J333D01*
G02X1225919Y183086I777J1167D01*
G03X1225948Y183692I-246J315D01*
G02X1227775Y183602I966J1016D01*
G03X1227746Y182996I246J-315D01*
G02X1227947Y182757I-966J-1016D01*
G03X1228613I333J222D01*
G02X1230947I1167J-777D01*
G03X1231613I333J222D01*
G02X1233557Y180813I1167J-777D01*
G03Y180147I222J-333D01*
G02X1231613Y178203I-777J-1167D01*
G03X1230947I-333J-222D01*
G02X1228613I-1167J777D01*
G03X1227947I-333J-222D01*
G37*
G36*
G01X1597025Y179619D02*
G02Y180981I-1225J681D01*
G03X1597725I350J194D01*
G02Y179619I1225J-681D01*
G03X1597025I-350J-194D01*
G37*
G36*
G01X1855682Y182846D02*
G02X1854144Y182808I-740J-1191D01*
G03X1854128Y183476I-228J329D01*
G02X1855666Y183514I740J1191D01*
G03X1855682Y182846I228J-329D01*
G37*
G36*
G01X87704Y182904D02*
G02X86355Y182989I-752J-1183D01*
G03X86399Y183689I-170J362D01*
G02X87748Y183604I752J1183D01*
G03X87704Y182904I170J-362D01*
G37*
G36*
G01X767754Y183850D02*
G02X765216Y182837I-1386J-214D01*
G03X764664Y182940I-328J-229D01*
G02X762508Y184389I-783J1163D01*
G03X762239Y184851I-391J81D01*
G02X761777Y185103I428J1335D01*
G03X761242Y185079I-254J-309D01*
G02X759160Y186949I-984J999D01*
G03X759122Y187489I-313J249D01*
G02X759037Y187575I954J1028D01*
G03X758734Y187570I-149J-133D01*
G02X756760Y187384I-1080J894D01*
G03X756226Y187363I-255J-308D01*
G02X754226Y187408I-978J1005D01*
G03X753662Y187428I-292J-273D01*
G02X751706Y187475I-954J1027D01*
G03X751142Y187482I-286J-280D01*
G02X749159Y187515I-975J1008D01*
G03X748561Y187488I-287J-278D01*
G02X746453Y187402I-1092J880D01*
G03X745889Y187417I-290J-276D01*
G02X743856Y187534I-961J1021D01*
G03X743227Y187511I-305J-258D01*
G02X741097Y187344I-1136J822D01*
G03X740491Y187298I-283J-282D01*
G02X737962Y188013I-1132J827D01*
G03X737509Y188377I-399J-32D01*
G02X737404Y188367I-185J1389D01*
G03X737028Y187967I24J-399D01*
G02X734269Y187614I-1402J-2D01*
G03X733811Y187908I-387J-100D01*
G02X732641Y188233I-247J1380D01*
G03X732106Y188226I-264J-301D01*
G02X732078Y190311I-951J1030D01*
G03X732613Y190318I264J301D01*
G02X734921Y189639I951J-1030D01*
G03X735379Y189345I387J100D01*
G02X735541Y189364I244J-1380D01*
G03X735917Y189764I-24J399D01*
G02X736450Y190866I1402J2D01*
G03X736498Y191449I-248J314D01*
G02X738938Y192406I1038J943D01*
G03X739405Y192016I400J4D01*
G02X740525Y189546I236J-1382D01*
G03X740463Y188989I253J-310D01*
G02X740499Y188941I-1103J-865D01*
G03X740840Y188967I163J116D01*
G02X743163Y189237I1251J-634D01*
G03X743792Y189260I305J258D01*
G02X745944Y189404I1136J-822D01*
G03X746508Y189389I290J276D01*
G02X748477Y189343I961J-1021D01*
G03X749075Y189370I287J278D01*
G02X751169Y189470I1091J-880D01*
G03X751733Y189463I286J280D01*
G02X753730Y189415I975J-1008D01*
G03X754294Y189395I292J273D01*
G02X756142Y189448I954J-1027D01*
G03X756676Y189469I255J308D01*
G02X758581Y189516I978J-1005D01*
G03X759120Y189526I264J300D01*
G02X760987Y189580I964J-1018D01*
G03X761531Y189606I258J306D01*
G02X763513Y189628I1002J-980D01*
G03X764062Y189619I279J286D01*
G02X766074Y189493I945J-1036D01*
G03X766622Y189435I304J259D01*
G02X768495Y187360I854J-1112D01*
G03X768543Y186768I291J-274D01*
G02X768047Y184298I-851J-1114D01*
G03X767754Y183850I102J-387D01*
G37*
G36*
G01X1643138Y183981D02*
G02X1640433Y184087I-1338J419D01*
G03X1639869Y184358I-390J-89D01*
G02X1640658Y185686I-611J1262D01*
G03X1640976Y185534I200J10D01*
G02X1641128Y185630I823J-1135D01*
G03X1641274Y186196I-192J351D01*
G02X1643844Y187149I1183J752D01*
G03X1644283Y186809I396J58D01*
G02X1643722Y184206I150J-1394D01*
G03X1643138Y183981I-203J-345D01*
G37*
G36*
G01X1703257Y188180D02*
G02X1701704Y188154I-757J-1180D01*
G03X1701693Y188820I-227J329D01*
G02X1703246Y188846I757J1180D01*
G03X1703257Y188180I227J-329D01*
G37*
G36*
G01X1709077Y188435D02*
G02X1708544Y186943I823J-1135D01*
G03X1707923Y187165I-387J-102D01*
G02X1708456Y188657I-823J1135D01*
G03X1709077Y188435I387J102D01*
G37*
G36*
G01X726687Y189694D02*
G02X726618Y188021I1089J-883D01*
G03X725977Y188047I-330J-226D01*
G02X726046Y189720I-1089J883D01*
G03X726687Y189694I330J226D01*
G37*
G36*
G01X1945242Y191496D02*
G02X1943626Y191653I-942J-1296D01*
G03X1943713Y192323I-169J363D01*
G02X1945285Y192170I898J1077D01*
G03X1945242Y191496I192J-351D01*
G37*
G36*
G01X1264031Y192350D02*
G02X1261842Y190662I-951J-1030D01*
G03X1261189Y190740I-354J-187D01*
G02X1258828Y191177I-1049J930D01*
G03X1258177Y191325I-374J-141D01*
G02X1255826Y192116I-967J1015D01*
G03X1255404Y192451I-395J-64D01*
G02X1254628Y192625I-94J1399D01*
G03X1254099Y192497I-196J-349D01*
G02X1251543Y193067I-1169J773D01*
G03X1251134Y193409I-396J-58D01*
G02X1249691Y194909I-45J1401D01*
G03X1249354Y195333I-399J29D01*
G02X1248169Y196692I217J1385D01*
G03X1247777Y197084I-400J-8D01*
G02X1246401Y198520I26J1402D01*
G03X1246021Y198930I-400J11D01*
G02X1244688Y200354I69J1400D01*
G03X1244309Y200760I-400J7D01*
G02X1242987Y202316I71J1400D01*
G03X1242636Y202758I-398J45D01*
G02X1242119Y205375I164J1392D01*
G03X1242207Y206008I-194J350D01*
G02X1241812Y206781I990J993D01*
G03X1241202Y207056I-395J-63D01*
G02X1239442Y209213I-750J1184D01*
G03Y209767I-288J277D01*
G02Y211713I1010J973D01*
G03Y212267I-288J277D01*
G02Y214213I1010J973D01*
G03Y214767I-288J277D01*
G02X1239446Y216717I1010J973D01*
G03X1239457Y217263I-287J279D01*
G02X1241506Y217223I1043J937D01*
G03X1241495Y216677I287J-279D01*
G02X1241462Y214767I-1043J-937D01*
G03Y214213I288J-277D01*
G02Y212267I-1010J-973D01*
G03Y211713I288J-277D01*
G02Y209767I-1010J-973D01*
G03Y209213I288J-277D01*
G02X1241836Y208461I-1011J-972D01*
G03X1242446Y208186I395J63D01*
G02X1244589Y207161I750J-1184D01*
G03X1244992Y206807I397J46D01*
G02X1246416Y205371I22J-1402D01*
G03X1246772Y204964I400J-10D01*
G02X1248021Y203529I-152J-1394D01*
G03X1248392Y203118I400J-12D01*
G02X1248785Y203032I-100J-1398D01*
G03X1249304Y203272I142J374D01*
G02X1252027Y202824I1321J-468D01*
G03X1252405Y202430I400J5D01*
G02X1252469Y202425I-77J-1400D01*
G03X1252908Y202827I39J398D01*
G02X1255088Y204006I1402J13D01*
G03X1255643Y204117I222J333D01*
G02X1256982Y204731I1167J-777D01*
G03X1257426Y205064I49J397D01*
G02X1258739Y206240I1384J-224D01*
G03X1259117Y206684I-20J400D01*
G02X1260386Y208236I1393J156D01*
G03X1260734Y208747I-36J398D01*
G02X1262016Y210541I1346J393D01*
G03X1262382Y211052I-18J399D01*
G02X1265099Y211149I1346J392D01*
G03X1265481Y210665I391J-84D01*
G02X1266852Y209289I-31J-1402D01*
G03X1267244Y208897I400J8D01*
G02X1268620Y207521I-26J-1402D01*
G03X1269012Y207129I400J8D01*
G02X1270388Y205753I-26J-1402D01*
G03X1270780Y205361I400J8D01*
G02X1272156Y203985I-26J-1402D01*
G03X1272548Y203593I400J8D01*
G02X1272678Y200798I-26J-1402D01*
G03X1272325Y200360I45J-398D01*
G02X1270974Y198819I-1395J-140D01*
G03X1270602Y198309I13J-400D01*
G02X1269325Y196523I-1348J-386D01*
G03X1268947Y196079I20J-400D01*
G02X1267382Y194532I-1393J-156D01*
G03X1266941Y194218I-50J-397D01*
G02X1264803Y193336I-1371J292D01*
G03X1264242Y193208I-219J-335D01*
G02X1264022Y192929I-1202J722D01*
G03X1264031Y192350I280J-285D01*
G37*
G36*
G01X706309Y191605D02*
G02X705545Y192886I-1402J32D01*
G03X706127Y193233I182J356D01*
G02X707720Y194589I1402J-33D01*
G03X708135Y195158I54J396D01*
G02X710728Y196211I1264J605D01*
G03X711280Y195978I379J128D01*
G02X712356Y196035I606J-1264D01*
G03X712855Y196250I133J377D01*
G02X715433Y196217I1282J-568D01*
G03X715953Y195999I370J153D01*
G02X715184Y194165I527J-1299D01*
G03X714664Y194383I-370J-153D01*
G02X713667Y194361I-527J1299D01*
G03X713168Y194146I-133J-377D01*
G02X710558Y194266I-1282J568D01*
G03X710006Y194499I-379J-128D01*
G02X709209Y194374I-607J1264D01*
G03X708794Y193805I-54J-396D01*
G02X706891Y191952I-1265J-605D01*
G03X706309Y191605I-182J-356D01*
G37*
G36*
G01X698454Y194415D02*
G02X696900Y194323I-708J-1210D01*
G03X696860Y194987I-242J319D01*
G02X698414Y195079I708J1210D01*
G03X698454Y194415I242J-319D01*
G37*
G36*
G01X98575Y195729D02*
G02X97147Y195683I-675J-1229D01*
G03X97125Y196371I-214J337D01*
G02X97155Y198845I675J1229D01*
G03Y199555I-184J355D01*
G02X98445I645J1245D01*
G03Y198845I184J-355D01*
G02X98553Y196417I-645J-1245D01*
G03X98575Y195729I214J-337D01*
G37*
G36*
G01X1630836Y196158D02*
G02X1630732Y196162I2J1402D01*
G03X1630314Y195670I-29J-399D01*
G02X1629054Y196742I-1364J-326D01*
G03X1629472Y197234I29J399D01*
G02X1632121Y197000I1364J326D01*
G03X1632340Y196724I184J-79D01*
G02X1632363Y196727I193J-1387D01*
G03X1632691Y197196I-65J395D01*
G02X1634296Y196071I1378J258D01*
G03X1633968Y195602I65J-395D01*
G02X1631226Y195666I-1378J-258D01*
G03X1630837Y196158I-389J92D01*
G01X1630836D01*
G37*
G36*
G01X105535Y196906D02*
G02X104105I-715J-1206D01*
G03Y197594I-204J344D01*
G02X105535I715J1206D01*
G03Y196906I204J-344D01*
G37*
G36*
G01X1731771Y195558D02*
G02X1731397Y196835I-1371J292D01*
G03X1732076Y197045I285J281D01*
G02X1733563Y198288I1487J-268D01*
G01X1738564D01*
G02X1740074Y196786I-1J-1512D01*
G01Y196691D01*
X1740065Y196607D01*
G02X1738563Y195264I-1502J168D01*
G01X1733563D01*
G02X1732456Y195747I1J1512D01*
G03X1731771Y195558I-294J-272D01*
G37*
G36*
G01X607489Y199401D02*
G02X605767Y199172I-716J-1205D01*
G03X605684Y199795I-287J279D01*
G02X605006Y201146I716J1205D01*
G03X604573Y201586I-398J41D01*
G02X605847Y202837I-120J1397D01*
G03X606280Y202397I398J-41D01*
G02X607406Y200024I120J-1397D01*
G03X607489Y199401I287J-279D01*
G37*
G36*
G01X799413Y200497D02*
G02X798046Y199727I-113J-1397D01*
G03X797694Y200305I-358J178D01*
G02X799100Y201098I23J1602D01*
G03X799413Y200497I345J-202D01*
G37*
G36*
G01X1894193Y200047D02*
G02X1893186Y201414I-1402J22D01*
G03X1893698Y201792I112J384D01*
G02X1894569Y203068I1402J-22D01*
G03X1894683Y203737I-152J370D01*
G02X1896145Y203487I932J1048D01*
G03X1896031Y202818I152J-370D01*
G02X1894705Y200425I-931J-1048D01*
G03X1894193Y200047I-112J-384D01*
G37*
G36*
G01X579220Y203377D02*
G02X578123Y202280I277J-1374D01*
G03X577652Y202751I-392J79D01*
G02X578749Y203848I-277J1374D01*
G03X579220Y203377I392J-79D01*
G37*
G36*
G01X1403833Y206100D02*
G02X1402555Y205885I-433J-1334D01*
G03X1402437Y206584I-241J319D01*
G02X1403715Y206799I433J1334D01*
G03X1403833Y206100I241J-319D01*
G37*
G36*
G01X562584Y206877D02*
G02X561487Y205780I277J-1374D01*
G03X561016Y206251I-392J79D01*
G02X562113Y207348I-277J1374D01*
G03X562584Y206877I392J-79D01*
G37*
G36*
G01X1955487Y214076D02*
G03X1955651Y214607I-193J350D01*
G02X1956220Y216466I1250J634D01*
G03Y217166I-194J350D01*
G02X1957582I681J1225D01*
G03Y216466I194J-350D01*
G02X1958147Y214599I-681J-1225D01*
G03X1958308Y214067I356J-183D01*
G02X1959541Y212715I-1418J-2532D01*
G03X1960200Y212606I365J163D01*
G02X1959928Y209839I1690J-1563D01*
G03X1959260Y209861I-341J-209D01*
G02X1957697Y208747I-2371J1673D01*
G01X1957552Y208706D01*
Y204492D01*
X1946598D01*
Y213346D01*
X1954623D01*
G02X1955487Y214076I2269J-1809D01*
G37*
G36*
G01X1330337Y207982D02*
G02X1330256Y209998I-1013J969D01*
G03X1330811Y210020I266J299D01*
G02X1332952Y209883I1013J-969D01*
G03X1333596I322J238D01*
G02Y208219I1128J-832D01*
G03X1332952I-322J-238D01*
G02X1330892Y208004I-1128J832D01*
G03X1330337Y207982I-266J-299D01*
G37*
G36*
G01X1884653Y211688D02*
G02X1882947I-853J-1113D01*
G03Y212323I-243J317D01*
G02X1885092Y213981I853J1113D01*
G03X1885791Y213912I368J155D01*
G02X1885660Y212580I1161J-787D01*
G03X1884961Y212649I-368J-155D01*
G02X1884653Y212323I-1160J788D01*
G03Y211688I243J-318D01*
G37*
G36*
G01X565773Y212929D02*
G02X564656Y211694I278J-1374D01*
G03X564178Y212126I-398J40D01*
G02X565295Y213361I-278J1374D01*
G03X565773Y212929I398J-40D01*
G37*
G36*
G01X174500Y210839D02*
G02X172195Y213060I-1200J1061D01*
G03Y213640I-275J290D01*
G02Y215960I1105J1160D01*
G03Y216540I-275J290D01*
G02X174636Y218584I1105J1160D01*
G03X175236Y218505I334J220D01*
G02X177852Y217706I1064J-1197D01*
G03X178451Y217467I387J100D01*
G02X180500Y217169I849J-1359D01*
G03X181100I300J265D01*
G02Y215047I1200J-1061D01*
G03X180500I-300J-265D01*
G02X180405Y214948I-1202J1059D01*
G03Y214368I275J-290D01*
G02X178469Y211839I-1105J-1159D01*
G03X177869Y211577I-208J-342D01*
G02X175100Y210839I-1569J323D01*
G03X174500I-300J-265D01*
G37*
G36*
G01X1848935Y212284D02*
G02Y213608I-1236J662D01*
G03X1849640I353J189D01*
G02Y212284I1236J-662D01*
G03X1848935I-352J-189D01*
G37*
G36*
G01X116300Y214684D02*
G02X114751Y214669I-763J-1176D01*
G03X114744Y215336I-224J331D01*
G02X116293Y215351I763J1176D01*
G03X116300Y214684I224J-331D01*
G37*
G36*
G01X765908D02*
G02X764359Y214669I-763J-1176D01*
G03X764352Y215336I-224J331D01*
G02X765901Y215351I763J1176D01*
G03X765908Y214684I224J-331D01*
G37*
G36*
G01X1220270Y214898D02*
G02X1218893Y216271I-1402J-29D01*
G03X1219300Y216679I7J400D01*
G02X1219317Y216923I1402J25D01*
G03X1218979Y217097I-198J31D01*
G02X1219396Y218228I-979J1003D01*
G03X1219996Y217919I398J37D01*
G02X1220677Y215306I706J-1211D01*
G03X1220270Y214898I-7J-400D01*
G37*
G36*
G01X1331241Y215723D02*
G02Y217277I-1167J777D01*
G03X1331907I333J222D01*
G02X1334241I1167J-777D01*
G03X1334907I333J222D01*
G02Y215723I1167J-777D01*
G03X1334241I-333J-222D01*
G02X1331907I-1167J777D01*
G03X1331241I-333J-222D01*
G37*
G36*
G01X580354Y218161D02*
G02X579257Y219258I-1374J-277D01*
G03X579728Y219729I79J392D01*
G02X580825Y218632I1374J277D01*
G03X580354Y218161I-79J-392D01*
G37*
G36*
G01X743908Y222185D02*
G02X741579Y220827I-971J-1011D01*
G03X741024Y221091I-388J-99D01*
G02X739426Y221393I-587J1273D01*
G03X738848I-289J-277D01*
G02X736866Y223375I-1011J971D01*
G03Y223953I-277J289D01*
G02X738848Y225935I971J1011D01*
G03X739426I289J277D01*
G02X739696Y226154I1011J-971D01*
G03X739665Y226850I-212J339D01*
G02X741685Y228317I635J1250D01*
G03X742262Y228023I395J62D01*
G02X743690Y225617I635J-1250D01*
G03X743699Y224951I226J-330D01*
G02X743908Y222763I-762J-1177D01*
G03Y222185I277J-289D01*
G37*
G36*
G01X642709Y222556D02*
G02X640382Y222440I-1109J-1156D01*
G03Y222960I-304J260D01*
G02Y225040I1218J1040D01*
G03Y225560I-304J260D01*
G02Y227640I1218J1040D01*
G03Y228160I-304J260D01*
G02Y230240I1218J1040D01*
G03Y230760I-304J260D01*
G02X642760Y232905I1218J1040D01*
G03X643340I290J275D01*
G02X645740Y232814I1160J-1105D01*
G03X646360I310J253D01*
G02X648840I1240J-1014D01*
G03X649460I310J253D01*
G02X651918Y230760I1240J-1014D01*
G03Y230240I304J-260D01*
G02Y228160I-1218J-1040D01*
G03Y227640I304J-260D01*
G02X652239Y227044I-1218J-1040D01*
G03X652849Y226824I385J111D01*
G02X652903Y224140I901J-1324D01*
G03X652294Y223840I-211J-340D01*
G02X649460Y222986I-1594J160D01*
G03X648840I-310J-253D01*
G02X646360I-1240J1014D01*
G03X645740I-310J-253D01*
G02X643340Y222895I-1240J1014D01*
G03X642760I-290J-275D01*
G02X642709Y222844I-1158J1107D01*
G03Y222556I139J-144D01*
G37*
G36*
G01X1904069Y226851D02*
G02X1901981Y226861I-1049J-1075D01*
G03X1901999Y227420I-277J289D01*
G02X1902167Y229471I1033J948D01*
G03X1902139Y230121I-247J315D01*
G02X1903772Y230191I768J1173D01*
G03X1903800Y229541I247J-315D01*
G02X1904056Y227410I-768J-1173D01*
G03X1904069Y226851I292J-273D01*
G37*
G36*
G01X1398440Y226716D02*
G02X1395924Y225485I-1229J-675D01*
G03X1395407Y225697I-367J-159D01*
G02X1396168Y227553I-526J1300D01*
G03X1396685Y227341I367J159D01*
G02X1397063Y227435I524J-1300D01*
G03X1397371Y228025I-43J398D01*
G02X1399574Y229708I1229J675D01*
G03X1400233Y229871I279J287D01*
G02X1400591Y228427I1332J-436D01*
G03X1399932Y228264I-279J-287D01*
G02X1398748Y227306I-1332J436D01*
G03X1398440Y226716I43J-398D01*
G37*
G36*
G01X602200Y227570D02*
G02X602143Y225908I1100J-870D01*
G03X601500Y225930I-330J-226D01*
G02X601557Y227592I-1100J870D01*
G03X602200Y227570I330J226D01*
G37*
G36*
G01X775868Y228446D02*
G02X774497Y228458I-697J-1330D01*
G03X774503Y229170I-180J358D01*
G02X775874Y229158I697J1330D01*
G03X775868Y228446I180J-358D01*
G37*
G36*
G01X1279850Y230736D02*
G02X1278675Y229922I99J-1398D01*
G03X1278283Y230488I-363J167D01*
G02X1276858Y232344I-100J1398D01*
G03X1276513Y232873I-378J130D01*
G02X1275240Y234465I115J1397D01*
G03X1274912Y234915I-396J56D01*
G02X1276542Y236101I242J1381D01*
G03X1276870Y235651I396J-56D01*
G02X1277953Y233812I-242J-1381D01*
G03X1278298Y233283I378J-130D01*
G02X1279458Y231302I-115J-1397D01*
G03X1279850Y230736I363J-167D01*
G37*
G36*
G01X1398802Y232142D02*
G02X1398004Y233383I-1402J-24D01*
G03X1398576Y233751I172J361D01*
G02X1399003Y234783I1402J24D01*
G03X1399023Y235337I-278J287D01*
G02X1398664Y236309I1043J937D01*
G03X1398073Y236670I-400J10D01*
G02X1398802Y237865I-673J1230D01*
G03X1399393Y237504I400J-10D01*
G02X1401041Y235266I674J-1230D01*
G03X1401021Y234712I278J-287D01*
G02X1399374Y232510I-1043J-937D01*
G03X1398802Y232142I-172J-361D01*
G37*
G36*
G01X1837228Y234063D02*
G02X1835822Y233596I-328J-1363D01*
G03X1835608Y234241I-307J256D01*
G02X1837014Y234708I328J1363D01*
G03X1837228Y234063I307J-256D01*
G37*
G36*
G01X1735168Y232256D02*
G02X1734900Y233771I-1288J553D01*
G03X1735559Y233888I291J274D01*
G02X1738014Y234111I1288J-554D01*
G03X1738680I333J222D01*
G02X1740447Y234601I1167J-777D01*
G03X1741013Y234900I171J362D01*
G02X1741153Y235327I1385J-218D01*
G03X1740972Y235871I-355J184D01*
G02X1740632Y236092I696J1443D01*
G03X1740108Y236086I-259J-305D01*
G02X1737864Y236200I-1064J1198D01*
G03X1737310Y236234I-295J-271D01*
G02X1735427Y236290I-911J1066D01*
G03X1734873I-277J-288D01*
G02Y238310I-973J1010D01*
G03X1735427I277J288D01*
G02X1737323Y238355I973J-1010D01*
G03X1737878Y238382I264J301D01*
G02X1740080Y238506I1166J-1098D01*
G03X1740604Y238512I259J305D01*
G02X1742733Y238511I1064J-1198D01*
G03X1743260Y238507I266J299D01*
G02X1745469Y238399I1048J-1212D01*
G03X1746052Y238403I290J276D01*
G02X1746066Y236210I1175J-1089D01*
G03X1745483Y236206I-290J-276D01*
G02X1744132Y235703I-1175J1089D01*
G03X1743713Y235167I-44J-398D01*
G02X1741798Y233414I-1315J-486D01*
G03X1741232Y233115I-171J-362D01*
G02X1738680Y232557I-1385J219D01*
G03X1738014I-333J-222D01*
G02X1735827Y232373I-1167J777D01*
G03X1735168Y232256I-291J-274D01*
G37*
G36*
G01X126246Y235654D02*
G02X124199Y233687I-683J-1338D01*
G03X123515Y233758I-363J-168D01*
G02X121399Y236085I-1284J958D01*
G03X121479Y236704I-208J342D01*
G02X123805Y238907I1153J1112D01*
G03X124391I293J272D01*
G02X126255Y236371I1173J-1091D01*
G03X126246Y235654I173J-361D01*
G37*
G36*
G01X1608415Y241546D02*
G02X1607183Y242777I-1566J-336D01*
G03X1607662Y243223I83J391D01*
G02X1608861Y242026I1389J192D01*
G03X1608415Y241546I-55J-396D01*
G37*
G36*
G01X1667018Y243217D02*
G02X1665659Y243210I-673J-1230D01*
G03X1665656Y243909I-196J349D01*
G02X1667015Y243916I673J1230D01*
G03X1667018Y243217I196J-349D01*
G37*
G36*
G01X1682647Y243237D02*
G02X1682508Y241656I1082J-892D01*
G03X1681851Y241714I-348J-196D01*
G02X1680454Y243971I-1082J891D01*
G03X1680674Y244614I-90J390D01*
G02X1682786Y246455I1086J886D01*
G03X1683397Y246484I293J272D01*
G02X1683483Y244676I1112J-853D01*
G03X1682872Y244647I-293J-272D01*
G02X1682075Y244134I-1113J853D01*
G03X1681855Y243491I90J-390D01*
G02X1681990Y243295I-1083J-890D01*
G03X1682647Y243237I348J196D01*
G37*
G36*
G01X128755Y242876D02*
G02X128442Y244539I-1255J625D01*
G03X129069Y244657I269J296D01*
G02X129382Y242994I1255J-625D01*
G03X128755Y242876I-269J-296D01*
G37*
G36*
G01X778282Y242932D02*
G02X778000Y244483I-1282J568D01*
G03X778650Y244601I285J281D01*
G02X778932Y243050I1282J-568D01*
G03X778282Y242932I-285J-281D01*
G37*
G36*
G01X1437365Y245552D02*
G02X1436078Y244616I35J-1402D01*
G03X1435690Y245148I-377J132D01*
G02X1436977Y246084I-35J1402D01*
G03X1437365Y245552I377J-132D01*
G37*
G36*
G01X116289Y246548D02*
G02X114740Y246533I-763J-1176D01*
G03X114733Y247200I-224J331D01*
G02X116282Y247215I763J1176D01*
G03X116289Y246548I224J-331D01*
G37*
G36*
G01X765908Y246684D02*
G02X764359Y246669I-763J-1176D01*
G03X764352Y247336I-224J331D01*
G02X765901Y247351I763J1176D01*
G03X765908Y246684I224J-331D01*
G37*
G36*
G01X849482Y245366D02*
G02X847064Y247467I-1200J1061D01*
G03Y247987I-304J260D01*
G02X847099Y250107I1218J1040D01*
G03Y250647I-295J270D01*
G02X846842Y251026I1184J1079D01*
G03X846196Y251130I-360J-175D01*
G02X846594Y252679I-1146J1120D01*
G03X846952Y252620I193J53D01*
G02X847064Y252767I1328J-896D01*
G03Y253287I-304J260D01*
G02X849482Y255388I1218J1040D01*
G03X850082I300J265D01*
G02X852482I1200J-1061D01*
G03X853082I300J265D01*
G02X855482I1200J-1061D01*
G03X856082I300J265D01*
G02X858500Y253287I1200J-1061D01*
G03Y252767I304J-260D01*
G02X858465Y250647I-1218J-1040D01*
G03Y250107I295J-270D01*
G02X858500Y247987I-1183J-1080D01*
G03Y247467I304J-260D01*
G02X856082Y245366I-1218J-1040D01*
G03X855482I-300J-265D01*
G02X853082I-1200J1061D01*
G03X852482I-300J-265D01*
G02X850082I-1200J1061D01*
G03X849482I-300J-265D01*
G37*
G36*
G01X1663900Y249338D02*
G02X1662940Y248226I424J-1336D01*
G03X1662424Y248672I-395J65D01*
G02X1663384Y249784I-424J1336D01*
G03X1663900Y249338I395J-65D01*
G37*
G36*
G01X718606Y249173D02*
G02X718591Y250691I-1186J747D01*
G03X719264Y250697I335J219D01*
G02X721584Y250774I1186J-747D01*
G03X722239Y250786I323J236D01*
G02X724545Y250809I1161J-786D01*
G03X725195Y250805I326J231D01*
G02X725183Y249170I1133J-826D01*
G03X724533Y249174I-326J-231D01*
G02X722266Y249176I-1133J826D01*
G03X721611Y249164I-323J-236D01*
G02X719279Y249179I-1161J786D01*
G03X718606Y249173I-335J-219D01*
G37*
G36*
G01X658864Y249391D02*
G02X658783Y251062I-1164J781D01*
G03X659424Y251093I309J254D01*
G02X659505Y249422I1164J-781D01*
G03X658864Y249391I-309J-254D01*
G37*
G36*
G01X1500777Y249858D02*
G02X1500262Y251528I-1305J512D01*
G03X1500860Y251712I226J330D01*
G02X1501375Y250042I1305J-512D01*
G03X1500777Y249858I-226J-330D01*
G37*
G36*
G01X1588322Y250980D02*
G02X1587633Y252491I-1372J287D01*
G03X1588220Y252759I195J349D01*
G02X1588909Y251248I1372J-287D01*
G03X1588322Y250980I-195J-349D01*
G37*
G36*
G01X1440096Y254445D02*
G02X1438370Y253545I-396J-1345D01*
G03X1438104Y254055I-379J127D01*
G02X1437463Y256344I396J1345D01*
G03X1437308Y256987I-296J269D01*
G02X1438837Y257356I492J1313D01*
G03X1438992Y256713I296J-269D01*
G02X1439830Y254955I-492J-1313D01*
G03X1440096Y254445I379J-127D01*
G37*
G36*
G01X1859705Y253139D02*
G02X1859613Y254436I-1285J561D01*
G03X1860320Y254486I340J210D01*
G02X1862690Y254813I1285J-561D01*
G03X1863289Y254791I309J254D01*
G02X1863220Y252937I1016J-966D01*
G03X1862621Y252959I-309J-254D01*
G02X1860412Y253189I-1016J966D01*
G03X1859705Y253139I-340J-210D01*
G37*
G36*
G01X749809Y253142D02*
G02X749663Y255019I-1109J858D01*
G03X750254Y255065I275J291D01*
G02X752491Y255039I1109J-858D01*
G03X753135I322J238D01*
G02Y253375I1128J-832D01*
G03X752491I-322J-238D01*
G02X750400Y253188I-1128J832D01*
G03X749809Y253142I-275J-291D01*
G37*
G36*
G01X1671347Y255991D02*
G02X1669766Y255613I-525J-1300D01*
G03X1669615Y256247I-301J263D01*
G02X1669027Y256694I525J1300D01*
G03X1668478Y256777I-318J-243D01*
G02X1666532Y258743I-811J1144D01*
G03X1666377Y259340I-324J234D01*
G02X1668103Y259788I591J1271D01*
G03X1668258Y259191I324J-234D01*
G02X1668780Y258773I-590J-1272D01*
G03X1669329Y258690I318J243D01*
G02X1671196Y256625I810J-1144D01*
G03X1671347Y255991I301J-263D01*
G37*
G36*
G01X1621068Y255879D02*
G02X1619424Y255874I-819J-1138D01*
G03X1619422Y256522I-236J323D01*
G02X1621066Y256527I819J1138D01*
G03X1621068Y255879I236J-323D01*
G37*
G36*
G01X1309929Y256611D02*
G02X1309831Y254805I1021J-961D01*
G03X1309221Y254839I-319J-241D01*
G02X1306892Y256305I-1021J961D01*
G03X1306534Y256849I-373J144D01*
G02X1307893Y257745I51J1401D01*
G03X1308251Y257201I373J-144D01*
G02X1309319Y256645I-51J-1401D01*
G03X1309929Y256611I319J241D01*
G37*
G36*
G01X1592716Y258175D02*
G02X1590523Y255841I-1118J-1147D01*
G03X1590003Y255856I-269J-297D01*
G02X1587961Y255884I-1004J1248D01*
G03X1587442Y255883I-259J-305D01*
G02X1585039Y256252I-1043J1216D01*
G03X1584369Y256267I-340J-211D01*
G02X1581977Y258363I-1323J903D01*
G03X1581983Y258953I-267J298D01*
G02X1584496Y260867I1095J1169D01*
G03X1585166Y260808I354J186D01*
G02X1587478Y261035I1264J-984D01*
G03X1587998Y261032I262J303D01*
G02X1590015Y261071I1033J-1225D01*
G03X1590534Y261094I246J315D01*
G02X1592722Y258754I1094J-1170D01*
G03X1592716Y258175I273J-292D01*
G37*
G36*
G01X643632Y262228D02*
G02X641968I-832J-1128D01*
G03Y262872I-238J322D01*
G02X642408Y265346I832J1128D01*
G03X642583Y266008I-112J384D01*
G02X642443Y267787I1008J974D01*
G03X642279Y268382I-328J230D01*
G02X644003Y268856I576J1278D01*
G03X644167Y268261I328J-230D01*
G02X643983Y265637I-576J-1278D01*
G03X643808Y264975I112J-384D01*
G02X643632Y262872I-1008J-975D01*
G03Y262228I238J-322D01*
G37*
G36*
G01X445821Y262562D02*
G02X444136Y262342I-698J-1216D01*
G03X444054Y262972I-282J284D01*
G02X443931Y265325I698J1216D01*
G03X443855Y266017I-234J325D01*
G02X445229Y266168I554J1288D01*
G03X445305Y265476I234J-325D01*
G02X445739Y263192I-553J-1288D01*
G03X445821Y262562I282J-284D01*
G37*
G36*
G01X1087254Y263369D02*
G02X1084819Y263312I-1193J-1069D01*
G03X1084807Y263831I-310J252D01*
G02X1087551Y265303I1193J1069D01*
G03X1087913Y265247I193J51D01*
G02X1088053Y265432I1184J-751D01*
G03X1088031Y265987I-299J266D01*
G02X1090047Y266068I969J1013D01*
G03X1090069Y265513I299J-266D01*
G02X1090267Y265277I-969J-1014D01*
G03X1090933I333J222D01*
G02X1091255Y265619I1167J-777D01*
G03X1091299Y266218I-241J319D01*
G02X1093145Y266081I1001J982D01*
G03X1093101Y265482I241J-319D01*
G02X1090933Y263723I-1001J-982D01*
G03X1090267I-333J-222D01*
G02X1087763Y264079I-1167J777D01*
G03X1087397Y264117I-191J-60D01*
G02X1087242Y263888I-1399J780D01*
G03X1087254Y263369I310J-252D01*
G37*
G36*
G01X440857Y264577D02*
G02X439243Y265001I-1093J-878D01*
G03X439407Y265622I-148J371D01*
G02X441021Y265198I1093J878D01*
G03X440857Y264577I148J-371D01*
G37*
G36*
G01X424225Y263565D02*
G02X421854Y263681I-1133J1132D01*
G03X421274Y263721I-309J-254D01*
G02X418988Y263837I-1086J1178D01*
G03X418390I-299J-265D01*
G02X415989Y263839I-1200J1062D01*
G03X415389I-300J-265D01*
G02X412988Y263838I-1201J1060D01*
G03X412388I-300J-265D01*
G02X409750Y264193I-1200J1061D01*
G03X409032I-359J-176D01*
G02X406394Y263838I-1438J706D01*
G03X405794I-300J-265D01*
G02Y265960I-1200J1061D01*
G03X406394I300J265D01*
G02X409032Y265605I1200J-1061D01*
G03X409750I359J176D01*
G02X412388Y265960I1438J-706D01*
G03X412988I300J265D01*
G02X415389Y265959I1200J-1061D01*
G03X415989I300J265D01*
G02X418390Y265961I1201J-1060D01*
G03X418988I299J265D01*
G02X421426Y265915I1199J-1062D01*
G03X422006Y265875I309J254D01*
G02X424215Y265840I1086J-1178D01*
G03X424778Y265842I280J285D01*
G02X424788Y263567I1133J-1133D01*
G03X424225Y263565I-280J-285D01*
G37*
G36*
G01X392061Y264122D02*
G02Y265676I-1167J777D01*
G03X392727I333J222D01*
G02Y264122I1167J-777D01*
G03X392061I-333J-222D01*
G37*
G36*
G01X398561D02*
G02Y265676I-1167J777D01*
G03X399227I333J222D01*
G02Y264122I1167J-777D01*
G03X398561I-333J-222D01*
G37*
G36*
G01X1041669D02*
G02Y265676I-1167J777D01*
G03X1042335I333J222D01*
G02Y264122I1167J-777D01*
G03X1041669I-333J-222D01*
G37*
G36*
G01X1048169D02*
G02Y265676I-1167J777D01*
G03X1048835I333J222D01*
G02Y264122I1167J-777D01*
G03X1048169I-333J-222D01*
G37*
G36*
G01X451230Y266487D02*
G02X450517Y264930I653J-1241D01*
G03X449941Y265194I-390J-90D01*
G02X450654Y266751I-653J1241D01*
G03X451230Y266487I390J90D01*
G37*
G36*
G01X1096538Y267024D02*
G02X1094862I-838J-1124D01*
G03Y267666I-239J321D01*
G02X1096538I838J1124D01*
G03Y267024I239J-321D01*
G37*
G36*
G01X126206Y267673D02*
G02X124199Y265687I-643J-1357D01*
G03X123515Y265758I-363J-168D01*
G02X121349Y268053I-1284J958D01*
G03X121409Y268673I-220J334D01*
G02X123704Y270907I1122J1143D01*
G03X124290I293J272D01*
G02X126194Y268391I1173J-1091D01*
G03X126206Y267673I183J-356D01*
G37*
G36*
G01X1481323Y266622D02*
G02X1479417Y268529I-1225J682D01*
G03Y269229I-194J350D01*
G02X1478873Y269773I681J1225D01*
G03X1478173I-350J-194D01*
G02X1475723I-1225J681D01*
G03X1475023I-350J-194D01*
G02X1472573Y269772I-1225J681D01*
G03X1471874I-349J-194D01*
G02X1469967Y271679I-1225J682D01*
G03Y272378I-194J350D01*
G02X1469968Y274828I682J1225D01*
G03Y275528I-194J350D01*
G02X1469967Y277978I681J1225D01*
G03Y278677I-194J350D01*
G02X1469968Y281127I682J1225D01*
G03Y281827I-194J350D01*
G02Y284277I681J1225D01*
G03Y284977I-194J350D01*
G02X1471874Y286884I681J1225D01*
G03X1472573I350J194D01*
G02X1473116Y287427I1225J-682D01*
G03Y288126I-194J350D01*
G02X1475023Y290032I682J1225D01*
G03X1475723I350J194D01*
G02X1477630Y288126I1225J-681D01*
G03Y287427I194J-350D01*
G02X1478173Y286883I-683J-1224D01*
G03X1478873I350J194D01*
G02X1481323Y286884I1225J-681D01*
G03X1482022I350J194D01*
G02X1482565Y287427I1225J-682D01*
G03Y288126I-194J350D01*
G02X1483929I682J1225D01*
G03Y287427I194J-350D01*
G02X1484472Y286883I-683J-1224D01*
G03X1485172I350J194D01*
G02X1487622Y286884I1225J-681D01*
G03X1488321I350J194D01*
G02Y285520I1225J-682D01*
G03X1487622I-349J-194D01*
G02X1487078Y284977I-1224J683D01*
G03Y284277I194J-350D01*
G02X1485172Y282371I-681J-1225D01*
G03X1484472I-350J-194D01*
G02X1483928Y281827I-1225J681D01*
G03Y281127I194J-350D01*
G02X1482566I-681J-1225D01*
G03Y281827I-194J350D01*
G02X1482022Y282370I680J1226D01*
G03X1481323I-349J-194D01*
G02X1479417Y284277I-1225J682D01*
G03Y284977I-194J350D01*
G02X1478873Y285521I681J1225D01*
G03X1478173I-350J-194D01*
G02X1475723I-1225J681D01*
G03X1475023I-350J-194D01*
G02X1474479Y284977I-1225J681D01*
G03Y284277I194J-350D01*
G02Y281827I-681J-1225D01*
G03Y281127I194J-350D01*
G02X1475023Y280583I-681J-1225D01*
G03X1475723I350J194D01*
G02X1477630Y278677I1225J-681D01*
G03Y277978I194J-350D01*
G02X1478173Y277434I-683J-1224D01*
G03X1478873I350J194D01*
G02X1480779Y275528I1225J-681D01*
G03Y274828I194J-350D01*
G02X1481323Y274285I-680J-1226D01*
G03X1482022I350J194D01*
G02X1483929Y272378I1225J-682D01*
G03Y271679I194J-350D01*
G02X1484472Y271135I-683J-1224D01*
G03X1485172I350J194D01*
G02Y269773I1225J-681D01*
G03X1484472I-350J-194D01*
G02X1483928Y269229I-1225J681D01*
G03Y268529I194J-350D01*
G02X1482022Y266622I-681J-1225D01*
G03X1481323I-349J-194D01*
G37*
G36*
G01X653393Y271818D02*
G02X651851Y271716I-694J-1218D01*
G03X651807Y272382I-242J318D01*
G02X653349Y272484I694J1218D01*
G03X653393Y271818I242J-318D01*
G37*
G36*
G01X710700Y273831D02*
G02X709004Y273683I-751J-1184D01*
G03X708949Y274316I-269J295D01*
G02X708692Y276474I751J1184D01*
G03X708670Y277051I-288J278D01*
G02X708511Y277217I930J1049D01*
G03X707889I-311J-252D01*
G02Y278983I-1089J883D01*
G03X708511I311J252D01*
G02X710608Y277126I1090J-882D01*
G03X710630Y276549I288J-278D01*
G02X710645Y274464I-930J-1049D01*
G03X710700Y273831I269J-295D01*
G37*
G36*
G01X1624564Y272426D02*
G02X1624542Y274148I-1117J847D01*
G03X1625174Y274156I313J249D01*
G02X1625196Y272434I1117J-847D01*
G03X1624564Y272426I-313J-249D01*
G37*
G36*
G01X755577Y274494D02*
G02X754007Y274540I-819J-1138D01*
G03X754027Y275202I-214J338D01*
G02X755597Y275156I819J1138D01*
G03X755577Y274494I214J-338D01*
G37*
G36*
G01X128755Y274876D02*
G02X128442Y276539I-1255J625D01*
G03X129069Y276657I269J296D01*
G02X129382Y274994I1255J-625D01*
G03X128755Y274876I-269J-296D01*
G37*
G36*
G01X116300Y278684D02*
G02X114751Y278669I-763J-1176D01*
G03X114744Y279336I-224J331D01*
G02X116293Y279351I763J1176D01*
G03X116300Y278684I224J-331D01*
G37*
G36*
G01X765908D02*
G02X764359Y278669I-763J-1176D01*
G03X764352Y279336I-224J331D01*
G02X765901Y279351I763J1176D01*
G03X765908Y278684I224J-331D01*
G37*
G36*
G01X750187Y280386D02*
G02X748558Y280793I-1087J-886D01*
G03X748713Y281414I-155J369D01*
G02X750342Y281007I1087J886D01*
G03X750187Y280386I155J-369D01*
G37*
G36*
G01X690825Y282220D02*
G02X689271I-777J-1167D01*
G03Y282886I-222J333D01*
G02X690825I777J1167D01*
G03Y282220I222J-333D01*
G37*
G36*
G01X1495494Y282261D02*
G02X1495450Y280598I1106J-861D01*
G03X1494806Y280615I-328J-229D01*
G02X1494850Y282278I-1106J861D01*
G03X1495494Y282261I328J229D01*
G37*
G36*
G01X1405610Y282190D02*
G02X1402952Y282162I-1324J-461D01*
G03X1402465Y282671I-380J124D01*
G02X1403191Y283152I-373J1351D01*
G03X1403465Y282866I157J-124D01*
G02X1403822Y283052I820J-1138D01*
G03X1404068Y283561I-132J378D01*
G02X1405856Y282699I1324J461D01*
G03X1405610Y282190I132J-378D01*
G37*
G36*
G01X684678Y281366D02*
G02X684620Y282940I-1188J744D01*
G03X685282Y282964I323J236D01*
G02X685340Y281390I1188J-744D01*
G03X684678Y281366I-323J-236D01*
G37*
G36*
G01X59894Y282265D02*
G02X59782Y283892I-1194J735D01*
G03X60431Y283936I309J254D01*
G02X60965Y284438I1194J-735D01*
G03X61026Y285104I-188J353D01*
G02X62560Y284963I874J1096D01*
G03X62499Y284297I188J-353D01*
G02X60543Y282309I-874J-1096D01*
G03X59894Y282265I-309J-254D01*
G37*
G36*
G01X766364Y284716D02*
G02X765442Y285696I-1357J-353D01*
G03X765953Y286177I124J380D01*
G02X765923Y286323I1357J355D01*
G03X765406Y286644I-395J-60D01*
G02X766367Y288187I-426J1336D01*
G03X766884Y287866I395J60D01*
G02X766875Y285197I426J-1336D01*
G03X766364Y284716I-124J-380D01*
G37*
G36*
G01X656121Y285442D02*
G02X654689Y285967I-1121J-842D01*
G03X654921Y286597I-88J390D01*
G02X656353Y286072I1121J842D01*
G03X656121Y285442I88J-390D01*
G37*
G36*
G01X1357775Y285582D02*
G02X1357735Y284295I1225J-682D01*
G03X1357025Y284318I-361J-172D01*
G02X1357065Y285605I-1225J682D01*
G03X1357775Y285582I361J172D01*
G37*
G36*
G01X1116937Y288227D02*
G02X1115684Y287313I62J-1401D01*
G03X1115292Y287851I-375J139D01*
G02X1116545Y288765I-62J1401D01*
G03X1116937Y288227I375J-139D01*
G37*
G36*
G01X465845Y293836D02*
G02X464680Y292661I221J-1384D01*
G03X464221Y293116I-396J60D01*
G02X465386Y294291I-221J1384D01*
G03X465845Y293836I396J-60D01*
G37*
G36*
G01X1048213Y293855D02*
G02X1048209Y291958I1289J-951D01*
G03X1047565Y291959I-322J-237D01*
G02X1047569Y293856I-1289J951D01*
G03X1048213Y293855I322J237D01*
G37*
G36*
G01X412461Y292127D02*
G02Y293681I-1167J777D01*
G03X413127I333J222D01*
G02Y292127I1167J-777D01*
G03X412461I-333J-222D01*
G37*
G36*
G01X419661D02*
G02Y293681I-1167J777D01*
G03X420327I333J222D01*
G02Y292127I1167J-777D01*
G03X419661I-333J-222D01*
G37*
G36*
G01X426861D02*
G02Y293681I-1167J777D01*
G03X427527I333J222D01*
G02Y292127I1167J-777D01*
G03X426861I-333J-222D01*
G37*
G36*
G01X434061D02*
G02Y293681I-1167J777D01*
G03X434727I333J222D01*
G02Y292127I1167J-777D01*
G03X434061I-333J-222D01*
G37*
G36*
G01X441261D02*
G02Y293681I-1167J777D01*
G03X441927I333J222D01*
G02Y292127I1167J-777D01*
G03X441261I-333J-222D01*
G37*
G36*
G01X1062069D02*
G02Y293681I-1167J777D01*
G03X1062735I333J222D01*
G02Y292127I1167J-777D01*
G03X1062069I-333J-222D01*
G37*
G36*
G01X1069269D02*
G02Y293681I-1167J777D01*
G03X1069935I333J222D01*
G02Y292127I1167J-777D01*
G03X1069269I-333J-222D01*
G37*
G36*
G01X1076469D02*
G02Y293681I-1167J777D01*
G03X1077135I333J222D01*
G02Y292127I1167J-777D01*
G03X1076469I-333J-222D01*
G37*
G36*
G01X1083669D02*
G02Y293681I-1167J777D01*
G03X1084335I333J222D01*
G02Y292127I1167J-777D01*
G03X1083669I-333J-222D01*
G37*
G36*
G01X1090869D02*
G02Y293681I-1167J777D01*
G03X1091535I333J222D01*
G02Y292127I1167J-777D01*
G03X1090869I-333J-222D01*
G37*
G36*
G01X1321162Y296032D02*
G02X1320246Y295063I438J-1332D01*
G03X1319735Y295546I-387J103D01*
G02X1320651Y296515I-438J1332D01*
G03X1321162Y296032I387J-103D01*
G37*
G36*
G01X1475023Y294968D02*
G02X1473116Y296874I-1225J681D01*
G03Y297573I-194J350D01*
G02X1472573Y298116I682J1225D01*
G03X1471874I-349J-194D01*
G02X1469968Y300023I-1225J682D01*
G03Y300723I-194J350D01*
G02Y303173I681J1225D01*
G03Y303873I-194J350D01*
G02X1469967Y306323I681J1225D01*
G03Y307022I-194J350D01*
G02X1469968Y309472I682J1225D01*
G03Y310172I-194J350D01*
G02X1469967Y312622I681J1225D01*
G03Y313321I-194J350D01*
G02X1471874Y315228I682J1225D01*
G03X1472573I350J194D01*
G02X1474480Y313321I1225J-682D01*
G03Y312622I194J-350D01*
G02X1475023Y312078I-683J-1224D01*
G03X1475723I350J194D01*
G02X1478173I1225J-681D01*
G03X1478873I350J194D01*
G02X1479416Y312622I1226J-680D01*
G03Y313321I-194J350D01*
G02X1481323Y315228I682J1225D01*
G03X1482022I350J194D01*
G02X1484472Y315227I1225J-682D01*
G03X1485172I350J194D01*
G02X1485715Y315771I1226J-680D01*
G03Y316470I-194J349D01*
G02X1487621Y318377I681J1226D01*
G03X1488321I350J194D01*
G02Y317015I1225J-681D01*
G03X1487621I-350J-194D01*
G02X1487078Y316471I-1226J680D01*
G03Y315772I194J-349D01*
G02X1485172Y313865I-681J-1226D01*
G03X1484472I-350J-194D01*
G02X1483929Y313321I-1226J680D01*
G03Y312622I194J-350D01*
G02X1482022Y310715I-682J-1225D01*
G03X1481323I-349J-194D01*
G02X1480779Y310172I-1224J683D01*
G03Y309472I194J-350D01*
G02X1478873Y307566I-681J-1225D01*
G03X1478173I-350J-194D01*
G02X1477630Y307022I-1226J680D01*
G03Y306323I194J-350D01*
G02X1475723Y304417I-682J-1225D01*
G03X1475023I-350J-194D01*
G02X1474479Y303873I-1225J681D01*
G03Y303173I194J-350D01*
G02Y300723I-681J-1225D01*
G03Y300023I194J-350D01*
G02X1475023Y299479I-681J-1225D01*
G03X1475723I350J194D01*
G02X1478173I1225J-681D01*
G03X1478873I350J194D01*
G02X1479417Y300023I1225J-681D01*
G03Y300723I-194J350D01*
G02X1481323Y302630I681J1225D01*
G03X1482022I350J194D01*
G02X1482566Y303173I1224J-683D01*
G03Y303873I-194J350D01*
G02X1484472Y305779I681J1225D01*
G03X1485172I350J194D01*
G02X1485715Y306323I1226J-680D01*
G03Y307022I-194J350D01*
G02X1487622Y308929I682J1225D01*
G03X1488321I350J194D01*
G02X1488865Y309472I1224J-683D01*
G03Y310172I-194J350D01*
G02X1490777Y312067I681J1225D01*
G03X1491478Y312062I352J191D01*
G02X1492031Y312608I1223J-685D01*
G03Y313312I-190J352D01*
G02X1493864Y315321I665J1234D01*
G03X1494531I334J221D01*
G02X1496328Y313293I1168J-775D01*
G03X1496317Y312584I179J-357D01*
G02X1494496Y310555I-666J-1234D01*
G03X1493841Y310561I-330J-226D01*
G02X1491469Y310706I-1141J815D01*
G03X1490768Y310711I-352J-191D01*
G02X1490227Y310172I-1222J686D01*
G03Y309472I194J-350D01*
G02X1488321Y307565I-681J-1225D01*
G03X1487622I-349J-194D01*
G02X1487079Y307022I-1225J682D01*
G03Y306323I194J-350D01*
G02X1487078Y303873I-682J-1225D01*
G03Y303173I194J-350D01*
G02X1487622Y302630I-680J-1226D01*
G03X1488321I350J194D01*
G02Y301266I1225J-682D01*
G03X1487622I-349J-194D01*
G02X1487078Y300723I-1224J683D01*
G03Y300023I194J-350D01*
G02X1487079Y297573I-681J-1225D01*
G03Y296874I194J-349D01*
G02X1485715I-682J-1225D01*
G03Y297573I-194J350D01*
G02X1485172Y298117I683J1224D01*
G03X1484472I-350J-194D01*
G02X1482022Y298116I-1225J681D01*
G03X1481323I-349J-194D01*
G02X1480780Y297573I-1225J682D01*
G03Y296874I194J-349D01*
G02X1478873Y294968I-682J-1225D01*
G03X1478173I-350J-194D01*
G02X1475723I-1225J681D01*
G03X1475023I-350J-194D01*
G37*
G36*
G01X1115777Y297174D02*
G02X1114706Y295993I319J-1365D01*
G03X1114219Y296435I-397J52D01*
G02X1115290Y297616I-319J1365D01*
G03X1115777Y297174I397J-52D01*
G37*
G36*
G01X59608Y298174D02*
G02X57670Y298249I-1008J-974D01*
G03X57692Y298826I-266J299D01*
G02X57830Y300900I1008J975D01*
G03X57808Y301543I-248J313D01*
G02X59470Y301600I792J1157D01*
G03X59492Y300957I248J-313D01*
G02X59630Y298751I-792J-1157D01*
G03X59608Y298174I266J-299D01*
G37*
G36*
G01X672778Y298889D02*
G02X672637Y297518I1144J-810D01*
G03X671944Y297589I-367J-160D01*
G02X669711Y297517I-1144J811D01*
G03X669089I-311J-252D01*
G02Y299283I-1089J883D01*
G03X669711I311J252D01*
G02X672085Y298960I1089J-883D01*
G03X672778Y298889I367J160D01*
G37*
G36*
G01X126357Y299591D02*
G02X124199Y297687I-794J-1275D01*
G03X123515Y297758I-363J-168D01*
G02X121403Y300088I-1284J958D01*
G03X121503Y300687I-206J342D01*
G02X123904Y302807I1228J1029D01*
G03X124490I293J272D01*
G02X126388Y300287I1173J-1091D01*
G03X126357Y299591I181J-357D01*
G37*
G36*
G01X4973Y301570D02*
G02Y303124I-1167J777D01*
G03X5639I333J222D01*
G02Y301570I1167J-777D01*
G03X4973I-333J-222D01*
G37*
G36*
G01X848882Y305666D02*
G02X846464Y307767I-1200J1061D01*
G03Y308287I-304J260D01*
G02X846499Y310407I1218J1040D01*
G03Y310947I-295J270D01*
G02X846225Y311362I1184J1079D01*
G03X845549Y311447I-364J-166D01*
G02X845757Y313115I-1249J1003D01*
G03X846433Y313030I364J166D01*
G02X846464Y313067I1243J-1010D01*
G03Y313587I-304J260D01*
G02X848882Y315688I1218J1040D01*
G03X849482I300J265D01*
G02X851882I1200J-1061D01*
G03X852482I300J265D01*
G02X854882I1200J-1061D01*
G03X855482I300J265D01*
G02X857900Y313587I1200J-1061D01*
G03Y313067I304J-260D01*
G02X857865Y310947I-1218J-1040D01*
G03Y310407I295J-270D01*
G02X857900Y308287I-1183J-1080D01*
G03Y307767I304J-260D01*
G02X855482Y305666I-1218J-1040D01*
G03X854882I-300J-265D01*
G02X852482I-1200J1061D01*
G03X851882I-300J-265D01*
G02X849482I-1200J1061D01*
G03X848882I-300J-265D01*
G37*
G36*
G01X1506795Y307781D02*
G02X1505065Y307774I-861J-1107D01*
G03X1505063Y308403I-248J314D01*
G02X1506793Y308410I861J1107D01*
G03X1506795Y307781I248J-314D01*
G37*
G36*
G01X777591Y306631D02*
G02X777150Y308191I-1321J469D01*
G03X777779Y308369I252J311D01*
G02X778220Y306809I1321J-469D01*
G03X777591Y306631I-252J-311D01*
G37*
G36*
G01X128755Y306876D02*
G02X128442Y308539I-1255J625D01*
G03X129069Y308657I269J296D01*
G02X129382Y306994I1255J-625D01*
G03X128755Y306876I-269J-296D01*
G37*
G36*
G01X1104766Y308814D02*
G02X1102437Y307365I-1010J-972D01*
G03X1101882Y307587I-376J-136D01*
G02X1099937Y308365I-626J1254D01*
G03X1099382Y308587I-376J-136D01*
G02X1097553Y309122I-626J1254D01*
G03X1096875Y309136I-343J-205D01*
G02X1094573Y309072I-1173J768D01*
G03X1093919Y309058I-322J-237D01*
G02X1091553Y309122I-1163J783D01*
G03X1090875Y309136I-343J-205D01*
G02X1090905Y310623I-1173J767D01*
G03X1091583Y310609I343J205D01*
G02X1093885Y310673I1173J-768D01*
G03X1094539Y310687I322J237D01*
G02X1096905Y310623I1163J-783D01*
G03X1097583Y310609I343J205D01*
G02X1100075Y310317I1173J-768D01*
G03X1100630Y310095I376J136D01*
G02X1101805Y310131I626J-1254D01*
G03X1102359Y310464I156J368D01*
G02X1104766Y309368I1397J-123D01*
G03Y308814I288J-277D01*
G37*
G36*
G01X116300Y310684D02*
G02X114751Y310669I-763J-1176D01*
G03X114744Y311336I-224J331D01*
G02X116293Y311351I763J1176D01*
G03X116300Y310684I224J-331D01*
G37*
G36*
G01X765908D02*
G02X764359Y310669I-763J-1176D01*
G03X764352Y311336I-224J331D01*
G02X765901Y311351I763J1176D01*
G03X765908Y310684I224J-331D01*
G37*
G36*
G01X377166Y310554D02*
G02X377121Y309128I1411J-758D01*
G03X376405Y309151I-364J-167D01*
G02X376450Y310577I-1411J758D01*
G03X377166Y310554I364J167D01*
G37*
G36*
G01X369925Y310765D02*
G02X369890Y308978I1312J-920D01*
G03X369226Y308991I-336J-216D01*
G02X369261Y310778I-1312J920D01*
G03X369925Y310765I336J216D01*
G37*
G36*
G01X441282Y309097D02*
G02Y310585I-1188J744D01*
G03X441960I339J213D01*
G02Y309097I1188J-744D01*
G03X441282I-339J-213D01*
G37*
G36*
G01X412461Y309127D02*
G02Y310681I-1167J777D01*
G03X413127I333J222D01*
G02Y309127I1167J-777D01*
G03X412461I-333J-222D01*
G37*
G36*
G01X419661D02*
G02Y310681I-1167J777D01*
G03X420327I333J222D01*
G02Y309127I1167J-777D01*
G03X419661I-333J-222D01*
G37*
G36*
G01X426861D02*
G02Y310681I-1167J777D01*
G03X427527I333J222D01*
G02Y309127I1167J-777D01*
G03X426861I-333J-222D01*
G37*
G36*
G01X434061D02*
G02Y310681I-1167J777D01*
G03X434727I333J222D01*
G02Y309127I1167J-777D01*
G03X434061I-333J-222D01*
G37*
G36*
G01X1062069D02*
G02Y310681I-1167J777D01*
G03X1062735I333J222D01*
G02Y309127I1167J-777D01*
G03X1062069I-333J-222D01*
G37*
G36*
G01X1069269D02*
G02Y310681I-1167J777D01*
G03X1069935I333J222D01*
G02Y309127I1167J-777D01*
G03X1069269I-333J-222D01*
G37*
G36*
G01X1076469D02*
G02Y310681I-1167J777D01*
G03X1077135I333J222D01*
G02Y309127I1167J-777D01*
G03X1076469I-333J-222D01*
G37*
G36*
G01X1083669D02*
G02Y310681I-1167J777D01*
G03X1084335I333J222D01*
G02Y309127I1167J-777D01*
G03X1083669I-333J-222D01*
G37*
G36*
G01X77011Y310638D02*
G02X74355Y309826I-1385J-221D01*
G03X73684Y309910I-362J-170D01*
G02X73871Y311392I-1084J890D01*
G03X74542Y311308I362J170D01*
G02X75699Y311818I1083J-890D01*
G03X76115Y312280I21J399D01*
G02X76713Y313660I1385J220D01*
G03X76668Y314348I-225J331D01*
G02X78087Y314440I631J1252D01*
G03X78132Y313752I225J-331D01*
G02X77427Y311100I-632J-1252D01*
G03X77011Y310638I-21J-399D01*
G37*
G36*
G01X766382Y316635D02*
G02X765182Y317754I-1375J-272D01*
G03X765625Y318228I50J397D01*
G02X765973Y319454I1375J272D01*
G03X765913Y320051I-293J272D01*
G02X767759Y320235I819J1138D01*
G03X767819Y319638I293J-272D01*
G02X766825Y317109I-819J-1138D01*
G03X766382Y316635I-50J-397D01*
G37*
G36*
G01X76830Y321972D02*
G02X76259Y320391I770J-1172D01*
G03X75657Y320608I-382J-117D01*
G02X73796Y320899I-770J1172D01*
G03X73178Y320903I-311J-252D01*
G02X73191Y322681I-1078J897D01*
G03X73809Y322677I311J252D01*
G02X76228Y322189I1078J-897D01*
G03X76830Y321972I382J117D01*
G37*
G36*
G01X94042Y324546D02*
G02X93615Y323004I896J-1078D01*
G03X92982Y323179I-377J-132D01*
G02X93409Y324721I-896J1078D01*
G03X94042Y324546I377J132D01*
G37*
G36*
G01X688114Y326341D02*
G02X686563Y326393I-815J-1141D01*
G03X686586Y327059I-210J341D01*
G02X688137Y327007I815J1141D01*
G03X688114Y326341I210J-341D01*
G37*
G36*
G01X637524Y328453D02*
G02X635905Y327850I-381J-1453D01*
G03X635691Y328459I-330J226D01*
G02X636069Y331202I409J1341D01*
G03X636420Y331777I-8J400D01*
G02X637712Y330988I1261J613D01*
G03X637361Y330413I8J-400D01*
G02X637286Y329053I-1261J-613D01*
G03X637524Y328453I339J-213D01*
G37*
G36*
G01X195992Y326582D02*
G02X193556Y326623I-1200J1061D01*
G03X192957Y326643I-308J-254D01*
G02X190464Y326847I-1165J1100D01*
G03X189837Y326893I-332J-224D01*
G02X187593Y329173I-1184J1079D01*
G03Y329773I-265J300D01*
G02X187561Y332145I1061J1201D01*
G03X187557Y332734I-273J293D01*
G02X187430Y332862I1072J1190D01*
G03X186830I-300J-265D01*
G02X184441Y334997I-1199J1062D01*
G03X184375Y335592I-297J268D01*
G02X184064Y335880I924J1309D01*
G03X183465Y335900I-308J-254D01*
G02X181100Y335939I-1165J1100D01*
G03X180500I-300J-265D01*
G02X178100I-1200J1061D01*
G03X177500I-300J-265D01*
G02X175100I-1200J1061D01*
G03X174500I-300J-265D01*
G02X172195Y338160I-1200J1061D01*
G03Y338740I-275J290D01*
G02X172558Y341320I1105J1160D01*
G03Y342028I-186J354D01*
G02X174500Y344509I742J1420D01*
G03X175100I300J265D01*
G02X177500I1200J-1061D01*
G03X178100I300J265D01*
G02X180500I1200J-1061D01*
G03X181100I300J265D01*
G02X183536Y344468I1200J-1061D01*
G03X184135Y344448I308J254D01*
G02X186500Y344409I1165J-1100D01*
G03X187100I300J265D01*
G02X189536Y344368I1200J-1061D01*
G03X190135Y344348I308J254D01*
G02X192114Y341868I1165J-1100D01*
G03Y341180I204J-344D01*
G02X190064Y338780I-815J-1380D01*
G03X189465Y338800I-308J-254D01*
G02X189361Y338700I-1161J1104D01*
G03Y338100I265J-300D01*
G02X189489Y335826I-1061J-1200D01*
G03X189555Y335231I297J-268D01*
G02X189723Y332751I-925J-1308D01*
G03X189727Y332162I273J-293D01*
G02X189715Y329773I-1073J-1189D01*
G03Y329173I265J-300D01*
G02X189982Y328869I-1060J-1201D01*
G03X190609Y328823I332J224D01*
G02X193028Y328763I1183J-1080D01*
G03X193627Y328743I308J254D01*
G02X195992Y328704I1165J-1100D01*
G03X196592I300J265D01*
G02Y326582I1200J-1061D01*
G03X195992I-300J-265D01*
G37*
G36*
G01X1514594Y328782D02*
G02X1513308Y328680I-545J-1292D01*
G03X1513252Y329388I-211J340D01*
G02X1514538Y329490I545J1292D01*
G03X1514594Y328782I211J-340D01*
G37*
G36*
G01X126430Y331542D02*
G02X124199Y329687I-867J-1226D01*
G03X123515Y329758I-363J-168D01*
G02X121500Y332142I-1284J958D01*
G03X121600Y332781I-182J356D01*
G02X124009Y334882I1131J1134D01*
G03X124562Y334799I319J241D01*
G02X126429Y332195I938J-1299D01*
G03X126430Y331542I232J-326D01*
G37*
G36*
G01X1106728Y335132D02*
G02X1104994Y335070I-828J-1132D01*
G03X1104972Y335698I-258J305D01*
G02X1106706Y335760I828J1132D01*
G03X1106728Y335132I258J-305D01*
G37*
G36*
G01X451673Y334540D02*
G02X449473Y334871I-973J1010D01*
G03X448830Y334949I-350J-194D01*
G02X449027Y336579I-1030J951D01*
G03X449670Y336501I350J194D01*
G02X451673Y336560I1030J-951D01*
G03X452227I277J288D01*
G02Y334540I973J-1010D01*
G03X451673I-277J-288D01*
G37*
G36*
G01X69546Y336983D02*
G02X67743Y337379I-1128J-833D01*
G03X67872Y337967I-193J350D01*
G02X67735Y338195I1128J833D01*
G03X67025Y338218I-361J-172D01*
G02X64643Y338108I-1225J682D01*
G03X64000Y338130I-330J-226D01*
G02X64057Y339792I-1100J870D01*
G03X64700Y339770I330J226D01*
G02X67065Y339505I1100J-870D01*
G03X67775Y339482I361J172D01*
G02X70167Y339577I1225J-682D01*
G03X70833I333J222D01*
G02X73073Y339702I1167J-777D01*
G03X73695Y339713I307J257D01*
G02X73727Y337948I1105J-863D01*
G03X73105Y337937I-307J-257D01*
G02X70833Y338023I-1105J863D01*
G03X70167I-333J-222D01*
G02X69675Y337571I-1167J777D01*
G03X69546Y336983I193J-350D01*
G37*
G36*
G01X1409740Y336269D02*
G02X1408622Y337811I-1392J167D01*
G03X1409097Y338155I78J392D01*
G02X1409130Y338332I1392J-168D01*
G03X1408866Y338568I-194J49D01*
G02X1409775Y339789I-490J1314D01*
G03X1410244Y339368I399J-27D01*
G02X1410215Y336613I245J-1380D01*
G03X1409740Y336269I-78J-392D01*
G37*
G36*
G01X1101253Y337632D02*
G02X1101084Y336002I1047J-932D01*
G03X1100438Y336069I-347J-199D01*
G02X1100607Y337699I-1047J932D01*
G03X1101253Y337632I347J199D01*
G37*
G36*
G01X1483734Y337311D02*
G02X1482776Y338273I-1348J-385D01*
G03X1483272Y338767I112J384D01*
G02X1483219Y339088I1348J387D01*
G03X1482768Y339466I-399J-18D01*
G02X1483986Y340920I-183J1390D01*
G03X1484437Y340542I399J18D01*
G02X1484230Y337805I183J-1390D01*
G03X1483734Y337311I-112J-384D01*
G37*
G36*
G01X53874Y338591D02*
G02X52942Y338875I-849J-1116D01*
G03X53248Y339502I-23J399D01*
G02X55802Y340299I1152J798D01*
G03X56224Y339900I400J0D01*
G02X57463Y339283I76J-1400D01*
G03X58162Y339350I331J224D01*
G02X58289Y338017I1290J-550D01*
G03X57590Y337950I-331J-224D01*
G02X54898Y338501I-1290J550D01*
G03X54476Y338900I-400J0D01*
G02X54045Y338944I-75J1400D01*
G03X53874Y338591I-50J-194D01*
G37*
G36*
G01X1488712Y338646D02*
G02X1487060Y338620I-808J-1146D01*
G03X1487050Y339266I-240J319D01*
G02X1488702Y339292I808J1146D01*
G03X1488712Y338646I240J-319D01*
G37*
G36*
G01X99363Y339304D02*
G02X97886Y339236I-684J-1224D01*
G03X97855Y339915I-226J330D01*
G02X99332Y339983I684J1224D01*
G03X99363Y339304I226J-330D01*
G37*
G36*
G01X399315Y337564D02*
G02Y339118I-1167J777D01*
G03X399981I333J222D01*
G02X402121Y339351I1167J-777D01*
G03X402675I277J288D01*
G02Y337331I973J-1010D01*
G03X402121I-277J-288D01*
G02X399981Y337564I-973J1010D01*
G03X399315I-333J-222D01*
G37*
G36*
G01X1048923D02*
G02Y339118I-1167J777D01*
G03X1049589I333J222D01*
G02X1051885Y339173I1167J-777D01*
G03X1052539Y339187I322J237D01*
G02X1054735Y339352I1163J-783D01*
G03X1055382Y339433I295J270D01*
G02X1055534Y337681I1410J-760D01*
G03X1054883Y337649I-314J-248D01*
G02X1052573Y337572I-1181J755D01*
G03X1051919Y337558I-322J-237D01*
G02X1049589Y337564I-1163J783D01*
G03X1048923I-333J-222D01*
G37*
G36*
G01X418263Y339420D02*
G02X418240Y337812I1137J-820D01*
G03X417585Y337821I-331J-225D01*
G02X415475Y337631I-1137J820D01*
G03X414921I-277J-288D01*
G02X412781Y337864I-973J1010D01*
G03X412115I-333J-222D01*
G02Y339418I-1167J777D01*
G03X412781I333J222D01*
G02X414921Y339651I1167J-777D01*
G03X415475I277J288D01*
G02X417608Y339429I973J-1010D01*
G03X418263Y339420I331J225D01*
G37*
G36*
G01X128370Y338700D02*
G02X127731Y340196I-1370J299D01*
G03X128330Y340452I208J341D01*
G02X128969Y338956I1370J-299D01*
G03X128370Y338700I-208J-341D01*
G37*
G36*
G01X1564167Y340223D02*
G02Y341777I-1167J777D01*
G03X1564833I333J222D01*
G02Y340223I1167J-777D01*
G03X1564167I-333J-222D01*
G37*
G36*
G01X116300Y342684D02*
G02X114751Y342669I-763J-1176D01*
G03X114744Y343336I-224J331D01*
G02X116293Y343351I763J1176D01*
G03X116300Y342684I224J-331D01*
G37*
G36*
G01X765908D02*
G02X764359Y342669I-763J-1176D01*
G03X764352Y343336I-224J331D01*
G02X765901Y343351I763J1176D01*
G03X765908Y342684I224J-331D01*
G37*
G36*
G01X50027Y344982D02*
G02X48007I-1010J-973D01*
G03Y345536I-288J277D01*
G02X48048Y347522I1010J973D01*
G03X48070Y348077I-277J289D01*
G02X48097Y349971I1047J932D01*
G03X48091Y350526I-291J274D01*
G02X48312Y352675I1000J983D01*
G03X48314Y353339I-222J333D01*
G02X49879Y353334I786J1161D01*
G03X49877Y352670I222J-333D01*
G02X50336Y352153I-786J-1161D01*
G03X50960Y352040I355J184D01*
G02X50557Y350596I940J-1041D01*
G03X50207Y350660I-191J-57D01*
G02X50111Y350547I-1115J850D01*
G03X50117Y349992I291J-274D01*
G02X50086Y347996I-1000J-983D01*
G03X50064Y347441I277J-289D01*
G02X50244Y347187I-1047J-933D01*
G03X50889Y347111I350J194D01*
G02X50696Y345486I1034J-947D01*
G03X50051Y345562I-350J-194D01*
G02X50027Y345536I-1042J938D01*
G03Y344982I288J-277D01*
G37*
G36*
G01X102884Y347278D02*
G02X101000Y347391I-1004J-978D01*
G03X101036Y347982I-251J312D01*
G02X101165Y350055I1004J978D01*
G03X101169Y350676I-250J312D01*
G02X101336Y352959I891J1082D01*
G03X101358Y353630I-207J343D01*
G02X102884Y353580I802J1150D01*
G03X102862Y352909I207J-343D01*
G02X102935Y350664I-802J-1150D01*
G03X102931Y350043I250J-312D01*
G02X102920Y347869I-891J-1083D01*
G03X102884Y347278I251J-312D01*
G37*
G36*
G01X1331530Y347307D02*
G02X1331474Y345600I1083J-890D01*
G03X1330840Y345621I-325J-233D01*
G02X1330896Y347328I-1083J890D01*
G03X1331530Y347307I325J233D01*
G37*
G36*
G01X65595Y349131D02*
G02X65121Y347275I755J-1181D01*
G03X64555Y347419I-350J-193D01*
G02X62757Y347664I-755J1181D01*
G03X62113Y347597I-298J-267D01*
G02X61943Y349236I-1213J702D01*
G03X62587Y349303I298J267D01*
G02X65029Y349275I1213J-703D01*
G03X65595Y349131I350J193D01*
G37*
G36*
G01X1644113Y349711D02*
G02X1642615Y349988I-963J-1019D01*
G03X1642737Y350648I-153J370D01*
G02X1644235Y350371I963J1019D01*
G03X1644113Y349711I153J-370D01*
G37*
G36*
G01X1338882Y350962D02*
G02X1338203Y349606I715J-1206D01*
G03X1337601Y349907I-398J-43D01*
G02X1338280Y351263I-715J1206D01*
G03X1338882Y350962I398J43D01*
G37*
G36*
G01X1588979Y351651D02*
G02X1588978Y350340I1239J-656D01*
G03X1588271I-354J-187D01*
G02X1588272Y351651I-1239J656D01*
G03X1588979I354J187D01*
G37*
G36*
G01X696449Y352760D02*
G02X695006Y352697I-659J-1460D01*
G03X694996Y353401I-195J349D01*
G02X694719Y355697I648J1243D01*
G03X694731Y356287I-264J300D01*
G02X696625Y356247I969J1013D01*
G03X696613Y355657I264J-300D01*
G02X696398Y353462I-969J-1013D01*
G03X696449Y352760I215J-337D01*
G37*
G36*
G01X1508004Y354215D02*
G02X1506340Y354241I-850J-1115D01*
G03X1506350Y354885I-232J326D01*
G02X1506271Y357050I850J1115D01*
G03Y357650I-265J300D01*
G02X1508129I929J1050D01*
G03Y357050I265J-300D01*
G02X1508014Y354859I-929J-1050D01*
G03X1508004Y354215I232J-326D01*
G37*
G36*
G01X1539469Y360376D02*
G02X1537451Y360293I-969J-1013D01*
G03X1537428Y360848I-299J266D01*
G02X1537462Y362906I969J1013D01*
G03X1537418Y363536I-267J298D01*
G02X1539135Y363655I782J1164D01*
G03X1539179Y363025I267J-298D01*
G02X1539446Y360931I-782J-1164D01*
G03X1539469Y360376I299J-266D01*
G37*
G36*
G01X1343883Y360683D02*
G02X1343419Y359074I848J-1116D01*
G03X1342802Y359252I-375J-141D01*
G02X1343266Y360861I-848J1116D01*
G03X1343883Y360683I375J141D01*
G37*
G36*
G01X102517Y361294D02*
G02X100999Y361304I-767J-1174D01*
G03X101003Y361976I-215J337D01*
G02X102521Y361966I767J1174D01*
G03X102517Y361294I215J-337D01*
G37*
G36*
G01X1357712Y360037D02*
G02X1357659Y361417I-1246J643D01*
G03X1358354Y361443I340J210D01*
G02X1358407Y360063I1246J-643D01*
G03X1357712Y360037I-340J-210D01*
G37*
G36*
G01X1608786Y360618D02*
G02X1608339Y361947I-1374J277D01*
G03X1608996Y362167I265J300D01*
G02X1609443Y360838I1374J-277D01*
G03X1608786Y360618I-265J-300D01*
G37*
G36*
G01X60254Y363533D02*
G02X59542Y362141I680J-1226D01*
G03X58951Y362443I-397J-48D01*
G02X59663Y363835I-680J1226D01*
G03X60254Y363533I397J48D01*
G37*
G36*
G01X679038Y364209D02*
G02X677514Y363539I-308J-1368D01*
G03X677255Y364128I-347J199D01*
G02X678779Y364798I308J1368D01*
G03X679038Y364209I347J-199D01*
G37*
G36*
G01X174671Y362220D02*
G02X172670Y364668I-1200J1061D01*
G03X172655Y365369I-200J346D01*
G02X172339Y367987I745J1418D01*
G03Y368587I-265J300D01*
G02X174600Y370848I1061J1200D01*
G03X175200I300J265D01*
G02X177600I1200J-1061D01*
G03X178200I300J265D01*
G02X180600I1200J-1061D01*
G03X181200I300J265D01*
G02X183600I1200J-1061D01*
G03X184200I300J265D01*
G02X186600I1200J-1061D01*
G03X187200I300J265D01*
G02X189461Y368587I1200J-1061D01*
G03Y367987I265J-300D01*
G02X189201Y365400I-1061J-1200D01*
G03X189216Y364699I200J-346D01*
G02X187271Y362220I-745J-1418D01*
G03X186671I-300J-265D01*
G02X184271I-1200J1061D01*
G03X183671I-300J-265D01*
G02X181271I-1200J1061D01*
G03X180671I-300J-265D01*
G02X178271I-1200J1061D01*
G03X177671I-300J-265D01*
G02X175271I-1200J1061D01*
G03X174671I-300J-265D01*
G37*
G36*
G01X1381129Y371450D02*
G02X1379271I-929J-1050D01*
G03Y372050I-265J300D01*
G02X1378921Y372526I929J1050D01*
G03X1378233Y372599I-365J-164D01*
G02X1377889Y372267I-1131J828D01*
G03X1377862Y371625I224J-331D01*
G02X1375667Y370041I-883J-1089D01*
G03X1375083Y370239I-374J-142D01*
G02X1373399Y372466I-739J1192D01*
G03X1373369Y373082I-270J296D01*
G02X1375689Y374773I899J1203D01*
G03X1376297Y374575I378J129D01*
G02X1378382Y374002I806J-1147D01*
G03X1379070Y373929I365J164D01*
G02X1381129Y372050I1131J-829D01*
G03Y371450I265J-300D01*
G37*
G36*
G01X128750Y371148D02*
G02X128552Y372417I-1330J442D01*
G03X129255Y372527I323J236D01*
G02X129453Y371258I1330J-442D01*
G03X128750Y371148I-323J-236D01*
G37*
G36*
G01X764923Y374919D02*
G02X763374Y374904I-763J-1176D01*
G03X763367Y375571I-224J331D01*
G02X764916Y375586I763J1176D01*
G03X764923Y374919I224J-331D01*
G37*
G36*
G01X744900Y373222D02*
G02Y374778I-1400J778D01*
G03X745600I350J194D01*
G02X748400I1400J-778D01*
G03X749100I350J194D01*
G02X751900I1400J-778D01*
G03X752600I350J194D01*
G02Y373222I1400J-778D01*
G03X751900I-350J-194D01*
G02X749100I-1400J778D01*
G03X748400I-350J-194D01*
G02X745600I-1400J778D01*
G03X744900I-350J-194D01*
G37*
G36*
G01X1333536Y375536D02*
G02X1331725Y375503I-886J-1086D01*
G03X1331714Y376114I-264J301D01*
G02X1331623Y376195I886J1087D01*
G03X1331090Y376217I-279J-287D01*
G02X1329151Y376370I-890J1083D01*
G03X1328574Y376392I-299J-266D01*
G02X1326551Y376470I-974J1008D01*
G03X1325974Y376492I-299J-266D01*
G02X1323787Y376797I-974J1008D01*
G03X1323143Y376864I-346J-200D01*
G02X1320807Y377258I-1043J936D01*
G03X1320186Y377413I-369J-155D01*
G02X1320673Y378784I-886J1087D01*
G03X1321022Y378697I196J41D01*
G02X1321181Y378859I1077J-898D01*
G03X1321171Y379471I-262J302D01*
G02X1323113Y381479I883J1089D01*
G03X1323738Y381506I302J263D01*
G02X1324095Y381849I1135J-824D01*
G03Y382515I-222J333D01*
G02X1326062Y384424I777J1167D01*
G03X1326711Y384384I339J212D01*
G02X1328875Y384400I1089J-884D01*
G03X1329531Y384464I306J257D01*
G02X1329981Y384952I1226J-679D01*
G03Y385618I-222J333D01*
G02Y387952I777J1167D01*
G03Y388618I-222J333D01*
G02X1331535I777J1167D01*
G03Y387952I222J-333D01*
G02Y385618I-777J-1167D01*
G03Y384952I222J-333D01*
G02X1329683Y382885I-777J-1167D01*
G03X1329027Y382821I-306J-257D01*
G02X1328475Y382271I-1227J679D01*
G03X1328453Y381583I192J-351D01*
G02X1328666Y381416I-755J-1182D01*
G03X1329219Y381417I276J290D01*
G02X1331148Y381430I971J-1011D01*
G03X1331715Y381451I273J292D01*
G02X1331790Y379479I1033J-948D01*
G03X1331223Y379458I-273J-292D01*
G02X1330905Y379200I-1033J948D01*
G03X1330907Y378511I204J-344D01*
G02X1331177Y378305I-709J-1209D01*
G03X1331710Y378283I279J287D01*
G02X1333525Y376147I890J-1083D01*
G03X1333536Y375536I264J-301D01*
G37*
G36*
G01X1446261Y374114D02*
G02X1446234Y375724I-1161J786D01*
G03X1446889Y375736I323J236D01*
G02X1446916Y374126I1161J-786D01*
G03X1446261Y374114I-323J-236D01*
G37*
G36*
G01X1631819Y376659D02*
G02X1629911Y376593I-919J-1059D01*
G03X1629862Y377201I-283J283D01*
G02X1629557Y379511I938J1299D01*
G03X1629414Y380126I-310J252D01*
G02X1631156Y380607I586J1274D01*
G03X1631349Y380005I330J-226D01*
G02X1631825Y377269I-549J-1505D01*
G03X1631819Y376659I256J-308D01*
G37*
G36*
G01X752559Y380778D02*
G02X752489Y379058I1315J-915D01*
G03X751815Y379085I-346J-201D01*
G02X749100Y379222I-1315J915D01*
G03X748400I-350J-194D01*
G02X745600I-1400J778D01*
G03X744900I-350J-194D01*
G02Y380778I-1400J778D01*
G03X745600I350J194D01*
G02X748400I1400J-778D01*
G03X749100I350J194D01*
G02X751885Y380805I1400J-778D01*
G03X752559Y380778I346J201D01*
G37*
G36*
G01X766290Y380798D02*
G02X764936Y381765I-1333J-435D01*
G03X765310Y382289I-6J400D01*
G02X766009Y383974I1333J435D01*
G03X766122Y384602I-181J357D01*
G02X767789Y384300I1033J948D01*
G03X767676Y383672I181J-357D01*
G02X766664Y381322I-1033J-948D01*
G03X766290Y380798I6J-400D01*
G37*
G36*
G01X117981Y382436D02*
G02X117232Y381078I648J-1243D01*
G03X116648Y381400I-399J-33D01*
G02X115528Y383963I-649J1243D01*
G03X115764Y384490I-135J377D01*
G02X117535Y383696I1299J526D01*
G03X117299Y383169I135J-377D01*
G02X117397Y382758I-1299J-527D01*
G03X117981Y382436I399J33D01*
G37*
G36*
G01X1457707Y385768D02*
G02X1456192Y385728I-726J-1199D01*
G03X1456174Y386401I-225J331D01*
G02X1457689Y386441I726J1199D01*
G03X1457707Y385768I225J-331D01*
G37*
G36*
G01X744900Y385222D02*
G02Y386778I-1400J778D01*
G03X745600I350J194D01*
G02X748400I1400J-778D01*
G03X749100I350J194D01*
G02X751900I1400J-778D01*
G03X752600I350J194D01*
G02Y385222I1400J-778D01*
G03X751900I-350J-194D01*
G02X749100I-1400J778D01*
G03X748400I-350J-194D01*
G02X745600I-1400J778D01*
G03X744900I-350J-194D01*
G37*
G36*
G01X680301Y386975D02*
G02X678638Y386895I-777J-1167D01*
G03X678607Y387538I-253J310D01*
G02X680270Y387618I777J1167D01*
G03X680301Y386975I253J-310D01*
G37*
G36*
G01X1381928Y391468D02*
G02Y393132I-1128J832D01*
G03X1382572I322J238D01*
G02Y391468I1128J-832D01*
G03X1381928I-322J-238D01*
G37*
G36*
G01X1470953Y393463D02*
G02X1469582Y393653I-853J-1113D01*
G03X1469737Y394285I-148J371D01*
G02X1469538Y395811I1063J915D01*
G03X1469332Y396354I-360J174D01*
G02X1468706Y396871I542J1293D01*
G03X1468040I-333J-222D01*
G02X1465862Y396677I-1167J777D01*
G03X1465284I-289J-277D01*
G02Y398619I-1011J971D01*
G03X1465862I289J277D01*
G02X1468040Y398425I1011J-971D01*
G03X1468706I333J222D01*
G02X1471135Y397037I1167J-777D01*
G03X1471341Y396494I360J-174D01*
G02X1472183Y395433I-541J-1294D01*
G03X1472689Y395116I394J67D01*
G02X1471700Y393537I394J-1346D01*
G03X1471194Y393854I-394J-67D01*
G02X1471040Y393819I-387J1348D01*
G03X1470953Y393463I34J-197D01*
G37*
G36*
G01X126222Y395666D02*
G02X124199Y393687I-659J-1350D01*
G03X123515Y393758I-363J-168D01*
G02X121035Y395781I-1284J958D01*
G03X120989Y396358I-299J267D01*
G02X123293Y398546I1011J1243D01*
G03X123952Y398566I323J236D01*
G02X126178Y396360I1348J-866D01*
G03X126222Y395666I219J-335D01*
G37*
G36*
G01X1631023Y396730D02*
G02X1629663Y396770I-723J-1430D01*
G03X1629703Y397484I-159J367D01*
G02X1629491Y399767I697J1216D01*
G03X1629524Y400344I-260J304D01*
G02X1631459Y400233I1026J956D01*
G03X1631426Y399656I260J-304D01*
G02X1631025Y397445I-1026J-956D01*
G03X1631023Y396730I178J-358D01*
G37*
G36*
G01X1244795Y398467D02*
G02X1244034Y399589I-1396J-128D01*
G03X1244614Y399982I182J356D01*
G02X1245375Y398860I1396J128D01*
G03X1244795Y398467I-182J-356D01*
G37*
G36*
G01X1332810Y400430D02*
G02X1330695Y398590I-1039J-941D01*
G03X1330094Y398605I-307J-256D01*
G02X1327897Y398779I-1030J951D01*
G03X1327231I-333J-222D01*
G02X1324897I-1167J777D01*
G03X1324231I-333J-222D01*
G02X1322028Y398611I-1167J777D01*
G03X1321442Y398616I-295J-270D01*
G02X1319229Y398844I-1019J963D01*
G03X1318644Y398952I-341J-209D01*
G02X1316778Y401035I-857J1110D01*
G03Y401589I-288J277D01*
G02X1319048Y403176I1010J973D01*
G03X1319361Y403113I180J87D01*
G02X1319442Y403180I933J-1046D01*
G03X1319456Y403487I-121J159D01*
G02X1321567Y405301I944J1037D01*
G03X1322233I333J222D01*
G02X1324567I1167J-777D01*
G03X1325233I333J222D01*
G02X1327567I1167J-777D01*
G03X1328233I333J222D01*
G02X1330380Y405527I1167J-777D01*
G03X1330951Y405539I280J286D01*
G02X1332902Y403530I1022J-959D01*
G03X1332876Y402956I265J-300D01*
G02X1332829Y400986I-1020J-961D01*
G03X1332810Y400430I278J-288D01*
G37*
G36*
G01X1466215Y401593D02*
G02Y403147I-1167J777D01*
G03X1466881I333J222D01*
G02Y401593I1167J-777D01*
G03X1466215I-333J-222D01*
G37*
G36*
G01X175831Y403321D02*
G02X175784Y404774I-1222J688D01*
G03X176467Y404797I335J219D01*
G02X178913Y404794I1222J-688D01*
G03X179603Y404780I349J195D01*
G02X179575Y403364I1196J-732D01*
G03X178885Y403378I-349J-195D01*
G02X176514Y403344I-1196J731D01*
G03X175831Y403321I-335J-219D01*
G37*
G36*
G01X1198437Y406752D02*
G02X1196898Y406240I-408J-1341D01*
G03X1196692Y406859I-323J236D01*
G02X1198231Y407371I408J1341D01*
G03X1198437Y406752I323J-236D01*
G37*
G36*
G01X1467549Y405996D02*
G02Y407550I-1167J777D01*
G03X1468215I333J222D01*
G02Y405996I1167J-777D01*
G03X1467549I-333J-222D01*
G37*
G36*
G01X1513552Y408921D02*
G02X1511886Y408561I-598J-1268D01*
G03X1511752Y409182I-305J259D01*
G02X1511125Y409769I599J1268D01*
G03X1510425I-350J-194D01*
G02Y411131I-1225J681D01*
G03X1511125I350J194D01*
G02X1513418Y409542I1226J-680D01*
G03X1513552Y408921I305J-259D01*
G37*
G36*
G01X1613554Y410172D02*
G02X1611843Y409975I-729J-1198D01*
G03X1611771Y410602I-280J286D01*
G02X1613482Y410799I729J1198D01*
G03X1613554Y410172I280J-286D01*
G37*
G36*
G01X1440497Y410646D02*
G02X1439003Y410566I-684J-1224D01*
G03X1438967Y411242I-231J327D01*
G02X1440461Y411322I684J1224D01*
G03X1440497Y410646I231J-327D01*
G37*
G36*
G01X798376Y410593D02*
G02X797035Y411222I-1176J-763D01*
G03X797324Y411837I-47J397D01*
G02X798834Y413962I1176J763D01*
G03X799302Y414494I95J388D01*
G02X800276Y413638I1308J506D01*
G03X799808Y413106I-95J-388D01*
G02X798665Y411208I-1308J-506D01*
G03X798376Y410593I47J-397D01*
G37*
G36*
G01X1395067Y411723D02*
G02X1392890Y413473I-1167J778D01*
G03Y414027I-288J277D01*
G02X1393952Y416401I1010J973D01*
G03X1394357Y416888I14J400D01*
G02X1397076Y416819I1368J305D01*
G03X1397337Y416332I386J-107D01*
G02X1397910Y414027I-437J-1332D01*
G03Y413473I288J-277D01*
G02X1395733Y411723I-1010J-972D01*
G03X1395067I-333J-222D01*
G37*
G36*
G01X1535647Y412859D02*
G02X1535604Y414219I-1247J641D01*
G03X1536303Y414241I343J205D01*
G02X1536869Y414825I1246J-642D01*
G03Y415525I-194J350D01*
G02X1536325Y416069I681J1225D01*
G03X1535625I-350J-194D01*
G02Y417431I-1225J681D01*
G03X1536325I350J194D01*
G02X1538775I1225J-681D01*
G03X1539475I350J194D01*
G02X1541925I1225J-681D01*
G03X1542625I350J194D01*
G02X1545075I1225J-681D01*
G03X1545775I350J194D01*
G02Y416069I1225J-681D01*
G03X1545075I-350J-194D01*
G02X1544531Y415525I-1225J681D01*
G03Y414825I194J-350D01*
G02X1542625Y412919I-681J-1225D01*
G03X1541925I-350J-194D01*
G02X1539475I-1225J681D01*
G03X1538775I-350J-194D01*
G02X1536346Y412881I-1225J681D01*
G03X1535647Y412859I-343J-205D01*
G37*
G36*
G01X1516725Y412919D02*
G02Y414281I-1225J681D01*
G03X1517425I350J194D01*
G02X1517969Y414825I1225J-681D01*
G03Y415525I-194J350D01*
G02X1519331I681J1225D01*
G03Y414825I194J-350D01*
G02X1517425Y412919I-681J-1225D01*
G03X1516725I-350J-194D01*
G37*
G36*
G01X1526197Y412959D02*
G02X1524289Y414836I-1247J641D01*
G03X1524300Y415535I-189J353D01*
G02X1525661Y415514I699J1215D01*
G03X1525650Y414815I189J-353D01*
G02X1526154Y414319I-700J-1215D01*
G03X1526853Y414341I343J205D01*
G02X1526896Y412981I1247J-641D01*
G03X1526197Y412959I-343J-205D01*
G37*
G36*
G01X149308Y415575D02*
G02X147577Y415801I-1008J-975D01*
G03X147658Y416422I-206J343D01*
G02X149389Y416196I1008J975D01*
G03X149308Y415575I206J-343D01*
G37*
G36*
G01X621202Y416175D02*
G02X620188Y417547I-1402J25D01*
G03X620698Y417925I110J385D01*
G02X620711Y418092I1402J-25D01*
G03X620412Y418292I-198J28D01*
G02X618977Y420701I-712J1208D01*
G03X618973Y421389I-206J343D01*
G02X621066Y422810I707J1211D01*
G03X621537Y422477I396J60D01*
G02X622612Y422243I263J-1377D01*
G03X622924Y422368I116J163D01*
G02X622969Y422540I1376J-268D01*
G03X622794Y422802I-190J63D01*
G02X623345Y425530I107J1398D01*
G03X623855Y425796I127J379D01*
G02X626596Y425274I1345J-396D01*
G03X626996Y424838I398J-36D01*
G02X627621Y424693I4J-1402D01*
G03X628199Y425062I178J358D01*
G02X628979Y423843I1401J38D01*
G03X628401Y423474I-178J-358D01*
G02X627920Y422378I-1401J-39D01*
G03X627862Y421837I262J-302D01*
G02X626470Y419624I-1125J-837D01*
G03X625996Y419268I-76J-393D01*
G02X624051Y418110I-1396J132D01*
G03X623497Y417777I-156J-368D01*
G02X621712Y416553I-1397J123D01*
G03X621202Y416175I-110J-385D01*
G37*
G36*
G01X52868Y415596D02*
G02X52769Y417119I-1223J685D01*
G03X53439Y417163I321J239D01*
G02X53538Y415640I1223J-685D01*
G03X52868Y415596I-321J-239D01*
G37*
G36*
G01X1510425Y416069D02*
G02X1508519Y417975I-1225J681D01*
G03Y418675I-194J350D01*
G02Y421125I681J1225D01*
G03Y421825I-194J350D01*
G02Y424275I681J1225D01*
G03Y424975I-194J350D01*
G02Y427425I681J1225D01*
G03Y428125I-194J350D01*
G02X1508000Y428625I680J1226D01*
G03X1507303Y428602I-342J-207D01*
G02X1507259Y429974I-1244J647D01*
G03X1507956Y429997I342J207D01*
G02X1510425Y430031I1244J-647D01*
G03X1511125I350J194D01*
G02X1513575I1225J-681D01*
G03X1514275I350J194D01*
G02X1516725I1225J-681D01*
G03X1517425I350J194D01*
G02X1519331Y428125I1225J-681D01*
G03Y427425I194J-350D01*
G02Y424975I-681J-1225D01*
G03Y424275I194J-350D01*
G02X1517425Y422369I-681J-1225D01*
G03X1516725I-350J-194D01*
G02X1516181Y421825I-1225J681D01*
G03Y421125I194J-350D01*
G02X1514275Y419219I-681J-1225D01*
G03X1513575I-350J-194D01*
G02X1513031Y418675I-1225J681D01*
G03Y417975I194J-350D01*
G02X1511125Y416069I-681J-1225D01*
G03X1510425I-350J-194D01*
G37*
G36*
G01X1317793Y417890D02*
G02X1315810Y419873I-973J1010D01*
G03Y420427I-288J277D01*
G02X1317830I1010J973D01*
G03Y419873I288J-277D01*
G02X1317914Y419777I-1012J-970D01*
G03X1318226I156J125D01*
G02X1320417Y419773I1094J-877D01*
G03X1321060Y419796I313J249D01*
G02X1321233Y420003I1157J-791D01*
G03X1321267Y420535I-281J285D01*
G02X1323322Y422429I1104J864D01*
G03X1323881Y422445I271J294D01*
G02X1325879Y422462I1007J-975D01*
G03X1326434Y422453I282J284D01*
G02X1328372Y422426I955J-1027D01*
G03X1328927Y422420I281J285D01*
G02X1330862Y422410I962J-1020D01*
G03X1331416I277J288D01*
G02X1333362I973J-1010D01*
G03X1333916I277J288D01*
G02X1335965Y420501I973J-1010D01*
G03X1335982Y419968I306J-257D01*
G02X1333904Y418087I-1014J-968D01*
G03X1333297Y418088I-304J-260D01*
G02X1331263Y417994I-1062J916D01*
G03X1330709I-277J-288D01*
G02X1328753Y418004I-973J1010D01*
G03X1328198Y418010I-281J-285D01*
G02X1326246Y418038I-962J1020D01*
G03X1325691Y418047I-282J-284D01*
G02X1323784Y418045I-955J1027D01*
G03X1323225Y418029I-271J-294D01*
G02X1321120Y418131I-1008J975D01*
G03X1320477Y418108I-313J-249D01*
G02X1318347Y417890I-1157J792D01*
G03X1317793I-277J-288D01*
G37*
G36*
G01X123483Y419851D02*
G02X121934Y420567I-1241J-652D01*
G03X122200Y421143I-88J390D01*
G02X123749Y420427I1241J652D01*
G03X123483Y419851I88J-390D01*
G37*
G36*
G01X1468429Y419934D02*
G02Y421488I-1167J777D01*
G03X1469095I333J222D01*
G02Y419934I1167J-777D01*
G03X1468429I-333J-222D01*
G37*
G36*
G01X1525631Y424275D02*
G02X1524269I-681J-1225D01*
G03Y424975I-194J350D01*
G02Y427425I681J1225D01*
G03Y428125I-194J350D01*
G02X1525631I681J1225D01*
G03Y427425I194J-350D01*
G02Y424975I-681J-1225D01*
G03Y424275I194J-350D01*
G37*
G36*
G01X1532475Y422369D02*
G02X1530569Y424275I-1225J681D01*
G03Y424975I-194J350D01*
G02Y427425I681J1225D01*
G03Y428125I-194J350D01*
G02X1532475Y430031I681J1225D01*
G03X1533175I350J194D01*
G02X1535625I1225J-681D01*
G03X1536325I350J194D01*
G02X1538775I1225J-681D01*
G03X1539475I350J194D01*
G02X1541381Y428125I1225J-681D01*
G03Y427425I194J-350D01*
G02Y424975I-681J-1225D01*
G03Y424275I194J-350D01*
G02X1539475Y422369I-681J-1225D01*
G03X1538775I-350J-194D01*
G02X1536325I-1225J681D01*
G03X1535625I-350J-194D01*
G02X1533175I-1225J681D01*
G03X1532475I-350J-194D01*
G37*
G36*
G01X1668413Y425845D02*
G02X1667107Y425878I-684J-1224D01*
G03X1667125Y426585I-177J358D01*
G02X1666997Y428952I684J1224D01*
G03X1666962Y429627I-231J326D01*
G02X1668461Y429706I687J1222D01*
G03X1668496Y429031I231J-326D01*
G02X1668431Y426552I-687J-1222D01*
G03X1668413Y425845I177J-358D01*
G37*
G36*
G01X1612829Y430595D02*
G02X1611286Y430758I-894J-1080D01*
G03X1611356Y431420I-185J354D01*
G02X1611473Y433667I894J1080D01*
G03Y434333I-222J333D01*
G02X1613027I777J1167D01*
G03Y433667I222J-333D01*
G02X1612899Y431257I-777J-1167D01*
G03X1612829Y430595I185J-354D01*
G37*
G36*
G01X746945Y431271D02*
G02X745331Y431282I-815J-1141D01*
G03X745336Y431936I-228J329D01*
G02X746950Y431925I815J1141D01*
G03X746945Y431271I228J-329D01*
G37*
G36*
G01X1510425Y434969D02*
G02X1508519Y436875I-1225J681D01*
G03Y437575I-194J350D01*
G02Y440025I681J1225D01*
G03Y440725I-194J350D01*
G02X1510425Y442631I681J1225D01*
G03X1511125I350J194D01*
G02X1513575I1225J-681D01*
G03X1514275I350J194D01*
G02X1516181Y440725I1225J-681D01*
G03Y440025I194J-350D01*
G02X1516725Y439481I-681J-1225D01*
G03X1517425I350J194D01*
G02X1519331Y437575I1225J-681D01*
G03Y436875I194J-350D01*
G02X1517425Y434969I-681J-1225D01*
G03X1516725I-350J-194D01*
G02X1514275I-1225J681D01*
G03X1513575I-350J-194D01*
G02X1511125I-1225J681D01*
G03X1510425I-350J-194D01*
G37*
G36*
G01X1525631Y436875D02*
G02X1524269I-681J-1225D01*
G03Y437575I-194J350D01*
G02X1525631I681J1225D01*
G03Y436875I194J-350D01*
G37*
G36*
G01X1532475Y434969D02*
G02X1530569Y436875I-1225J681D01*
G03Y437575I-194J350D01*
G02X1532475Y439481I681J1225D01*
G03X1533175I350J194D01*
G02X1535625I1225J-681D01*
G03X1536325I350J194D01*
G02X1538775I1225J-681D01*
G03X1539475I350J194D01*
G02X1541381Y437575I1225J-681D01*
G03Y436875I194J-350D01*
G02X1540019I-681J-1225D01*
G03Y437575I-194J350D01*
G02X1539475Y438119I681J1225D01*
G03X1538775I-350J-194D01*
G02X1536325I-1225J681D01*
G03X1535625I-350J-194D01*
G02X1535081Y437575I-1225J681D01*
G03Y436875I194J-350D01*
G02X1533175Y434969I-681J-1225D01*
G03X1532475I-350J-194D01*
G37*
G36*
G01X1665691Y439085D02*
G02X1663833I-929J-1050D01*
G03Y439685I-265J300D01*
G02X1663985Y441902I929J1050D01*
G03Y442568I-222J333D01*
G02X1665539I777J1167D01*
G03Y441902I222J-333D01*
G02X1665812Y441664I-777J-1167D01*
G03X1666412I300J265D01*
G02X1668435Y441745I1050J-929D01*
G03X1668989I277J288D01*
G02X1670527Y439452I973J-1010D01*
G03X1670330Y438907I161J-366D01*
G02X1667769Y438789I-1254J-626D01*
G03X1667411Y439334I-373J145D01*
G02X1666412Y439806I51J1401D01*
G03X1665812I-300J-265D01*
G02X1665691Y439685I-1050J929D01*
G03Y439085I265J-300D01*
G37*
G36*
G01X1544591Y440047D02*
G02X1543231Y440004I-641J-1247D01*
G03X1543209Y440703I-205J343D01*
G02X1543169Y443175I641J1247D01*
G03Y443875I-194J350D01*
G02X1542625Y444419I681J1225D01*
G03X1541925I-350J-194D01*
G02X1539475I-1225J681D01*
G03X1538775I-350J-194D01*
G02X1536325I-1225J681D01*
G03X1535625I-350J-194D01*
G02X1533175I-1225J681D01*
G03X1532475I-350J-194D01*
G02X1530569Y446325I-1225J681D01*
G03Y447025I-194J350D01*
G02X1532475Y448931I681J1225D01*
G03X1533175I350J194D01*
G02X1535625I1225J-681D01*
G03X1536325I350J194D01*
G02X1538775I1225J-681D01*
G03X1539475I350J194D01*
G02X1541381Y447025I1225J-681D01*
G03Y446325I194J-350D01*
G02X1541925Y445781I-681J-1225D01*
G03X1542625I350J194D01*
G02X1544531Y443875I1225J-681D01*
G03Y443175I194J-350D01*
G02X1544569Y440746I-681J-1225D01*
G03X1544591Y440047I205J-343D01*
G37*
G36*
G01X1286805Y441007D02*
G02X1285559Y441448I-1036J-945D01*
G03X1285795Y442113I-60J395D01*
G02X1286911Y444458I1036J945D01*
G03X1287320Y444964I24J399D01*
G02X1288591Y443938I1351J374D01*
G03X1288182Y443432I-24J-399D01*
G02X1287041Y441672I-1351J-374D01*
G03X1286805Y441007I60J-395D01*
G37*
G36*
G01X1725270Y442675D02*
G02X1723640Y442799I-901J-1074D01*
G03X1723689Y443447I-208J342D01*
G02X1723579Y443550I902J1073D01*
G03X1723001I-289J-277D01*
G02Y445492I-1011J971D01*
G03X1723579I289J277D01*
G02X1725804Y445222I1011J-971D01*
G03X1726476Y445191I346J201D01*
G02X1726406Y443679I1144J-811D01*
G03X1725734Y443710I-346J-201D01*
G02X1725319Y443323I-1144J811D01*
G03X1725270Y442675I208J-342D01*
G37*
G36*
G01X1602290Y445654D02*
G02X1601199Y444330I310J-1367D01*
G03X1600710Y444733I-400J13D01*
G02X1601801Y446057I-310J1367D01*
G03X1602290Y445654I400J-13D01*
G37*
G36*
G01X1523025Y444419D02*
G02Y445781I-1225J681D01*
G03X1523725I350J194D01*
G02X1524269Y446325I1225J-681D01*
G03Y447025I-194J350D01*
G02X1525631I681J1225D01*
G03Y446325I194J-350D01*
G02X1523725Y444419I-681J-1225D01*
G03X1523025I-350J-194D01*
G37*
G36*
G01X1504495Y446629D02*
G02X1503769Y448171I-1370J297D01*
G03X1504344Y448442I184J355D01*
G02X1505070Y446900I1370J-297D01*
G03X1504495Y446629I-184J-355D01*
G37*
G36*
G01X1918547Y447249D02*
G02X1916039Y447364I-1225J681D01*
G03X1915340Y447424I-366J-162D01*
G02X1915456Y448766I-1167J777D01*
G03X1916155Y448706I366J162D01*
G02X1918547Y448611I1167J-776D01*
G03X1919247I350J194D01*
G02Y447249I1225J-681D01*
G03X1918547I-350J-194D01*
G37*
G36*
G01X1516725Y447569D02*
G02X1514777Y449451I-1225J681D01*
G03X1514753Y450151I-205J343D01*
G02X1516112Y450199I636J1249D01*
G03X1516136Y449499I205J-343D01*
G02X1516725Y448931I-636J-1249D01*
G03X1517425I350J194D01*
G02X1517996Y449490I1225J-681D01*
G03X1518002Y450195I-186J354D01*
G02X1519896Y452114I673J1230D01*
G03X1520590Y452108I349J196D01*
G02X1520579Y450711I1210J-708D01*
G03X1519885Y450717I-349J-196D01*
G02X1519329Y450185I-1210J708D01*
G03X1519323Y449480I186J-354D01*
G02X1517425Y447569I-673J-1230D01*
G03X1516725I-350J-194D01*
G37*
G36*
G01X1933562Y449612D02*
G02X1933835Y451960I-3243J1567D01*
G03X1934464Y451726I390J87D01*
G02X1934228Y449696I836J-1126D01*
G03X1933562Y449612I-306J-258D01*
G37*
G36*
G01X1887351Y453165D02*
G02X1884768Y453561I-1151J1115D01*
G03X1884063Y453579I-357J-180D01*
G02X1884101Y455087I-1394J790D01*
G03X1884806Y455069I357J180D01*
G02X1887264Y455477I1394J-789D01*
G03X1887817Y455498I266J299D01*
G02X1890228Y455372I1151J-1115D01*
G03X1890858I315J247D01*
G02Y453394I1260J-989D01*
G03X1890228I-315J-247D01*
G02X1887904Y453186I-1260J989D01*
G03X1887351Y453165I-266J-299D01*
G37*
G36*
G01X1842797Y453544D02*
G02Y455098I-1167J777D01*
G03X1843463I333J222D01*
G02Y453544I1167J-777D01*
G03X1842797I-333J-222D01*
G37*
G36*
G01X22038Y453348D02*
G02X19937Y455766I-1040J1218D01*
G03Y456366I-265J300D01*
G02X20141Y458919I1061J1200D01*
G03X20165Y459579I-214J338D01*
G02X22158Y462084I953J1287D01*
G03X22678I260J304D01*
G02X24758I1040J-1218D01*
G03X25278I260J304D01*
G02X27382Y462064I1041J-1218D01*
G03X27915Y462066I265J299D01*
G02X29845Y459523I1073J-1190D01*
G03X29821Y458863I214J-338D01*
G02X29929Y456376I-953J-1287D01*
G03Y455776I265J-300D01*
G02X27804Y453378I-1061J-1200D01*
G03X27271Y453376I-265J-299D01*
G02X25158Y453348I-1072J1190D01*
G03X24638I-260J-304D01*
G02X22558I-1040J1218D01*
G03X22038I-260J-304D01*
G37*
G36*
G01X620740Y465350D02*
G02X619173Y464668I-340J-1360D01*
G03X618920Y465250I-350J194D01*
G02X618450Y467754I340J1360D01*
G03X618479Y468385I-231J327D01*
G02X620200Y468306I911J1065D01*
G03X620171Y467675I231J-327D01*
G02X620487Y465932I-911J-1065D01*
G03X620740Y465350I350J-194D01*
G37*
G36*
G01X-5187Y465904D02*
G02X-6694Y466110I-913J-1064D01*
G03X-6603Y466776I-169J362D01*
G02X-5096Y466570I913J1064D01*
G03X-5187Y465904I169J-362D01*
G37*
G36*
G01X635166Y468771D02*
G02X633700Y469205I-1133J-1133D01*
G03X633917Y469861I-83J391D01*
G02X633628Y471206I1050J929D01*
G03X633151Y471713I-382J118D01*
G02X634270Y472704I-380J1556D01*
G03X634716Y472169I374J-141D01*
G02X635277Y472157I251J-1379D01*
G03X635761Y472605I88J390D01*
G02X636838Y471442I1387J204D01*
G03X636354Y470994I-88J-390D01*
G02X635342Y469439I-1387J-204D01*
G03X635166Y468771I107J-385D01*
G37*
G36*
G01X1617774Y469168D02*
G02Y470722I-1167J777D01*
G03X1618440I333J222D01*
G02Y469168I1167J-777D01*
G03X1617774I-333J-222D01*
G37*
G36*
G01X1911277Y473167D02*
G02X1909723I-777J-1167D01*
G03Y473833I-222J333D01*
G02X1911277I777J1167D01*
G03Y473167I222J-333D01*
G37*
G36*
G01X607004Y472635D02*
G02X604816Y474367I-1179J759D01*
G03Y474921I-288J277D01*
G02X606836I1010J973D01*
G03Y474367I288J-277D01*
G02X606961Y474216I-1015J-967D01*
G03X607622Y474234I324J235D01*
G02X607665Y472653I1178J-759D01*
G03X607004Y472635I-324J-235D01*
G37*
G36*
G01X66784Y476042D02*
G02X65693Y476991I-1334J-432D01*
G03X66143Y477508I70J394D01*
G02X67234Y476559I1334J432D01*
G03X66784Y476042I-70J-394D01*
G37*
G36*
G01X1841917Y474947D02*
G02Y476501I-1167J777D01*
G03X1842583I333J222D01*
G02Y474947I1167J-777D01*
G03X1841917I-333J-222D01*
G37*
G36*
G01X4127Y479339D02*
G02X3786Y477842I973J-1009D01*
G03X3133Y477991I-375J-139D01*
G02X931Y478326I-973J1009D01*
G03X229I-351J-192D01*
G02Y479674I-1229J674D01*
G03X931I351J192D01*
G02X1566Y480270I1229J-674D01*
G03X1661Y480932I-170J362D01*
G02X3795Y482698I928J1051D01*
G03X4483I344J204D01*
G02Y481268I1206J-715D01*
G03X3795I-344J-204D01*
G02X3183Y480713I-1206J715D01*
G03X3088Y480051I170J-362D01*
G02X3474Y479488I-928J-1050D01*
G03X4127Y479339I375J139D01*
G37*
G36*
G01X90883Y478991D02*
G02X90312Y480342I-1386J210D01*
G03X90940Y480608I232J325D01*
G02X93029Y481611I1386J-210D01*
G03X93622Y481881I200J346D01*
G02X94295Y480399I1376J-269D01*
G03X93702Y480129I-200J-346D01*
G02X91511Y479257I-1376J269D01*
G03X90883Y478991I-232J-325D01*
G37*
G36*
G01X1599811Y478370D02*
G02Y480080I-1111J855D01*
G03X1600446I317J243D01*
G02Y478370I1111J-855D01*
G03X1599811I-317J-243D01*
G37*
G36*
G01X1570800Y480997D02*
G02X1569699Y482101I-1375J-271D01*
G03X1570170Y482571I78J392D01*
G02X1571271Y481467I1375J271D01*
G03X1570800Y480997I-78J-392D01*
G37*
G36*
G01X626879Y481069D02*
G02X626695Y482403I-1310J499D01*
G03X627390Y482499I321J239D01*
G02X627574Y481165I1310J-499D01*
G03X626879Y481069I-321J-239D01*
G37*
G36*
G01X32607Y481958D02*
G02X32544Y483698I-1130J830D01*
G03X33170Y483720I304J259D01*
G02X33233Y481980I1130J-830D01*
G03X32607Y481958I-304J-259D01*
G37*
G36*
G01X1688120Y485257D02*
G02X1686836Y485235I-621J-1257D01*
G03X1686823Y485946I-190J352D01*
G02X1688416Y488213I620J1257D01*
G03X1688970I277J288D01*
G02X1690893Y488234I973J-1010D01*
G03X1691448Y488247I271J294D01*
G02X1691493Y486228I995J-988D01*
G03X1690938Y486215I-271J-294D01*
G02X1688970Y486193I-995J988D01*
G03X1688416I-277J-288D01*
G02X1688107Y485968I-972J1010D01*
G03X1688120Y485257I190J-352D01*
G37*
G36*
G01X1457304Y487077D02*
G02X1455890Y487072I-703J-1213D01*
G03X1455888Y487763I-203J345D01*
G02X1457302Y487768I703J1213D01*
G03X1457304Y487077I203J-345D01*
G37*
G36*
G01X657051Y487930D02*
G02X655110Y487893I-951J-1030D01*
G03X655099Y488470I-282J283D01*
G02X657402Y489870I951J1030D01*
G03X658073Y489694I386J105D01*
G02X657718Y488339I997J-985D01*
G03X657047Y488515I-386J-105D01*
G02X657040Y488507I-1056J917D01*
G03X657051Y487930I282J-283D01*
G37*
G36*
G01X1642122Y488168D02*
G02X1641073Y489131I-1341J-408D01*
G03X1641539Y489639I83J391D01*
G02X1642588Y488676I1341J408D01*
G03X1642122Y488168I-83J-391D01*
G37*
G36*
G01X729744Y488062D02*
G02X729310Y489399I-1371J294D01*
G03X729968Y489613I267J298D01*
G02X730402Y488276I1371J-294D01*
G03X729744Y488062I-267J-298D01*
G37*
G36*
G01X1641064Y497040D02*
G02X1640645Y495487I899J-1076D01*
G03X1640012Y495658I-376J-136D01*
G02X1640431Y497211I-899J1076D01*
G03X1641064Y497040I376J136D01*
G37*
G36*
G01X1590192Y495198D02*
G02Y496752I-1167J777D01*
G03X1590858I333J222D01*
G02Y495198I1167J-777D01*
G03X1590192I-333J-222D01*
G37*
G36*
G01X1268014Y497007D02*
G02X1267785Y495327I992J-991D01*
G03X1267154Y495413I-348J-197D01*
G02X1267383Y497093I-992J991D01*
G03X1268014Y497007I348J197D01*
G37*
G36*
G01X1279705Y497522D02*
G02X1279311Y495877I890J-1083D01*
G03X1278690Y496025I-366J-161D01*
G02X1279084Y497670I-890J1083D01*
G03X1279705Y497522I366J161D01*
G37*
G36*
G01X1728637Y501596D02*
X1733639D01*
G02X1735150Y500095I0J-1511D01*
G01Y500000D01*
X1735141Y499916D01*
G02X1733639Y498574I-1502J169D01*
G01X1729602D01*
G03X1729310Y497901I0J-400D01*
G02X1726932Y495754I-1171J-1094D01*
G03X1726418Y495829I-301J-263D01*
G02X1723965Y497144I-852J1357D01*
G03X1723570Y497533I-400J-11D01*
G02X1723600Y500737I21J1602D01*
G03X1724002Y501110I3J400D01*
G02X1727123Y501498I1598J-110D01*
G03X1727741Y501301I380J124D01*
G02X1728637Y501596I897J-1216D01*
G37*
G36*
G01X1789242Y495925D02*
G02X1786803Y496003I-1197J729D01*
G03X1786100Y496014I-354J-185D01*
G02X1786120Y497352I-1222J687D01*
G03X1786823Y497341I354J185D01*
G02X1789235Y497396I1222J-687D01*
G03X1789916Y497399I340J211D01*
G02X1789923Y495928I1197J-730D01*
G03X1789242Y495925I-340J-211D01*
G37*
G36*
G01X689432Y497063D02*
G02X689149Y498770I-1230J673D01*
G03X689770Y498873I270J295D01*
G02X690053Y497166I1230J-673D01*
G03X689432Y497063I-270J-295D01*
G37*
G36*
G01X1616058Y497784D02*
G02X1615976Y499474I-1158J791D01*
G03X1616613Y499505I307J256D01*
G02X1616695Y497815I1158J-791D01*
G03X1616058Y497784I-307J-256D01*
G37*
G36*
G01X55164Y501438D02*
G02X53088Y503514I-1264J812D01*
G03Y504186I-216J336D01*
G02X55164Y506262I812J1264D01*
G03X55836I336J216D01*
G02X58364I1264J-812D01*
G03X59036I336J216D01*
G02X61112Y504186I1264J-812D01*
G03Y503514I216J-336D01*
G02X59036Y501438I-812J-1264D01*
G03X58364I-336J-216D01*
G02X55836I-1264J812D01*
G03X55164I-336J-216D01*
G37*
G36*
G01X1565777Y504496D02*
G02X1564223I-777J-1167D01*
G03Y505162I-222J333D01*
G02X1565777I777J1167D01*
G03Y504496I222J-333D01*
G37*
G36*
G01X680274Y503064D02*
G02X680159Y504602I-1225J682D01*
G03X680825Y504652I317J245D01*
G02X680940Y503114I1225J-682D01*
G03X680274Y503064I-317J-245D01*
G37*
G36*
G01X1689443Y505238D02*
G02X1688723Y503689I648J-1243D01*
G03X1688148Y503957I-391J-87D01*
G02X1686391Y504342I-648J1243D01*
G03X1685759I-316J-245D01*
G02Y506058I-1109J858D01*
G03X1686391I316J245D01*
G02X1688868Y505506I1109J-858D01*
G03X1689443Y505238I391J87D01*
G37*
G36*
G01X1333988Y506103D02*
G02X1331680Y507358I-1388J197D01*
G03X1331658Y507979I-263J302D01*
G02X1333892Y509263I842J1121D01*
G03X1334470Y508952I398J46D01*
G02X1334543Y506413I630J-1252D01*
G03X1333988Y506103I-159J-367D01*
G37*
G36*
G01X1011044Y536906D02*
Y516802D01*
G03X1011245Y516602I200J0D01*
G02X1012288Y516142I5J-1402D01*
G03X1012870Y516132I296J269D01*
G02X1014884Y516123I1003J-980D01*
G03X1015462I289J277D01*
G02Y514181I1011J-971D01*
G03X1014884I-289J-277D01*
G02X1012835Y514210I-1011J971D01*
G03X1012253Y514220I-296J-269D01*
G02X1010966Y513827I-1003J980D01*
G01X1010860Y513849D01*
X1009029Y512018D01*
G03X1009138Y511376I283J-282D01*
G02X1009537Y511085I-614J-1261D01*
G03X1010115I289J277D01*
G02X1012195Y511022I1012J-971D01*
G03X1012804I304J258D01*
G02X1014884Y511085I1068J-908D01*
G03X1015462I289J277D01*
G02Y509143I1011J-971D01*
G03X1014884I-289J-277D01*
G02X1012804Y509206I-1012J971D01*
G03X1012195I-305J-258D01*
G02X1010115Y509143I-1068J908D01*
G03X1009537I-289J-277D01*
G02X1007431Y510990I-1011J971D01*
G03X1007119Y511640I-312J250D01*
G01X1007011D01*
X1002307Y506936D01*
X971428D01*
X969047Y509317D01*
G03X968444Y509274I-283J-283D01*
G02X966482Y511237I-1122J840D01*
G03X966525Y511840I-240J320D01*
G01X965940Y512425D01*
G03X965284Y512287I-283J-283D01*
G02X964412Y514125I-1308J505D01*
G03X964936Y514505I124J380D01*
G01Y516344D01*
G03X964412Y516724I-400J0D01*
G02Y519390I-436J1333D01*
G03X964936Y519770I124J380D01*
G01Y534212D01*
X966232Y535507D01*
G03X966254Y536049I-283J283D01*
G02X968230Y538025I1068J908D01*
G03X968772Y538047I259J305D01*
G01X970335Y539610D01*
G02X970865Y539830I531J-530D01*
G01X1008120D01*
G02X1008650Y539610I-1J-750D01*
G01X1010824Y537436D01*
G02X1011044Y536906I-530J-531D01*
G37*
G36*
G01X1534568Y510040D02*
G02X1532953Y510276I-972J-1010D01*
G03X1533047Y510920I-183J356D01*
G02X1534662Y510684I972J1010D01*
G03X1534568Y510040I183J-356D01*
G37*
G36*
G01X1401610Y509379D02*
G02X1401229Y511321I-1165J780D01*
G03X1401785Y511430I224J332D01*
G02X1404117Y511427I1165J-780D01*
G03X1404783I333J222D01*
G02X1406073Y512047I1167J-777D01*
G03X1406502Y512513I35J398D01*
G02X1407761Y511354I1382J238D01*
G03X1407332Y510888I-35J-398D01*
G02X1404783Y509873I-1382J-238D01*
G03X1404117I-333J-222D01*
G02X1402166Y509488I-1167J777D01*
G03X1401610Y509379I-224J-332D01*
G37*
G36*
G01X1910967Y509923D02*
G02Y511477I-1167J777D01*
G03X1911633I333J222D01*
G02Y509923I1167J-777D01*
G03X1910967I-333J-222D01*
G37*
G36*
G01X1296853Y509800D02*
G02X1294958Y511866I-973J1010D01*
G03X1294975Y512452I-263J301D01*
G02X1295183Y514617I985J998D01*
G03Y515283I-222J333D01*
G02Y517617I777J1167D01*
G03Y518283I-222J333D01*
G02X1296933Y520460I778J1167D01*
G03X1297487I277J288D01*
G02X1299237Y518283I972J-1010D01*
G03Y517617I222J-333D01*
G02Y515283I-777J-1167D01*
G03Y514617I222J-333D01*
G02X1299382Y512394I-777J-1167D01*
G03X1299365Y511808I263J-301D01*
G02X1297407Y509800I-985J-998D01*
G03X1296853I-277J-288D01*
G37*
G36*
G01X713293Y511963D02*
G02X713170Y513605I-1193J736D01*
G03X713816Y513654I305J259D01*
G02X713939Y512012I1193J-736D01*
G03X713293Y511963I-305J-259D01*
G37*
G36*
G01X1828753Y514383D02*
G02X1826598Y513175I-753J-1183D01*
G03X1826088Y513553I-400J-7D01*
G02X1826184Y516216I-388J1347D01*
G03X1826716Y516527I137J375D01*
G02X1827212Y517385I1384J-227D01*
G03X1827234Y517984I-254J309D01*
G02X1829088Y517915I966J1016D01*
G03X1829066Y517316I254J-309D01*
G02X1828775Y515071I-966J-1016D01*
G03X1828753Y514383I192J-351D01*
G37*
G36*
G01X1797553Y514117D02*
G02X1796878Y515400I-1400J83D01*
G03X1797483Y515719I206J343D01*
G02X1799952Y516543I1400J-83D01*
G03X1800555Y516535I305J259D01*
G02X1800531Y514693I1045J-935D01*
G03X1799928Y514701I-305J-259D01*
G02X1798158Y514436I-1045J935D01*
G03X1797553Y514117I-206J-343D01*
G37*
G36*
G01X1340419Y516938D02*
G02X1339015Y517074I-819J-1138D01*
G03X1339081Y517762I-167J363D01*
G02X1340485Y517626I819J1138D01*
G03X1340419Y516938I167J-363D01*
G37*
G36*
G01X1861057Y521367D02*
G02X1859312Y521214I-777J-1167D01*
G03X1859126Y521894I-276J290D01*
G02X1861122Y522069I728J3169D01*
G03X1861057Y521367I156J-368D01*
G37*
G36*
G01X41429Y521343D02*
G02X40279Y522116I-1318J-720D01*
G03X40675Y522705I45J397D01*
G02X41825Y521932I1318J720D01*
G03X41429Y521343I-45J-397D01*
G37*
G36*
G01X1804213Y522569D02*
G02X1802541Y526180I-3227J698D01*
G03X1803122Y526459I188J353D01*
G02X1803575Y527253I1378J-260D01*
G03X1803409Y527942I-264J301D01*
G02X1804677Y528248I343J1359D01*
G03X1804843Y527559I264J-301D01*
G02X1805726Y525521I-343J-1359D01*
G03X1806076Y524927I350J-194D01*
G02X1804931Y522716I0J-1402D01*
G03X1804213Y522569I-327J-231D01*
G37*
G36*
G01X1415993Y520663D02*
G02X1415941Y522214I-1193J736D01*
G03X1416607Y522237I325J233D01*
G02X1416659Y520686I1193J-736D01*
G03X1415993Y520663I-325J-233D01*
G37*
G36*
G01X90674Y523007D02*
G02X90451Y521273I976J-1007D01*
G03X89831Y521352I-342J-208D01*
G02X90054Y523086I-976J1007D01*
G03X90674Y523007I342J208D01*
G37*
G36*
G01X47646Y524933D02*
G02X46049Y525384I-1139J-980D01*
G03X46230Y526025I-122J381D01*
G02X47827Y525574I1139J980D01*
G03X47646Y524933I122J-381D01*
G37*
G36*
G01X1437747Y525335D02*
G02X1436550Y526531I-1389J-193D01*
G03X1437001Y526982I55J396D01*
G02X1438198Y525786I1389J193D01*
G03X1437747Y525335I-55J-396D01*
G37*
G36*
G01X717110Y526173D02*
G02X715090I-1010J-973D01*
G03Y526727I-288J277D01*
G02X715006Y526823I1012J970D01*
G03X714694I-156J-125D01*
G02X713488Y526302I-1094J877D01*
G03X713067Y525810I-32J-399D01*
G02X711816Y526881I-1363J-327D01*
G03X712237Y527373I32J399D01*
G02X712590Y528673I1363J328D01*
G03Y529227I-288J277D01*
G02Y531173I1010J973D01*
G03Y531727I-288J277D01*
G02X714573Y533710I1010J973D01*
G03X715127I277J288D01*
G02X717110Y531727I973J-1010D01*
G03Y531173I288J-277D01*
G02Y529227I-1010J-973D01*
G03Y528673I288J-277D01*
G02Y526727I-1010J-973D01*
G03Y526173I288J-277D01*
G37*
G36*
G01X1296749Y526817D02*
G02X1294883Y528867I-1089J883D01*
G03Y529533I-222J333D01*
G02Y531867I777J1167D01*
G03Y532533I-222J333D01*
G02Y534867I777J1167D01*
G03Y535533I-222J333D01*
G02X1296749Y537583I777J1167D01*
G03X1297371I311J252D01*
G02X1299237Y535533I1089J-883D01*
G03Y534867I222J-333D01*
G02Y532533I-777J-1167D01*
G03Y531867I222J-333D01*
G02Y529533I-777J-1167D01*
G03Y528867I222J-333D01*
G02X1297371Y526817I-777J-1167D01*
G03X1296749I-311J-252D01*
G37*
G36*
G01X686650Y529153D02*
G02X685186Y528521I-275J-1375D01*
G03X684925Y529125I-339J212D01*
G02X683958Y531151I275J1375D01*
G03X683803Y531684I-354J186D01*
G02X685742Y532249I697J1216D01*
G03X685897Y531716I354J-186D01*
G02X686389Y529757I-697J-1216D01*
G03X686650Y529153I339J-212D01*
G37*
G36*
G01X309343Y528053D02*
G02X309250Y529790I-1145J810D01*
G03X309876Y529824I300J265D01*
G02X309969Y528087I1145J-810D01*
G03X309343Y528053I-300J-265D01*
G37*
G36*
G01X958951D02*
G02X958858Y529790I-1145J810D01*
G03X959484Y529824I300J265D01*
G02X959577Y528087I1145J-810D01*
G03X958951Y528053I-300J-265D01*
G37*
G36*
G01X652317Y529423D02*
G02X650121Y531152I-1167J777D01*
G03X650110Y531707I-293J272D01*
G02X652283Y533453I991J992D01*
G03X652971Y533475I337J214D01*
G02X655151Y531770I1229J-675D01*
G03X655140Y531193I271J-294D01*
G02X652983Y529423I-990J-993D01*
G03X652317I-333J-222D01*
G37*
G36*
G01X658223Y530290D02*
G02X656473Y532467I-972J1010D01*
G03Y533133I-222J333D01*
G02X658223Y535310I778J1167D01*
G03X658777I277J288D01*
G02X660527Y533133I972J-1010D01*
G03Y532467I222J-333D01*
G02X658777Y530290I-778J-1167D01*
G03X658223I-277J-288D01*
G37*
G36*
G01X1460414Y532386D02*
G02X1460352Y530695I1086J-886D01*
G03X1459715Y530718I-327J-230D01*
G02X1459777Y532409I-1086J886D01*
G03X1460414Y532386I327J230D01*
G37*
G36*
G01X726180Y532943D02*
G02X726154Y534496I-1180J757D01*
G03X726820Y534507I329J227D01*
G02X726846Y532954I1180J-757D01*
G03X726180Y532943I-329J-227D01*
G37*
G36*
G01X63667Y534723D02*
G02Y536277I-1167J777D01*
G03X64333I333J222D01*
G02X66667I1167J-777D01*
G03X67333I333J222D01*
G02Y534723I1167J-777D01*
G03X66667I-333J-222D01*
G02X64333I-1167J777D01*
G03X63667I-333J-222D01*
G37*
G36*
G01X1385303Y534550D02*
G02X1383533Y536707I-993J990D01*
G03Y537373I-222J333D01*
G02Y539707I777J1167D01*
G03Y540373I-222J333D01*
G02X1382961Y541923I777J1167D01*
G03X1382522Y542429I-384J110D01*
G02X1383680Y543435I-191J1389D01*
G03X1384119Y542929I384J-110D01*
G02X1385295Y542538I191J-1389D01*
G03X1385848Y542529I281J284D01*
G02X1386507Y542871I952J-1029D01*
G03X1386753Y543490I-83J391D01*
G02X1388200Y542915I1154J796D01*
G03X1387954Y542296I83J-391D01*
G02X1387577Y540333I-1154J-796D01*
G03Y539667I222J-333D01*
G02X1387632Y537372I-777J-1167D01*
G03Y536728I238J-322D01*
G02X1385856Y534564I-832J-1128D01*
G03X1385303Y534550I-269J-296D01*
G37*
G36*
G01X71506Y537405D02*
G02X69730Y539561I-984J999D01*
G03X69725Y540224I-226J330D01*
G02X71455Y542419I774J1169D01*
G03X72012Y542430I273J292D01*
G02X73953Y542481I997J-986D01*
G03X74497Y542486I269J296D01*
G02X76433Y542478I964J-1018D01*
G03X76988I277J288D01*
G02X78905Y542504I972J-1010D01*
G03X79444I270J295D01*
G02X81166Y540301I944J-1036D01*
G03Y539635I222J-333D01*
G02X79444Y537432I-778J-1167D01*
G03X78905I-270J-295D01*
G02X76988Y537458I-945J1036D01*
G03X76433I-277J-288D01*
G02X74517Y537431I-972J1010D01*
G03X73973Y537426I-269J-296D01*
G02X72058Y537414I-964J1018D01*
G03X71506Y537405I-271J-294D01*
G37*
G36*
G01X646927Y541517D02*
G02X645373I-777J-1167D01*
G03Y542183I-222J333D01*
G02Y544517I777J1167D01*
G03Y545183I-222J333D01*
G02X646927I777J1167D01*
G03Y544517I222J-333D01*
G02Y542183I-777J-1167D01*
G03Y541517I222J-333D01*
G37*
G36*
G01X1940620Y541958D02*
G02X1938484Y540203I-920J-1058D01*
G03X1937951Y540358I-347J-199D01*
G02X1938516Y542297I-651J1242D01*
G03X1939049Y542142I347J199D01*
G02X1939064Y542150I667J-1233D01*
G03X1939077Y542499I-91J178D01*
G02X1938408Y543537I723J1201D01*
G03X1937830Y543848I-398J-46D01*
G02X1937855Y546340I-630J1252D01*
G03X1938432Y546606I187J354D01*
G02X1940771Y545289I1368J-306D01*
G03Y544711I277J-289D01*
G02X1940642Y542579I-971J-1011D01*
G03X1940620Y541958I241J-319D01*
G37*
G36*
G01X1922965Y544767D02*
G02X1921424Y545028I-965J-1017D01*
G03X1921535Y545683I-164J365D01*
G02X1923076Y545422I965J1017D01*
G03X1922965Y544767I164J-365D01*
G37*
G36*
G01X1453864Y545629D02*
G02X1450791Y544939I-1472J-631D01*
G03X1450287Y545310I-400J-15D01*
G02X1448818Y545799I-365J1354D01*
G03X1448175Y545780I-314J-247D01*
G02X1448126Y547443I-1153J798D01*
G03X1448769Y547462I314J247D01*
G02X1450926Y547642I1153J-798D01*
G03X1451603Y547833I287J279D01*
G02X1454310Y548603I1563J-352D01*
G03X1454892Y548615I285J280D01*
G02X1454936Y546418I1188J-1075D01*
G03X1454354Y546406I-285J-280D01*
G02X1454019Y546125I-1187J1075D01*
G03X1453864Y545629I213J-339D01*
G37*
G36*
G01X1915609Y545971D02*
G02X1914125Y546118I-859J-1108D01*
G03X1914191Y546792I-179J358D01*
G02X1915675Y546645I859J1108D01*
G03X1915609Y545971I179J-358D01*
G37*
G36*
G01X1811291Y544448D02*
G02X1811069Y546068I-1239J655D01*
G03X1811713Y546156I290J275D01*
G02X1811935Y544536I1239J-655D01*
G03X1811291Y544448I-290J-275D01*
G37*
G36*
G01X1278982Y546573D02*
G02X1277957Y545548I336J-1361D01*
G03X1277473Y546032I-389J95D01*
G02X1278498Y547057I-336J1361D01*
G03X1278982Y546573I389J-95D01*
G37*
G36*
G01X1899954Y546114D02*
G02X1898485Y546604I-1104J-864D01*
G03X1898696Y547236I-104J386D01*
G02X1898565Y547436I1103J865D01*
G03X1898010Y547591I-352J-190D01*
G02X1898535Y549464I-710J1209D01*
G03X1899090Y549309I352J190D01*
G02X1900165Y546746I710J-1209D01*
G03X1899954Y546114I104J-386D01*
G37*
G36*
G01X356449Y548600D02*
G02X356446Y547234I1223J-686D01*
G03X355748Y547236I-350J-194D01*
G02X355751Y548602I-1223J686D01*
G03X356449Y548600I350J194D01*
G37*
G36*
G01X1006057D02*
G02X1006054Y547234I1223J-686D01*
G03X1005356Y547236I-350J-194D01*
G02X1005359Y548602I-1223J686D01*
G03X1006057Y548600I350J194D01*
G37*
G36*
G01X1857125Y548275D02*
G02X1855432Y549365I-1375J-275D01*
G03X1855733Y549833I-91J389D01*
G02X1856137Y551119I1375J275D01*
G03Y551697I-277J289D01*
G02X1856097Y551737I971J1011D01*
G03X1855519I-289J-277D01*
G02X1853146Y553039I-1011J971D01*
G03X1852678Y553526I-389J95D01*
G02X1853762Y554569I-278J1374D01*
G03X1854230Y554082I389J-95D01*
G02X1855519Y553679I278J-1374D01*
G03X1856097I289J277D01*
G02X1858119I1011J-971D01*
G03X1858697I289J277D01*
G02Y551737I1011J-971D01*
G03X1858119I-289J-277D01*
G02X1858079Y551697I-1011J971D01*
G03Y551119I277J-289D01*
G02X1857426Y548743I-971J-1011D01*
G03X1857125Y548275I91J-389D01*
G37*
G36*
G01X1849505Y549465D02*
G02X1848218Y549425I-605J-1265D01*
G03X1848195Y550135I-195J349D01*
G02X1849482Y550175I605J1265D01*
G03X1849505Y549465I195J-349D01*
G37*
G36*
G01X1836978Y550660D02*
G02X1836688Y549207I1022J-959D01*
G03X1836022Y549340I-374J-141D01*
G02X1836312Y550793I-1022J959D01*
G03X1836978Y550660I374J141D01*
G37*
G36*
G01X730541Y549008D02*
G02X728773Y551167I-991J992D01*
G03Y551833I-222J333D01*
G02Y554167I777J1167D01*
G03Y554833I-222J333D01*
G02X730541Y556992I777J1167D01*
G03X731107I283J282D01*
G02X732875Y554833I991J-992D01*
G03Y554167I222J-333D01*
G02Y551833I-777J-1167D01*
G03Y551167I222J-333D01*
G02X731107Y549008I-777J-1167D01*
G03X730541I-283J-282D01*
G37*
G36*
G01X1816995Y551606D02*
G02X1815565I-715J-1206D01*
G03Y552294I-204J344D01*
G02X1816995I715J1206D01*
G03Y551606I204J-344D01*
G37*
G36*
G01X1300777Y553567D02*
G02X1299223I-777J-1167D01*
G03Y554233I-222J333D01*
G02Y556567I777J1167D01*
G03Y557233I-222J333D01*
G02X1300777I777J1167D01*
G03Y556567I222J-333D01*
G02Y554233I-777J-1167D01*
G03Y553567I222J-333D01*
G37*
G36*
G01X1318667Y551623D02*
G02X1316723Y553567I-1167J777D01*
G03Y554233I-222J333D01*
G02Y556567I777J1167D01*
G03Y557233I-222J333D01*
G02X1318667Y559177I777J1167D01*
G03X1319333I333J222D01*
G02X1321667I1167J-777D01*
G03X1322333I333J222D01*
G02X1324277Y557233I1167J-777D01*
G03Y556567I222J-333D01*
G02Y554233I-777J-1167D01*
G03Y553567I222J-333D01*
G02X1322333Y551623I-777J-1167D01*
G03X1321667I-333J-222D01*
G02X1319333I-1167J777D01*
G03X1318667I-333J-222D01*
G37*
G36*
G01X658306Y551785D02*
G02Y553215I-1206J715D01*
G03X658994I344J204D01*
G02Y551785I1206J-715D01*
G03X658306I-344J-204D01*
G37*
G36*
G01X1755319Y553024D02*
G02X1754626Y554754I-1319J476D01*
G03X1755181Y554976I179J358D01*
G02X1757667Y555277I1319J-476D01*
G03X1758333I333J222D01*
G02Y553723I1167J-777D01*
G03X1757667I-333J-222D01*
G02X1755874Y553246I-1167J777D01*
G03X1755319Y553024I-179J-358D01*
G37*
G36*
G01X64667Y553723D02*
G02X62723Y555667I-1167J777D01*
G03Y556333I-222J333D01*
G02X64667Y558277I777J1167D01*
G03X65333I333J222D01*
G02X67667I1167J-777D01*
G03X68333I333J222D01*
G02X70667I1167J-777D01*
G03X71333I333J222D01*
G02X73667I1167J-777D01*
G03X74333I333J222D01*
G02X76667I1167J-777D01*
G03X77333I333J222D01*
G02X79667I1167J-777D01*
G03X80333I333J222D01*
G02X82277Y556333I1167J-777D01*
G03Y555667I222J-333D01*
G02X80333Y553723I-777J-1167D01*
G03X79667I-333J-222D01*
G02X77333I-1167J777D01*
G03X76667I-333J-222D01*
G02X74333I-1167J777D01*
G03X73667I-333J-222D01*
G02X71333I-1167J777D01*
G03X70667I-333J-222D01*
G02X68333I-1167J777D01*
G03X67667I-333J-222D01*
G02X65333I-1167J777D01*
G03X64667I-333J-222D01*
G37*
G36*
G01X1913006Y556655D02*
G02X1912416Y555278I794J-1155D01*
G03X1911794Y555545I-395J-63D01*
G02X1912384Y556922I-794J1155D01*
G03X1913006Y556655I395J63D01*
G37*
G36*
G01X369006Y556601D02*
G02X368922Y554910I1074J-901D01*
G03X368285Y554941I-330J-226D01*
G02X366182Y554890I-1074J901D01*
G03X365594I-294J-271D01*
G02Y556794I-1029J952D01*
G03X366182I294J271D01*
G02X368369Y556632I1029J-952D01*
G03X369006Y556601I330J226D01*
G37*
G36*
G01X1018651Y556604D02*
G02X1018629Y555029I1149J-804D01*
G03X1017968Y555038I-334J-220D01*
G02X1015790Y554890I-1149J804D01*
G03X1015202I-294J-271D01*
G02Y556794I-1029J952D01*
G03X1015790I294J271D01*
G02X1017990Y556613I1029J-952D01*
G03X1018651Y556604I334J220D01*
G37*
G36*
G01X1536281Y560614D02*
G02X1533713Y558729I-1385J-805D01*
G03X1533131Y558740I-296J-269D01*
G02X1530906Y558677I-1145J1120D01*
G03X1530366I-270J-295D01*
G02X1528206I-1080J1183D01*
G03X1527666I-270J-295D01*
G02X1525021Y560201I-1080J1183D01*
G03X1524612Y560686I-391J85D01*
G02X1525595Y563490I-74J1600D01*
G03X1526144Y563510I264J301D01*
G02X1528365Y563569I1141J-1124D01*
G03X1528905I270J295D01*
G02X1531065I1080J-1183D01*
G03X1531605I270J295D01*
G02X1533765I1080J-1183D01*
G03X1534305I270J295D01*
G02X1536151Y563793I1080J-1183D01*
G03X1536740Y564098I192J351D01*
G02X1538930Y565399I1591J-185D01*
G03X1539480Y565787I150J371D01*
G02X1542280Y566920I1600J72D01*
G03X1542880I300J265D01*
G02X1543019Y567059I1200J-1061D01*
G03Y567659I-265J300D01*
G02X1545217Y569988I1062J1200D01*
G03X1545737Y569947I284J282D01*
G02X1547621Y569956I948J-1291D01*
G03X1548140Y570001I233J325D01*
G02X1550532Y567875I1145J-1120D01*
G03X1550560Y567342I311J-251D01*
G02X1550607Y565129I-1135J-1131D01*
G03X1550601Y564596I295J-270D01*
G02X1548459Y562241I-1206J-1055D01*
G03X1547940Y562196I-233J-325D01*
G02X1545716Y562132I-1145J1120D01*
G03X1545151Y562106I-269J-296D01*
G02X1542887Y562002I-1184J1079D01*
G03X1542347I-270J-295D01*
G02X1539752Y562663I-1080J1183D01*
G03X1539426Y562744I-189J-65D01*
G02X1539284Y562625I-1098J1166D01*
G03X1539290Y562300I119J-160D01*
G02X1536784Y561034I-905J-1322D01*
G03X1536451Y561190I-200J7D01*
G02X1536379Y561129I-1071J1191D01*
G03X1536281Y560614I248J-314D01*
G37*
G36*
G01X1377086Y560726D02*
G02X1374974Y560635I-1016J-966D01*
G03X1374935Y561176I-313J249D01*
G02X1377398Y562710I1026J1097D01*
G03X1378051Y562532I383J117D01*
G02X1377603Y561386I949J-1032D01*
G03X1377234Y561476I-199J-16D01*
G02X1377078Y561269I-1273J797D01*
G03X1377086Y560726I298J-267D01*
G37*
G36*
G01X1286743Y560598D02*
G02X1286157Y562180I-1343J402D01*
G03X1286757Y562402I217J336D01*
G02X1288885Y563162I1343J-402D01*
G03X1289506Y563450I224J332D01*
G02X1290115Y562138I1394J-150D01*
G03X1289494Y561850I-224J-332D01*
G02X1287343Y560820I-1394J150D01*
G03X1286743Y560598I-217J-336D01*
G37*
G36*
G01X64667Y560723D02*
G02Y562277I-1167J777D01*
G03X65333I333J222D01*
G02X67667I1167J-777D01*
G03X68333I333J222D01*
G02X70667I1167J-777D01*
G03X71333I333J222D01*
G02X73667I1167J-777D01*
G03X74333I333J222D01*
G02X76667I1167J-777D01*
G03X77333I333J222D01*
G02X79667I1167J-777D01*
G03X80333I333J222D01*
G02Y560723I1167J-777D01*
G03X79667I-333J-222D01*
G02X77333I-1167J777D01*
G03X76667I-333J-222D01*
G02X74333I-1167J777D01*
G03X73667I-333J-222D01*
G02X71333I-1167J777D01*
G03X70667I-333J-222D01*
G02X68333I-1167J777D01*
G03X67667I-333J-222D01*
G02X65333I-1167J777D01*
G03X64667I-333J-222D01*
G37*
G36*
G01X1744116Y562666D02*
G02X1742395Y562912I-1016J-966D01*
G03X1742484Y563534I-201J346D01*
G02X1742513Y565496I1016J966D01*
G03X1742447Y566118I-281J285D01*
G02X1742199Y568282I753J1183D01*
G03X1742155Y568881I-285J280D01*
G02X1744001Y569018I845J1119D01*
G03X1744045Y568419I285J-280D01*
G02X1744187Y566304I-845J-1119D01*
G03X1744253Y565682I281J-285D01*
G02X1744205Y563288I-753J-1182D01*
G03X1744116Y562666I201J-346D01*
G37*
G36*
G01X1934521Y563300D02*
G02X1933278Y562368I79J-1400D01*
G03X1932879Y562900I-377J133D01*
G02X1934122Y563832I-79J1400D01*
G03X1934521Y563300I377J-133D01*
G37*
G36*
G01X1417391Y563595D02*
G02X1417219Y561871I1011J-971D01*
G03X1416593Y561933I-337J-215D01*
G02X1416765Y563657I-1011J971D01*
G03X1417391Y563595I337J215D01*
G37*
G36*
G01X1324551Y564312D02*
G02X1322613Y562358I-778J-1167D01*
G03X1321998Y562415I-331J-224D01*
G02X1319833Y562623I-998J985D01*
G03X1319167I-333J-222D01*
G02X1316833I-1167J777D01*
G03X1316167I-333J-222D01*
G02X1313833I-1167J777D01*
G03X1313167I-333J-222D01*
G02X1310833I-1167J777D01*
G03X1310167I-333J-222D01*
G02X1307833I-1167J777D01*
G03X1307167I-333J-222D01*
G02X1304833I-1167J777D01*
G03X1304167I-333J-222D01*
G02X1301990Y564373I-1167J778D01*
G03Y564927I-288J277D01*
G02X1302223Y567067I1010J973D01*
G03Y567733I-222J333D01*
G02X1301990Y569873I777J1167D01*
G03Y570427I-288J277D01*
G02X1304167Y572177I1010J972D01*
G03X1304833I333J222D01*
G02X1307167I1167J-777D01*
G03X1307833I333J222D01*
G02X1310167I1167J-777D01*
G03X1310833I333J222D01*
G02X1313167I1167J-777D01*
G03X1313833I333J222D01*
G02X1316167I1167J-777D01*
G03X1316833I333J222D01*
G02X1319167I1167J-777D01*
G03X1319833I333J222D01*
G02X1322167I1167J-777D01*
G03X1322833I333J222D01*
G02X1325010Y570427I1167J-778D01*
G03Y569873I288J-277D01*
G02X1324809Y567755I-1010J-973D01*
G03X1324758Y567143I230J-327D01*
G02X1324551Y564978I-984J-998D01*
G03Y564312I222J-333D01*
G37*
G36*
G01X645967Y562523D02*
G02Y564077I-1167J777D01*
G03X646633I333J222D01*
G02X648967I1167J-777D01*
G03X649633I333J222D01*
G02X651967I1167J-777D01*
G03X652633I333J222D01*
G02Y562523I1167J-777D01*
G03X651967I-333J-222D01*
G02X649633I-1167J777D01*
G03X648967I-333J-222D01*
G02X646633I-1167J777D01*
G03X645967I-333J-222D01*
G37*
G36*
G01X1781547Y566291D02*
G02X1780064Y566043I-546J-1291D01*
G03X1779953Y566709I-267J298D01*
G02X1779579Y569057I547J1291D01*
G03Y569661I-262J302D01*
G02X1781421I921J1057D01*
G03Y569057I262J-302D01*
G02X1781436Y566957I-921J-1057D01*
G03X1781547Y566291I267J-298D01*
G37*
G36*
G01X1291833Y574879D02*
G02X1290274Y576083I-4430J-4124D01*
G03X1290847Y576550I190J352D01*
G02X1290798Y577116I1343J401D01*
G03X1290376Y577563I-397J48D01*
G02X1291684Y578798I-84J1399D01*
G03X1292106Y578351I397J-48D01*
G02X1292140Y575551I84J-1399D01*
G03X1291833Y574879I-14J-400D01*
G37*
G36*
G01X309183Y566016D02*
G02X309148Y567525I-1199J727D01*
G03X309822Y567541I332J223D01*
G02X309857Y566032I1199J-727D01*
G03X309183Y566016I-332J-223D01*
G37*
G36*
G01X958791D02*
G02X958756Y567525I-1199J727D01*
G03X959430Y567541I332J223D01*
G02X959465Y566032I1199J-727D01*
G03X958791Y566016I-332J-223D01*
G37*
G36*
G01X1936343Y569287D02*
G02X1935512Y567803I557J-1287D01*
G03X1934957Y568113I-396J-57D01*
G02X1935788Y569597I-557J1287D01*
G03X1936343Y569287I396J57D01*
G37*
G36*
G01X1726471Y569981D02*
G02X1724917I-777J-1167D01*
G03Y570647I-222J333D01*
G02X1726471I777J1167D01*
G03Y569981I222J-333D01*
G37*
G36*
G01X1467630Y570975D02*
G02X1467374Y569429I1019J-963D01*
G03X1466719Y569537I-364J-166D01*
G02X1466975Y571083I-1019J963D01*
G03X1467630Y570975I364J166D01*
G37*
G36*
G01X1808834Y571292D02*
G02X1807280I-777J-1167D01*
G03Y571958I-222J333D01*
G02X1808834I777J1167D01*
G03Y571292I222J-333D01*
G37*
G36*
G01X1418208Y569756D02*
G02X1416196Y569715I-1026J955D01*
G03X1415654Y569735I-282J-284D01*
G02X1413758Y571797I-910J1066D01*
G03X1413757Y572366I-282J284D01*
G02X1415676Y574409I986J996D01*
G03X1416233Y574433I266J299D01*
G02X1416588Y574705I1019J-963D01*
G03X1416596Y575405I-190J352D01*
G02X1416340Y575591I691J1220D01*
G03X1415799I-270J-295D01*
G02Y577657I-948J1033D01*
G03X1416340I271J295D01*
G02X1418229Y577663I948J-1033D01*
G03X1418789Y577685I269J296D01*
G02X1420825Y577689I1020J-962D01*
G03X1421424Y577711I290J276D01*
G02X1423286Y575656I1085J-888D01*
G03Y574990I222J-333D01*
G02Y572656I-777J-1167D01*
G03Y571990I222J-333D01*
G02X1421493Y569857I-777J-1167D01*
G03X1420894Y569835I-290J-276D01*
G02X1418791Y569759I-1085J888D01*
G03X1418208Y569756I-290J-276D01*
G37*
G36*
G01X1764596Y575913D02*
G02X1763899Y574647I704J-1213D01*
G03X1763299Y574978I-400J-15D01*
G02X1763996Y576244I-704J1213D01*
G03X1764596Y575913I400J15D01*
G37*
G36*
G01X1386444Y573872D02*
G02X1384021Y574167I-1128J833D01*
G03X1383396Y574322I-370J-153D01*
G02X1383795Y575938I-896J1078D01*
G03X1384420Y575783I370J153D01*
G02X1386266Y575736I896J-1078D01*
G03X1386858Y575793I270J295D01*
G02X1387036Y573929I1128J-833D01*
G03X1386444Y573872I-270J-295D01*
G37*
G36*
G01X72667Y574223D02*
G02X70723Y576167I-1167J777D01*
G03Y576833I-222J333D01*
G02X72667Y578777I777J1167D01*
G03X73333I333J222D01*
G02X75277Y576833I1167J-777D01*
G03Y576167I222J-333D01*
G02X73333Y574223I-777J-1167D01*
G03X72667I-333J-222D01*
G37*
G36*
G01X79667D02*
G02X77723Y576167I-1167J777D01*
G03Y576833I-222J333D01*
G02X79667Y578777I777J1167D01*
G03X80333I333J222D01*
G02X82277Y576833I1167J-777D01*
G03Y576167I222J-333D01*
G02X80333Y574223I-777J-1167D01*
G03X79667I-333J-222D01*
G37*
G36*
G01X1304167Y575223D02*
G02X1302223Y577167I-1167J777D01*
G03Y577833I-222J333D01*
G02X1304167Y579777I777J1167D01*
G03X1304833I333J222D01*
G02X1306777Y577833I1167J-777D01*
G03Y577167I222J-333D01*
G02X1304833Y575223I-777J-1167D01*
G03X1304167I-333J-222D01*
G37*
G36*
G01X1935503Y577183D02*
G02X1935270Y578606I-1303J517D01*
G03X1935947Y578717I305J259D01*
G02X1936180Y577294I1303J-517D01*
G03X1935503Y577183I-305J-259D01*
G37*
G36*
G01X1383529Y580052D02*
G02X1381918Y580375I-1029J-952D01*
G03X1382045Y581011I-166J364D01*
G02X1383656Y580688I1029J952D01*
G03X1383529Y580052I166J-364D01*
G37*
G36*
G01X1780237Y580693D02*
G02X1778686Y580641I-736J-1193D01*
G03X1778663Y581307I-233J325D01*
G02X1778490Y583566I737J1193D01*
G03X1778401Y584232I-260J304D01*
G02X1778223Y586667I599J1268D01*
G03Y587333I-222J333D01*
G02X1779777I777J1167D01*
G03Y586667I222J-333D01*
G02X1779910Y584434I-777J-1167D01*
G03X1779999Y583768I260J-304D01*
G02X1780214Y581359I-599J-1268D01*
G03X1780237Y580693I233J-325D01*
G37*
G36*
G01X1431862Y580346D02*
G02X1429326Y580244I-1292J544D01*
G03X1428644Y580290I-355J-185D01*
G02X1428744Y581746I-1144J810D01*
G03X1429426Y581700I355J185D01*
G02X1431246Y582118I1144J-810D01*
G03X1431808Y582314I193J350D01*
G02X1432046Y582695I1293J-543D01*
G03X1431933Y583312I-301J264D01*
G02X1433644Y583625I658J1238D01*
G03X1433757Y583008I301J-264D01*
G02X1432424Y580542I-657J-1238D01*
G03X1431862Y580346I-193J-350D01*
G37*
G36*
G01X723628Y580068D02*
G02Y581732I-1128J832D01*
G03X724272I322J238D01*
G02Y580068I1128J-832D01*
G03X723628I-322J-238D01*
G37*
G36*
G01X1283571Y582011D02*
G02X1281629I-971J-1011D01*
G03Y582589I-277J289D01*
G02X1282579Y585002I971J1011D01*
G03X1282872Y585667I-6J400D01*
G02X1284548Y584343I4531J4012D01*
G03X1283969Y583904I-188J-353D01*
G02X1283571Y582589I-1369J-303D01*
G03Y582011I277J-289D01*
G37*
G36*
G01X72667Y581223D02*
G02Y582777I-1167J777D01*
G03X73333I333J222D01*
G02Y581223I1167J-777D01*
G03X72667I-333J-222D01*
G37*
G36*
G01X79667D02*
G02Y582777I-1167J777D01*
G03X80333I333J222D01*
G02Y581223I1167J-777D01*
G03X79667I-333J-222D01*
G37*
G36*
G01X1793330Y584687D02*
G02X1792007Y585292I-1160J-787D01*
G03X1792292Y585914I-46J398D01*
G02X1793615Y585309I1160J787D01*
G03X1793330Y584687I46J-398D01*
G37*
G36*
G01X1857775Y587634D02*
G02X1856700Y586776I225J-1384D01*
G03X1856265Y587320I-371J149D01*
G02X1857340Y588178I-225J1384D01*
G03X1857775Y587634I371J-149D01*
G37*
G36*
G01X1739937Y587832D02*
G02X1738234Y587102I-437J-1332D01*
G03X1737997Y587654I-361J172D01*
G02X1737778Y587747I437J1332D01*
G03X1737239Y587582I-186J-354D01*
G02X1736659Y589483I-1236J662D01*
G03X1737198Y589648I186J354D01*
G02X1738077Y590342I1236J-662D01*
G03X1738243Y591026I-101J387D01*
G02X1738719Y593394I936J1044D01*
G03X1738961Y593916I-131J378D01*
G02X1738950Y594891I1309J502D01*
G03X1738715Y595400I-377J135D01*
G02X1740531Y596239I496J1311D01*
G03X1740766Y595730I377J-135D01*
G02X1740730Y593095I-496J-1311D01*
G03X1740488Y592573I131J-378D01*
G02X1739536Y590714I-1309J-503D01*
G03X1739370Y590030I101J-387D01*
G02X1739700Y588384I-936J-1044D01*
G03X1739937Y587832I361J-172D01*
G37*
G36*
G01X1399147Y586309D02*
G02X1397189Y588243I-1167J777D01*
G03X1397195Y588899I-226J330D01*
G02X1396711Y589513I815J1141D01*
G03X1396056Y589644I-371J-151D01*
G02X1396359Y591157I-996J986D01*
G03X1397014Y591026I371J151D01*
G02X1399282Y590629I996J-986D01*
G03X1399942Y590528I363J168D01*
G02X1401990Y588613I1038J-942D01*
G03Y588059I288J-277D01*
G02X1399813Y586309I-1010J-972D01*
G03X1399147I-333J-222D01*
G37*
G36*
G01X1821030Y593534D02*
G02X1820316Y595039I-1376J269D01*
G03X1820897Y595315I189J353D01*
G02X1821611Y593810I1376J-269D01*
G03X1821030Y593534I-189J-353D01*
G37*
G36*
G01X1938781Y595545D02*
G02X1937060Y595624I-911J-1065D01*
G03X1937089Y596255I-231J327D01*
G02X1938810Y596176I911J1065D01*
G03X1938781Y595545I231J-327D01*
G37*
G36*
G01X1444034Y596099D02*
G02X1442396Y595368I-380J-1350D01*
G03X1442145Y595929I-359J176D01*
G02X1442075Y598607I380J1350D01*
G03X1442286Y599198I-128J379D01*
G02X1443923Y598616I1187J746D01*
G03X1443712Y598025I128J-379D01*
G02X1443783Y596660I-1187J-746D01*
G03X1444034Y596099I359J-176D01*
G37*
G36*
G01X64667Y595223D02*
G02X62723Y597167I-1167J777D01*
G03Y597833I-222J333D01*
G02Y600167I777J1167D01*
G03Y600833I-222J333D01*
G02X64667Y602777I777J1167D01*
G03X65333I333J222D01*
G02X67667I1167J-777D01*
G03X68333I333J222D01*
G02X70667I1167J-777D01*
G03X71333I333J222D01*
G02X73667I1167J-777D01*
G03X74333I333J222D01*
G02X76667I1167J-777D01*
G03X77333I333J222D01*
G02X79667I1167J-777D01*
G03X80333I333J222D01*
G02X82277Y600833I1167J-777D01*
G03Y600167I222J-333D01*
G02Y597833I-777J-1167D01*
G03Y597167I222J-333D01*
G02X80333Y595223I-777J-1167D01*
G03X79667I-333J-222D01*
G02X77333I-1167J777D01*
G03X76667I-333J-222D01*
G02X74333I-1167J777D01*
G03X73667I-333J-222D01*
G02X71333I-1167J777D01*
G03X70667I-333J-222D01*
G02X68333I-1167J777D01*
G03X67667I-333J-222D01*
G02X65333I-1167J777D01*
G03X64667I-333J-222D01*
G37*
G36*
G01X1310267Y597723D02*
G02X1308090Y599473I-1167J778D01*
G03Y600027I-288J277D01*
G02X1310267Y601777I1010J972D01*
G03X1310933I333J222D01*
G02X1313267I1167J-777D01*
G03X1313933I333J222D01*
G02X1316267I1167J-777D01*
G03X1316933I333J222D01*
G02X1319267I1167J-777D01*
G03X1319933I333J222D01*
G02X1322110Y600027I1167J-778D01*
G03Y599473I288J-277D01*
G02X1319933Y597723I-1010J-972D01*
G03X1319267I-333J-222D01*
G02X1316933I-1167J777D01*
G03X1316267I-333J-222D01*
G02X1313933I-1167J777D01*
G03X1313267I-333J-222D01*
G02X1310933I-1167J777D01*
G03X1310267I-333J-222D01*
G37*
G36*
G01X1385675Y603929D02*
G02X1384126Y603796I-675J-1229D01*
G03X1384069Y604460I-249J313D01*
G02X1383529Y604989I675J1229D01*
G03X1382964Y605125I-347J-199D01*
G02X1383415Y607000I-764J1175D01*
G03X1383980Y606864I347J199D01*
G02X1385618Y604593I764J-1175D01*
G03X1385675Y603929I249J-313D01*
G37*
G36*
G01X1454689Y602452D02*
G02X1452656Y604378I-1061J916D01*
G03X1452616Y604988I-278J288D01*
G02X1452404Y605181I833J1128D01*
G03X1451798Y605171I-299J-266D01*
G02X1449720Y605084I-1078J896D01*
G03X1449132Y605065I-285J-280D01*
G02X1447003Y605073I-1061J916D01*
G03X1446354Y605016I-304J-259D01*
G02X1446213Y606635I-1209J710D01*
G03X1446862Y606692I304J259D01*
G02X1449071Y606964I1209J-711D01*
G03X1449659Y606983I285J280D01*
G02X1451767Y607000I1061J-916D01*
G03X1452373Y607010I299J266D01*
G02X1454451Y607097I1078J-896D01*
G03X1455039Y607116I285J280D01*
G02X1457072Y605190I1061J-916D01*
G03X1457112Y604580I278J-288D01*
G02X1455277Y602471I-835J-1126D01*
G03X1454689Y602452I-285J-280D01*
G37*
G36*
G01X713077Y605061D02*
G02X711135I-971J-1011D01*
G03Y605639I-277J289D01*
G02X711703Y607993I971J1011D01*
G03X711931Y608582I-115J383D01*
G02X714356Y609989I1201J724D01*
G03X715016Y609932I349J195D01*
G02X714882Y608367I1090J-882D01*
G03X714222Y608424I-349J-195D01*
G02X713535Y607963I-1090J882D01*
G03X713307Y607374I115J-383D01*
G02X713077Y605639I-1201J-724D01*
G03Y605061I277J-289D01*
G37*
G36*
G01X1758833Y605723D02*
G02X1757309Y605002I-283J-1373D01*
G03X1757036Y605580I-354J186D01*
G02X1758560Y606301I283J1373D01*
G03X1758833Y605723I354J-186D01*
G37*
G36*
G01X1921759Y605264D02*
G02X1921707Y603713I1141J-815D01*
G03X1921041Y603736I-341J-210D01*
G02X1921093Y605287I-1141J815D01*
G03X1921759Y605264I341J210D01*
G37*
G36*
G01X1019465D02*
G02X1019460Y603946I1235J-664D01*
G03X1018754Y603950I-354J-186D01*
G02X1018759Y605268I-1235J664D01*
G03X1019465Y605264I354J186D01*
G37*
G36*
G01X1470066Y608965D02*
G02X1468457Y608910I-765J-1175D01*
G03X1468435Y609564I-241J319D01*
G02X1470044Y609619I765J1175D01*
G03X1470066Y608965I241J-319D01*
G37*
G36*
G01X1498208Y611341D02*
G02X1496845Y611026I-408J-1341D01*
G03X1496689Y611702I-272J293D01*
G02X1495870Y612364I407J1342D01*
G03X1495205Y612417I-350J-193D01*
G02X1493563Y611985I-1105J863D01*
G03X1493011Y611640I-153J-370D01*
G02X1492140Y613096I-1499J92D01*
G03X1492705Y613420I167J364D01*
G02X1492859Y613932I1395J-140D01*
G03X1492559Y614514I-354J186D01*
G02X1493991Y615251I191J1389D01*
G03X1494291Y614669I354J-186D01*
G02X1495327Y613959I-191J-1389D01*
G03X1495992Y613906I350J193D01*
G02X1498052Y612017I1105J-862D01*
G03X1498208Y611341I272J-293D01*
G37*
G36*
G01X730778Y610078D02*
G02X728540Y609964I-1162J785D01*
G03X727928Y609966I-307J-256D01*
G02X727933Y611770I-1071J905D01*
G03X728545Y611768I307J256D01*
G02X730698Y611754I1071J-905D01*
G03X731338Y611785I308J255D01*
G02X731418Y610109I1162J-784D01*
G03X730778Y610078I-308J-255D01*
G37*
G36*
G01X1701138Y618388D02*
G02X1700272Y616314I4633J-3152D01*
G03X1699708Y616752I-392J77D01*
G02X1700430Y618481I-602J1266D01*
G03X1701138Y618388I377J132D01*
G37*
G36*
G01X79667Y611223D02*
G02Y612777I-1167J777D01*
G03X80333I333J222D01*
G02Y611223I1167J-777D01*
G03X79667I-333J-222D01*
G37*
G36*
G01X70667Y614723D02*
G02Y616277I-1167J777D01*
G03X71333I333J222D01*
G02X73667I1167J-777D01*
G03X74333I333J222D01*
G02X76667I1167J-777D01*
G03X77333I333J222D01*
G02X79667I1167J-777D01*
G03X80333I333J222D01*
G02Y614723I1167J-777D01*
G03X79667I-333J-222D01*
G02X77333I-1167J777D01*
G03X76667I-333J-222D01*
G02X74333I-1167J777D01*
G03X73667I-333J-222D01*
G02X71333I-1167J777D01*
G03X70667I-333J-222D01*
G37*
G36*
G01X1471710Y617638D02*
G02X1469044Y617506I-1354J362D01*
G03X1468485Y617720I-374J-141D01*
G02X1469151Y619458I-646J1244D01*
G03X1469710Y619244I374J141D01*
G02X1471006Y619242I646J-1244D01*
G03X1471578Y619493I185J355D01*
G02X1474057Y619968I1354J-362D01*
G03X1474712Y619987I321J239D01*
G02X1476871Y620212I1171J-770D01*
G03X1477451Y620231I281J284D01*
G02X1479164Y620535I1049J-931D01*
G03X1479714Y620712I190J352D01*
G02X1482272Y620633I1261J-612D01*
G03X1482783Y620411I370J152D01*
G02X1481982Y618567I496J-1311D01*
G03X1481471Y618789I-370J-152D01*
G02X1480311Y618865I-497J1311D01*
G03X1479761Y618688I-190J-352D01*
G02X1477512Y618305I-1261J612D01*
G03X1476932Y618286I-281J-284D01*
G02X1474758Y618380I-1049J931D01*
G03X1474103Y618361I-321J-239D01*
G02X1472282Y617889I-1171J770D01*
G03X1471710Y617638I-185J-355D01*
G37*
G36*
G01X92682Y618956D02*
G02X92719Y617218I1118J-846D01*
G03X92131Y617249I-308J-255D01*
G02X89762Y618451I-981J1001D01*
G03X89365Y618908I-396J57D01*
G02X88156Y619592I-5J1402D01*
G03X87461Y619579I-344J-205D01*
G02X87434Y620968I-1231J671D01*
G03X88129Y620981I344J205D01*
G02X90158Y621463I1231J-671D01*
G03X90734Y621594I228J328D01*
G02X92499Y619609I1218J-694D01*
G03X92321Y619021I156J-368D01*
G02X92351Y618974I-1167J-778D01*
G03X92682Y618956I172J103D01*
G37*
G36*
G01X1778267Y620296D02*
G02X1777054Y619294I133J-1396D01*
G03X1776633Y619804I-384J112D01*
G02X1777846Y620806I-133J1396D01*
G03X1778267Y620296I384J-112D01*
G37*
G36*
G01X1517373Y618790D02*
G02X1515315Y618912I-973J1010D01*
G03X1514716Y618934I-309J-254D01*
G02X1512666Y618953I-1016J966D01*
G03X1512112Y618988I-295J-270D01*
G02X1510259Y619021I-908J1068D01*
G03X1509670Y618966I-269J-296D01*
G02X1507346Y619092I-1120J844D01*
G03X1506708Y619159I-344J-204D01*
G02X1506883Y620829I-1029J952D01*
G03X1507521Y620762I344J204D01*
G02X1509495Y620845I1029J-952D01*
G03X1510084Y620900I269J296D01*
G02X1512238Y621003I1120J-844D01*
G03X1512792Y620968I295J270D01*
G02X1514785Y620788I908J-1068D01*
G03X1515384Y620766I309J254D01*
G02X1517373Y620810I1016J-966D01*
G03X1517927I277J288D01*
G02Y618790I973J-1010D01*
G03X1517373I-277J-288D01*
G37*
G36*
G01X1322260Y281218D02*
X1318751D01*
G02Y284242I0J1512D01*
G01X1322261D01*
G02X1323772Y282740I-1J-1512D01*
G01Y282645D01*
X1323762Y282561D01*
G02X1323058Y281447I-1502J170D01*
G03X1323004Y281396I108J-168D01*
G02X1322837Y281316I-160J120D01*
G03X1322763Y281305I-8J-200D01*
G02X1322260Y281218I-505J1425D01*
G37*
G36*
G01X1323733Y281174D02*
X1327244D01*
G02X1328422Y280609I0J-1511D01*
G03X1329023Y280584I311J251D01*
G02X1328993Y278685I1016J-966D01*
G03X1328390Y278679I-299J-266D01*
G02X1327243Y278152I-1147J984D01*
G01X1323734D01*
G02X1322936Y280946I0J1511D01*
G03X1322990Y280997I-108J168D01*
G02X1323157Y281077I160J-120D01*
G03X1323231Y281088I8J200D01*
G02X1323733Y281174I503J-1425D01*
G37*
G36*
G01X1453595Y267493D02*
G02X1452725Y265728I461J-1324D01*
G03X1452214Y265980I-380J-126D01*
G02X1450528Y266623I-461J1324D01*
G03X1449828I-350J-194D01*
G02X1447378Y266622I-1225J681D01*
G03X1446679I-350J-194D01*
G02X1444228Y266623I-1225J682D01*
G03X1443529I-350J-194D01*
G02X1441623Y268529I-1226J680D01*
G03Y269228I-195J349D01*
G02X1441622Y271679I680J1226D01*
G03Y272378I-195J350D01*
G02X1443529Y274284I682J1225D01*
G03X1444229I350J194D01*
G02X1444773Y274828I1225J-681D01*
G03Y275528I-194J350D01*
G02X1444772Y277978I681J1225D01*
G03Y278677I-194J350D01*
G02X1444229Y279221I683J1224D01*
G03X1443529I-350J-194D01*
G02Y280583I-1225J681D01*
G03X1444229I350J194D01*
G02X1446679Y280584I1225J-681D01*
G03X1447378I349J194D01*
G02X1447923Y281128I1225J-682D01*
G03Y281827I-195J349D01*
G02X1447921Y284278I680J1226D01*
G03Y284977I-194J350D01*
G02Y287427I682J1225D01*
G03Y288126I-194J350D01*
G02X1447378Y288669I682J1225D01*
G03X1446679I-350J-194D01*
G02X1444229I-1225J682D01*
G03X1443530I-350J-194D01*
G02X1441622Y290575I-1226J681D01*
G03Y291274I-194J349D01*
G02X1443513Y293209I682J1225D01*
G03X1444206Y293215I345J203D01*
G02X1444711Y293731I1221J-689D01*
G03Y294419I-205J344D01*
G02X1444774Y296864I716J1205D01*
G03X1444780Y297569I-187J354D01*
G02X1444228Y298118I674J1229D01*
G03X1443529I-350J-194D01*
G02Y299479I-1226J681D01*
G03X1444228I349J194D01*
G02X1444773Y300023I1225J-682D01*
G03Y300723I-194J350D01*
G02Y303173I681J1225D01*
G03Y303873I-194J350D01*
G02X1444229Y304417I681J1225D01*
G03X1443529I-350J-194D01*
G02X1441622Y306323I-1225J681D01*
G03Y307022I-194J350D01*
G02X1441623Y309472I682J1225D01*
G03Y310172I-194J350D01*
G02X1443529Y312078I681J1225D01*
G03X1444229I350J194D01*
G02X1446135Y310172I1225J-681D01*
G03Y309472I194J-350D01*
G02X1446679Y308929I-680J-1226D01*
G03X1447378I349J194D01*
G02X1449285Y307022I1225J-682D01*
G03Y306323I194J-350D01*
G02X1449828Y305779I-683J-1224D01*
G03X1450528I350J194D01*
G02X1452434Y303873I1225J-681D01*
G03Y303173I194J-350D01*
G02X1452978Y302630I-680J-1226D01*
G03X1453677I349J194D01*
G02X1455583Y300723I1225J-682D01*
G03Y300023I194J-350D01*
G02X1456127Y299479I-681J-1225D01*
G03X1456827I350J194D01*
G02X1459277I1225J-681D01*
G03X1459977I350J194D01*
G02X1460521Y300023I1225J-681D01*
G03Y300723I-194J350D01*
G02Y303173I681J1225D01*
G03Y303873I-194J350D01*
G02X1459977Y304417I681J1225D01*
G03X1459277I-350J-194D01*
G02X1457370Y306323I-1225J681D01*
G03Y307022I-194J350D01*
G02X1456827Y307566I683J1224D01*
G03X1456127I-350J-194D01*
G02X1454221Y309472I-1225J681D01*
G03Y310172I-194J350D01*
G02X1453677Y310715I680J1226D01*
G03X1452978I-350J-194D01*
G02X1451071Y312622I-1225J682D01*
G03Y313321I-194J350D01*
G02X1450528Y313865I683J1224D01*
G03X1449828I-350J-194D01*
G02X1447922Y315771I-1225J681D01*
G03Y316471I-194J350D01*
G02X1447389Y316995I681J1225D01*
G03X1446706Y317012I-347J-200D01*
G02X1446742Y318473I-1178J760D01*
G03X1447425Y318456I347J200D01*
G02X1449828Y318377I1178J-760D01*
G03X1450528I350J194D01*
G02X1452982Y318370I1225J-681D01*
G03X1453687Y318376I351J192D01*
G02X1455580Y316482I1241J-653D01*
G03X1455574Y315776I185J-355D01*
G02X1456127Y315227I-672J-1230D01*
G03X1456827I350J194D01*
G02X1459277I1225J-681D01*
G03X1459977I350J194D01*
G02X1461884Y313321I1225J-681D01*
G03Y312622I194J-350D01*
G02X1462427Y312079I-682J-1225D01*
G03X1463126I349J194D01*
G02X1465032Y310171I1225J-682D01*
G03Y309472I194J-350D01*
G02Y307022I-682J-1225D01*
G03Y306323I195J-350D01*
G02Y303873I-681J-1225D01*
G03Y303173I194J-350D01*
G02Y300723I-681J-1225D01*
G03Y300023I194J-350D01*
G02X1463126Y298116I-681J-1225D01*
G03X1462427I-350J-194D01*
G02X1461884Y297573I-1225J682D01*
G03Y296874I194J-349D01*
G02X1459977Y294968I-682J-1225D01*
G03X1459277I-350J-194D01*
G02X1456827I-1225J681D01*
G03X1456127I-350J-194D01*
G02X1455618Y294444I-1225J681D01*
G03X1455585Y293778I204J-344D01*
G02X1454035Y293856I-834J-1127D01*
G03X1454068Y294522I-204J344D01*
G02X1453676Y294969I834J1127D01*
G03X1452977I-350J-195D01*
G02X1450521Y294975I-1226J680D01*
G03X1449817Y294970I-351J-192D01*
G02X1447352Y294943I-1240J654D01*
G03X1446652I-350J-194D01*
G02X1446143Y294419I-1225J681D01*
G03Y293731I205J-344D01*
G02X1446101Y291297I-716J-1205D01*
G03X1446107Y290592I192J-351D01*
G02X1446679Y290033I-653J-1241D01*
G03X1447378I349J194D01*
G02X1449828Y290032I1225J-682D01*
G03X1450528I350J194D01*
G02X1452978Y290033I1225J-681D01*
G03X1453677I349J194D01*
G02X1456127Y290032I1225J-682D01*
G03X1456827I350J194D01*
G02X1459277I1225J-681D01*
G03X1459977I350J194D01*
G02X1461884Y288126I1225J-681D01*
G03Y287427I194J-350D01*
G02X1462427Y286884I-682J-1225D01*
G03X1463126I349J194D01*
G02X1465032Y284977I1225J-682D01*
G03Y284277I194J-350D01*
G02Y281827I-681J-1225D01*
G03Y281127I194J-350D01*
G02X1465033Y278677I-681J-1225D01*
G03Y277978I194J-350D01*
G02X1465109Y275573I-682J-1225D01*
G03X1465125Y274890I216J-337D01*
G02X1463666Y274856I-702J-1214D01*
G03X1463650Y275539I-216J337D01*
G02X1463126Y276071I701J1214D01*
G03X1462427I-350J-194D01*
G02X1461883Y275528I-1224J683D01*
G03Y274828I194J-350D01*
G02X1459977Y272922I-681J-1225D01*
G03X1459277I-350J-194D01*
G02X1458715Y272368I-1225J681D01*
G03X1458726Y271657I189J-353D01*
G02X1459346Y271048I-624J-1255D01*
G03X1460056Y271047I355J184D01*
G02Y269754I1244J-646D01*
G03X1459346Y269755I-355J-184D01*
G02X1456847Y269778I-1244J647D01*
G03X1456136Y269789I-358J-178D01*
G02X1453677Y269772I-1234J665D01*
G03X1452978I-350J-194D01*
G02X1452434Y269229I-1224J683D01*
G03Y268529I194J-350D01*
G02X1453084Y267745I-681J-1226D01*
G03X1453595Y267493I380J126D01*
G37*
G36*
G01X1646462Y108510D02*
G02X1644556Y110416I-1225J681D01*
G03Y111116I-194J350D01*
G02Y113566I681J1225D01*
G03Y114266I-194J350D01*
G02X1644010Y114813I681J1225D01*
G03X1643310Y114814I-350J-193D01*
G02X1642626Y114201I-1226J680D01*
G03X1642556Y113501I154J-369D01*
G02X1641228Y113633I-786J-1161D01*
G03X1641298Y114333I-154J369D01*
G02X1641440Y116740I786J1161D01*
G03X1641455Y117442I-183J355D01*
G02X1643356Y119376I695J1218D01*
G03X1644041Y119371I344J204D01*
G02X1645919Y117415I1196J-731D01*
G03Y116716I194J-350D01*
G02X1646462Y116172I-683J-1224D01*
G03X1647162I350J194D01*
G02X1649612Y116173I1225J-681D01*
G03X1650311I350J194D01*
G02X1652217Y114266I1225J-682D01*
G03Y113566I194J-350D01*
G02X1652761Y113023I-680J-1226D01*
G03X1653460I350J194D01*
G02X1655910Y113022I1225J-682D01*
G03X1656610I350J194D01*
G02X1657154Y113566I1225J-681D01*
G03Y114266I-194J350D01*
G02X1657153Y116716I681J1225D01*
G03Y117415I-194J349D01*
G02X1656607Y117963I682J1225D01*
G03X1655906Y117960I-350J-194D01*
G02X1654005Y119861I-1233J668D01*
G03X1654008Y120562I-191J351D01*
G02X1654004Y123016I677J1228D01*
G03Y123715I-194J349D01*
G02X1653461Y124258I682J1225D01*
G03X1652762I-349J-194D01*
G02X1650855Y126164I-1226J681D01*
G03Y126864I-194J350D01*
G02Y129314I681J1225D01*
G03Y130014I-194J350D01*
G02X1650854Y132464I681J1225D01*
G03Y133163I-194J350D01*
G02X1650850Y135611I682J1225D01*
G03Y136309I-195J349D01*
G02X1650855Y138761I682J1225D01*
G03Y139461I-194J350D01*
G02Y141912I681J1226D01*
G03Y142612I-194J350D01*
G02X1650856Y145063I681J1225D01*
G03Y145762I-195J350D01*
G02X1652216I680J1226D01*
G03Y145063I195J-349D01*
G02X1652761Y144519I-680J-1226D01*
G03X1653460I350J194D01*
G02X1655910Y144518I1225J-682D01*
G03X1656610I350J194D01*
G02X1657154Y145062I1225J-681D01*
G03Y145762I-194J350D01*
G02X1659060Y147668I681J1225D01*
G03X1659760I350J194D01*
G02X1660304Y148212I1225J-681D01*
G03Y148912I-194J350D01*
G02X1661666I681J1225D01*
G03Y148212I194J-350D01*
G02X1662220Y147651I-680J-1226D01*
G03X1662930Y147662I352J189D01*
G02X1662951Y146374I1256J-624D01*
G03X1662241Y146363I-352J-189D01*
G02X1661666Y145762I-1255J625D01*
G03Y145062I194J-350D01*
G02X1661667Y142612I-681J-1225D01*
G03Y141913I194J-349D01*
G02Y139463I-682J-1225D01*
G03Y138764I194J-350D01*
G02X1662211Y138219I-682J-1225D01*
G03X1662911I350J194D01*
G02Y136857I1225J-681D01*
G03X1662211I-350J-194D01*
G02X1659761I-1225J681D01*
G03X1659061I-350J-194D01*
G02X1657155Y138763I-1225J681D01*
G03Y139463I-194J350D01*
G02X1656610Y140007I680J1226D01*
G03X1655911I-349J-194D01*
G02X1653460Y140005I-1226J680D01*
G03X1652761I-349J-194D01*
G02X1652213Y139460I-1224J683D01*
G03Y138760I194J-350D01*
G02X1652218Y136311I-681J-1226D01*
G03Y135613I195J-349D01*
G02X1652761Y135070I-682J-1225D01*
G03X1653460I350J194D01*
G02X1655367Y133163I1226J-681D01*
G03Y132464I194J-350D01*
G02X1655910Y131920I-683J-1224D01*
G03X1656610I350J194D01*
G02X1659060I1225J-681D01*
G03X1659760I350J194D01*
G02X1662210I1225J-681D01*
G03X1662910I350J194D01*
G02X1665360Y131921I1225J-681D01*
G03X1666059I350J194D01*
G02Y130557I1225J-682D01*
G03X1665360I-349J-194D01*
G02X1664816Y130014I-1224J683D01*
G03Y129314I194J-350D01*
G02X1662910Y127408I-681J-1225D01*
G03X1662210I-350J-194D01*
G02X1661666Y126864I-1225J681D01*
G03Y126164I194J-350D01*
G02X1661667Y123714I-681J-1225D01*
G03Y123015I194J-350D01*
G02X1662210Y122471I-683J-1224D01*
G03X1662910I350J194D01*
G02X1664816Y120565I1225J-681D01*
G03Y119865I194J-350D01*
G02X1664817Y117415I-681J-1225D01*
G03Y116716I194J-350D01*
G02X1665360Y116173I-682J-1225D01*
G03X1666059I350J194D01*
G02X1668509Y116172I1225J-682D01*
G03X1669209I350J194D01*
G02Y114810I1225J-681D01*
G03X1668509I-350J-194D01*
G02X1667978Y114273I-1225J681D01*
G03X1667968Y113584I198J-347D01*
G02X1666041Y111656I-730J-1197D01*
G03X1665353Y111646I-341J-208D01*
G02X1662910Y111660I-1218J695D01*
G03X1662210I-350J-194D01*
G02X1661666Y111116I-1225J681D01*
G03Y110416I194J-350D01*
G02X1659760Y108510I-681J-1225D01*
G03X1659060I-350J-194D01*
G02X1656610Y108509I-1225J681D01*
G03X1655911I-349J-194D01*
G02X1653461Y108510I-1225J682D01*
G03X1652761I-350J-194D01*
G02X1650311Y108509I-1225J681D01*
G03X1649612I-349J-194D01*
G02X1647162Y108510I-1225J682D01*
G03X1646462I-350J-194D01*
G37*
G36*
G01X1498944Y114388D02*
G02X1501966Y114398I1511J0D01*
G01Y110848D01*
X1501957Y110764D01*
G02X1500456Y109422I-1502J169D01*
G03X1500091Y108859I1J-400D01*
G02X1498755Y109691I-1281J-569D01*
G03X1499098Y110267I-16J400D01*
G02X1498944Y110930I1357J665D01*
G01Y114388D01*
G37*
G36*
G01X1614423Y107267D02*
G02X1613059I-682J-1225D01*
G03Y107966I-194J350D01*
G02X1613060Y110416I682J1225D01*
G03Y111116I-194J350D01*
G02X1612516Y111660I681J1225D01*
G03X1611816I-350J-194D01*
G02X1609366I-1225J681D01*
G03X1608666I-350J-194D01*
G02X1606760Y113566I-1225J681D01*
G03Y114266I-194J350D01*
G02X1608666Y116172I681J1225D01*
G03X1609366I350J194D01*
G02X1609909Y116716I1226J-680D01*
G03Y117415I-194J349D01*
G02X1609910Y119865I682J1225D01*
G03Y120565I-194J350D01*
G02X1609366Y121109I681J1225D01*
G03X1608666I-350J-194D01*
G02X1606759Y123015I-1225J681D01*
G03Y123714I-194J350D01*
G02X1608666Y125620I682J1225D01*
G03X1609366I350J194D01*
G02X1609910Y126164I1225J-681D01*
G03Y126864I-194J350D01*
G02X1611816Y128770I681J1225D01*
G03X1612516I350J194D01*
G02X1614966I1225J-681D01*
G03X1615666I350J194D01*
G02X1618116Y128771I1225J-681D01*
G03X1618815I350J194D01*
G02X1621265Y128770I1225J-682D01*
G03X1621965I350J194D01*
G02X1623872Y126864I1225J-681D01*
G03Y126165I194J-350D01*
G02X1624415Y125622I-682J-1225D01*
G03X1625114I350J194D01*
G02X1627012Y123710I1225J-682D01*
G03X1627018Y123005I192J-351D01*
G02X1627060Y120548I-654J-1240D01*
G03X1627054Y119857I198J-347D01*
G02X1627013Y117422I-715J-1206D01*
G03Y116720I192J-351D01*
G02X1627564Y116172I-674J-1229D01*
G03X1628264I350J194D01*
G02X1630714Y116173I1225J-681D01*
G03X1631413I350J194D01*
G02X1631957Y116716I1224J-683D01*
G03Y117415I-195J349D01*
G02X1633864Y119322I682J1225D01*
G03X1634563I350J194D01*
G02Y117958I1225J-682D01*
G03X1633864I-350J-194D01*
G02X1633320Y117415I-1224J683D01*
G03Y116716I195J-350D01*
G02X1633319Y114266I-682J-1225D01*
G03Y113566I194J-350D01*
G02X1633327Y111120I-681J-1225D01*
G03X1633322Y110426I196J-348D01*
G02X1633309Y107997I-707J-1211D01*
G03X1633299Y107307I197J-348D01*
G02X1631334Y105452I-725J-1200D01*
G03X1630630Y105458I-354J-187D01*
G02X1628753Y107375I-1230J673D01*
G03X1628772Y108074I-185J355D01*
G02X1628282Y108564I716J1206D01*
G03X1627583Y108544I-344J-204D01*
G02X1625615Y110392I-1244J647D01*
G03X1625606Y111082I-207J342D01*
G02X1625664Y113549I694J1218D01*
G03X1625672Y114258I-182J357D01*
G02X1625665Y116720I667J1233D01*
G03Y117422I-192J351D01*
G02X1625643Y119868I674J1229D01*
G03X1625649Y120559I-198J347D01*
G02X1625691Y122995I715J1206D01*
G03X1625685Y123700I-192J351D01*
G02X1625114Y124258I654J1240D01*
G03X1624415I-349J-194D01*
G02X1622508Y126165I-1225J682D01*
G03Y126864I-194J349D01*
G02X1621965Y127408I683J1224D01*
G03X1621265I-350J-194D01*
G02X1618815Y127407I-1225J681D01*
G03X1618116I-350J-194D01*
G02X1615666Y127408I-1225J682D01*
G03X1614966I-350J-194D01*
G02X1614436Y126872I-1225J681D01*
G03X1614425Y126184I199J-347D01*
G02X1614354Y123755I-735J-1194D01*
G03X1614366Y123045I190J-352D01*
G02X1614422Y120565I-625J-1255D01*
G03Y119865I194J-350D01*
G02X1614966Y119322I-680J-1226D01*
G03X1615665I350J195D01*
G02X1617524Y117391I1225J-681D01*
G03X1617515Y116682I181J-357D01*
G02X1617574Y114250I-667J-1233D01*
G03X1617583Y113560I207J-342D01*
G02X1615665Y111659I-693J-1219D01*
G03X1614966I-349J-194D01*
G02X1614422Y111116I-1224J683D01*
G03Y110416I194J-350D01*
G02X1614423Y107966I-681J-1225D01*
G03Y107267I194J-350D01*
G37*
G36*
G01X1464743Y358094D02*
G02X1462744Y358356I-1126J-835D01*
G03X1462816Y358907I-249J313D01*
G02X1462742Y359017I1125J837D01*
G03X1462092Y359067I-343J-206D01*
G02X1461366Y361323I-1076J898D01*
G03X1461851Y361819I100J387D01*
G02X1464431Y361528I1349J381D01*
G03X1464595Y360983I351J-192D01*
G02X1464815Y358645I-653J-1241D01*
G03X1464743Y358094I249J-313D01*
G37*
G36*
G01X1559790Y361274D02*
G02X1558147Y361257I-810J-1144D01*
G03X1558140Y361906I-238J322D01*
G02X1559783Y361923I810J1144D01*
G03X1559790Y361274I238J-322D01*
G37*
G36*
G01X110785Y128096D02*
G02X110826Y129597I-1163J783D01*
G03X111501Y129578I344J205D01*
G02X111460Y128077I1163J-783D01*
G03X110785Y128096I-344J-205D01*
G37*
G36*
G01X118581Y133842D02*
G03X119128Y133859I264J300D01*
G02X121151Y131918I989J-994D01*
G03X121155Y131373I295J-270D01*
G02X119191Y129374I-1017J-965D01*
G03X118646Y129369I-270J-295D01*
G02X116626Y131310I-964J1018D01*
G03X116620Y131843I-301J263D01*
G02X118581Y133842I1032J949D01*
G37*
G54D79*
X1950000Y220787D03*
Y228661D03*
G54D42*
X1037797Y608555D03*
Y551879D03*
Y589679D03*
Y570755D03*
Y50878D03*
Y88678D03*
Y69778D03*
Y13078D03*
Y31978D03*
Y-5822D03*
X388187Y608555D03*
Y551879D03*
Y589679D03*
Y570755D03*
Y50878D03*
Y13078D03*
Y31978D03*
Y-5822D03*
G54D54*
X11925Y74867D03*
X11864Y71294D03*
X11539Y39927D03*
X11500Y43400D03*
X44050Y504383D03*
X38389Y523748D03*
X27280Y510420D03*
X47550Y504367D03*
X1439Y546583D03*
X1539Y550183D03*
Y586183D03*
X1439Y582583D03*
X71500Y298000D03*
X66000Y292700D03*
X76800Y298000D03*
X76900Y292600D03*
X66500Y303400D03*
X76800D03*
X125663Y230716D03*
X125563Y227116D03*
Y259116D03*
X125663Y262716D03*
Y294716D03*
X125563Y291116D03*
Y323116D03*
X125663Y326716D03*
X125563Y355116D03*
X125663Y358716D03*
Y390716D03*
X125563Y387116D03*
X706500Y207800D03*
X706561Y211417D03*
X775171Y234316D03*
X775271Y262716D03*
X775171Y259116D03*
X775271Y294716D03*
X775171Y291116D03*
X775271Y326716D03*
X775171Y323116D03*
X775271Y358716D03*
X775171Y355116D03*
X775221Y390716D03*
X775121Y387116D03*
X1386400Y237900D03*
X1391900Y232118D03*
X1403037Y302046D03*
X1374300Y377885D03*
Y381485D03*
X1375961Y569473D03*
X1376000Y565700D03*
X1400216Y560128D03*
X1375961Y600673D03*
X1375861Y597073D03*
X1375961Y593473D03*
X1413720Y301983D03*
X1418341Y494423D03*
Y477323D03*
X1442141Y477623D03*
X1442041Y489223D03*
X1523450Y612900D03*
X1519850Y613000D03*
X1487912Y611632D03*
X1484312Y611732D03*
X1590154Y354762D03*
X1594280Y472370D03*
X1681586Y141438D03*
X1693586Y142438D03*
X1689785Y161180D03*
X1688207Y168972D03*
X1788290Y612006D03*
X1842250Y90750D03*
X1885000Y227500D03*
X1934256Y99459D03*
X1909421Y208805D03*
G54D72*
X1643803Y570630D03*
X1646756Y565118D03*
Y580079D03*
Y610000D03*
X1643803Y600551D03*
Y615512D03*
X1691047Y570630D03*
X1694000Y565118D03*
Y580079D03*
Y610000D03*
X1691047Y600551D03*
Y615512D03*
G54D63*
X50500Y205696D03*
X108174Y164127D03*
X85609Y385234D03*
X123624Y164600D03*
X234501Y270392D03*
X224390Y258920D03*
X230800Y265200D03*
X219500Y254500D03*
X195300Y229250D03*
X219000Y335900D03*
X229100Y325900D03*
X224000Y330900D03*
X234000Y320900D03*
X214000Y340900D03*
X378294Y292904D03*
X605176Y487581D03*
X628589Y463649D03*
X641107Y471989D03*
X629359Y469583D03*
X710800Y7100D03*
X705250Y8600D03*
X818960Y202230D03*
X814849Y205001D03*
X808165Y203529D03*
X803134Y202969D03*
X792514Y201290D03*
X844400Y280500D03*
X845050Y229400D03*
X844350Y344000D03*
X889586Y274278D03*
X884586Y269278D03*
X879586Y264278D03*
X874586Y259278D03*
X869586Y254278D03*
X877008Y326100D03*
X867008Y336100D03*
X872008Y331100D03*
X862008Y341100D03*
X1028136Y309815D03*
X1017083Y309910D03*
X1301240Y476228D03*
X1431664Y190213D03*
X1463369Y561763D03*
X1490821Y73750D03*
X1567425Y144373D03*
X1573121Y120649D03*
X1591865Y237407D03*
X1570020Y295340D03*
X1569926Y308064D03*
X1576074Y359600D03*
X1590530Y610620D03*
X1608099Y197125D03*
X1608280Y249234D03*
X1598028Y256422D03*
X1600552Y261281D03*
X1640001Y370790D03*
X1644856Y604930D03*
X1640921Y605334D03*
X1680139Y99073D03*
X1695734Y164676D03*
X1663566Y213009D03*
X1687741Y466988D03*
X1759093Y9310D03*
X1761872Y-7220D03*
X1734875Y9238D03*
X1777000Y115750D03*
X1778000Y120000D03*
X1723189Y176012D03*
X1758324Y232657D03*
X1758000Y250000D03*
X1789356Y38286D03*
X1780720Y153850D03*
X1784750Y124000D03*
X1828390Y165600D03*
X1832000Y165800D03*
X1836396Y481349D03*
X1852654Y164624D03*
X1847654D03*
X1847000Y198600D03*
X1954271Y80449D03*
X1908400Y101010D03*
X1949389Y152083D03*
X1963092Y167936D03*
X1944550Y176450D03*
X1950981Y168064D03*
X1966700Y152400D03*
X251213Y646784D03*
Y652784D03*
X261125Y646784D03*
Y652784D03*
X389473Y646508D03*
Y652508D03*
X379561Y646508D03*
Y652508D03*
X448593Y652514D03*
Y646514D03*
X438681D03*
Y652514D03*
X567029Y652238D03*
Y646238D03*
X576941D03*
Y652238D03*
X951795Y652234D03*
Y646234D03*
X941883D03*
Y652234D03*
X1196198Y652206D03*
Y646206D03*
X1206110D03*
Y652206D03*
X1265293Y652264D03*
Y646264D03*
X1255381D03*
Y652264D03*
X1509696Y652236D03*
Y646236D03*
X1519608D03*
Y652236D03*
G54D81*
X1912406Y518328D03*
X1904532D03*
G54D58*
X10512Y467244D03*
X20512D03*
X50512D03*
X1884100Y493000D03*
X1894100D03*
X1891086Y592105D03*
Y612105D03*
Y602105D03*
X1904100Y493000D03*
G54D74*
X1779504Y-15000D03*
G54D66*
X1392264Y23976D03*
X1513918D03*
G54D55*
X-10236Y116969D03*
X-4725D03*
X23228Y124843D03*
X17716D03*
X-10236Y132717D03*
X-4725D03*
X6299D03*
X11811D03*
X17716Y140591D03*
X23228D03*
X-10236Y373110D03*
X-4725D03*
X23228Y380984D03*
X17716D03*
X-10236Y388858D03*
X-4725D03*
X6299D03*
X11811D03*
X17716Y396732D03*
X23228D03*
G54D68*
X1527844Y80791D03*
X1724606Y235430D03*
G54D78*
X1892720Y525415D03*
X1900595D03*
X1894689Y518328D03*
X1908469Y525415D03*
X1916343D03*
X1924217D03*
G54D69*
X1627642Y-14488D03*
X1647327Y-315D03*
X1667012Y-14488D03*
X1969291Y486064D03*
Y497874D03*
G54D39*
X1630386Y413942D03*
X1634400Y412900D03*
X1630120Y418887D03*
X1621347Y415297D03*
X1603000Y422971D03*
X1611418D03*
X1673800Y201070D03*
X1681352Y196092D03*
X1469000Y345850D03*
X-19210Y162529D03*
X-17014Y455604D03*
X-17200Y510800D03*
X-17302Y506798D03*
X-13500Y486400D03*
X-14800Y526100D03*
X-18160Y522609D03*
X-19802Y476738D03*
X-19783Y481286D03*
X-16186Y519304D03*
X-12600Y578900D03*
X-14971Y540000D03*
X-17500Y574000D03*
X8660Y27274D03*
X43960Y20572D03*
X-3560Y34620D03*
X-10850Y30800D03*
X2871Y22791D03*
X19964Y18793D03*
X2934Y26933D03*
X16550Y18300D03*
X602Y30502D03*
X25827Y-16958D03*
X8988Y58267D03*
X-1750Y43320D03*
X-1920Y47290D03*
X-1470Y63910D03*
X37037Y138425D03*
X39109Y154901D03*
X5120Y276058D03*
X2269Y273532D03*
X48550Y301650D03*
X1500Y295000D03*
X47100Y327000D03*
X49200Y340650D03*
X10365Y461602D03*
X37550Y425400D03*
X40965Y429434D03*
X2450Y460000D03*
X-9600Y526100D03*
X-6650Y487800D03*
X-5680Y524570D03*
X47800Y487600D03*
X3354Y517143D03*
X6748Y517021D03*
X-6200Y505400D03*
X-6676Y501800D03*
X10932Y523601D03*
X14700Y517000D03*
X-9900Y486400D03*
X-2430Y524340D03*
X-7360Y512000D03*
X-6712Y515731D03*
X-2083Y513704D03*
X-4350Y482100D03*
X-900Y482300D03*
X22491Y500618D03*
X2350Y469650D03*
X-8318Y542216D03*
X-8200Y578600D03*
X-3100Y533991D03*
X-2500Y569500D03*
X-10947Y544117D03*
X-4300Y558400D03*
X-4100Y554400D03*
X-9287Y531604D03*
X-6566Y568363D03*
X-9291Y535201D03*
X-9283Y571324D03*
X-4500Y594000D03*
X93500Y-18000D03*
X82300Y-16600D03*
X53382Y-1173D03*
X52744Y-4368D03*
X74386Y-18439D03*
X71172Y-18486D03*
X87091Y-16391D03*
X106000Y17260D03*
X52389Y-14258D03*
X60035Y7508D03*
X51090Y8080D03*
X54307Y-8051D03*
X104500Y-1850D03*
X76106Y89337D03*
X86600Y94000D03*
X70980Y97166D03*
X105898Y55194D03*
X82046Y90043D03*
X98420Y112198D03*
X99250Y160370D03*
X104424Y110833D03*
X87200Y152374D03*
X91913Y121318D03*
X77790Y121030D03*
X79670Y132300D03*
X75660Y152380D03*
X78950Y152810D03*
X91306Y157194D03*
X61800Y191600D03*
X76143Y183019D03*
X61356Y181000D03*
X61256Y186000D03*
X90831Y184982D03*
X86731Y189148D03*
X107700Y211040D03*
X104820Y202100D03*
X102507Y211047D03*
X79300Y272300D03*
X84000Y272500D03*
X99500Y223800D03*
X97200Y265000D03*
X99758Y240300D03*
X91600Y278700D03*
X70700Y330349D03*
X93500Y289000D03*
X58400Y314600D03*
X53000Y323500D03*
X52804Y333247D03*
X61300Y328600D03*
X93500Y285000D03*
X93400Y296000D03*
X53400Y298100D03*
X79410Y331636D03*
X84000Y324542D03*
X53100Y327000D03*
X64700Y310525D03*
X69125Y310625D03*
X84300Y305700D03*
Y310700D03*
X66300Y285850D03*
X72904Y284898D03*
X84300Y289000D03*
X82050Y283951D03*
X77103Y283900D03*
X88000Y343900D03*
X88600Y302997D03*
X94360Y335210D03*
X82500Y341400D03*
X103500Y304700D03*
X104600Y316602D03*
X103500Y308500D03*
X84866Y294213D03*
X79400Y325400D03*
X84300Y299000D03*
X87400Y337200D03*
X103200Y330190D03*
X88840Y324740D03*
X53100Y315000D03*
X53250Y302800D03*
X102322Y295478D03*
X66900Y322000D03*
X60400Y355750D03*
X57395Y366795D03*
X55500Y371700D03*
X109500Y370000D03*
X61914Y368731D03*
X57800Y376100D03*
X60565Y380131D03*
X65000Y383000D03*
X74800Y379700D03*
X80200D03*
X62600Y375100D03*
X87900Y347500D03*
X93712Y380507D03*
X97472Y380934D03*
X90518Y388828D03*
X54900Y389400D03*
X110452Y407092D03*
X79100Y347000D03*
X61041Y351737D03*
X74800Y383114D03*
X66016Y468350D03*
X106392Y527413D03*
X59731Y480066D03*
X71050Y478670D03*
X86100Y505200D03*
X105392Y566000D03*
X102236Y614167D03*
X106192Y604600D03*
X132959Y33700D03*
X163391D03*
X160431Y27899D03*
X130313D03*
X157084Y34100D03*
X153738Y27899D03*
X126580Y33700D03*
X123620Y27899D03*
X150391Y34100D03*
X147045Y27899D03*
X169770Y33700D03*
X167124Y27899D03*
X132959Y-4100D03*
X130313Y17157D03*
X163391Y-4100D03*
X160431Y17157D03*
Y-9901D03*
X163477Y12114D03*
X130313Y-9901D03*
X132959Y12114D03*
X157084Y-3700D03*
X153738Y17157D03*
Y-9901D03*
X157084Y12114D03*
X126580Y-4100D03*
X123620Y17157D03*
Y-9901D03*
X126666Y12114D03*
X147045Y17157D03*
X150391Y-3700D03*
X147045Y-9901D03*
X150391Y12114D03*
X169770Y-4100D03*
X167124Y17157D03*
Y-9901D03*
X169770Y12114D03*
X114680Y17320D03*
X120273Y9157D03*
X116070Y35780D03*
X114050Y21320D03*
X116692Y-1800D03*
X116300Y-9460D03*
X132959Y71500D03*
X130313Y92757D03*
X163391Y71500D03*
X160431Y92757D03*
Y65699D03*
X163477Y87714D03*
X130313Y65699D03*
X132959Y87714D03*
X157084Y71900D03*
X153738Y92757D03*
Y65699D03*
X157084Y87714D03*
X126580Y71500D03*
X123620Y92757D03*
Y65699D03*
X126666Y87714D03*
X150391Y71900D03*
X147045Y92757D03*
Y65699D03*
X150391Y87714D03*
X169770Y71500D03*
X167124Y92757D03*
Y65699D03*
X169770Y87714D03*
X130313Y54957D03*
X160431D03*
X163477Y49914D03*
X132959D03*
X153738Y54957D03*
X157084Y49914D03*
X123620Y54957D03*
X126666Y49914D03*
X147045Y54957D03*
X150391Y49914D03*
X167124Y54957D03*
X169770Y49914D03*
X119892Y84700D03*
X120273Y46957D03*
X116200Y70387D03*
X115980Y73680D03*
X117600Y193805D03*
X122542Y214019D03*
X150000Y194850D03*
Y199850D03*
X162800Y195600D03*
X162788Y200650D03*
X124340Y197750D03*
X122203Y246675D03*
X122400Y278671D03*
X122361Y342649D03*
X122493Y310633D03*
X122473Y374716D03*
X153392Y404000D03*
X167640Y404842D03*
X118220Y360500D03*
X151909Y413267D03*
X148409Y422239D03*
X153392Y407500D03*
X167680Y408440D03*
X157862Y416012D03*
X150650Y409860D03*
X130313Y518157D03*
X160431D03*
X163477Y513114D03*
X160431Y528899D03*
X132959Y513114D03*
X130313Y528899D03*
X153738Y518157D03*
Y528899D03*
X157084Y513114D03*
X123620Y518157D03*
Y528899D03*
X126666Y513114D03*
X147045Y518157D03*
X150391Y513114D03*
X147045Y528899D03*
X167124Y518157D03*
Y528899D03*
X169770Y513114D03*
X119892Y510100D03*
X116927Y517900D03*
X132959Y534700D03*
X163391D03*
X157084Y535100D03*
X126580Y534700D03*
X150391Y535100D03*
X169770Y534700D03*
X130313Y555957D03*
X132959Y572500D03*
X160431Y555957D03*
X163391Y572500D03*
X163477Y550914D03*
X160431Y566699D03*
X132959Y550914D03*
X130313Y566699D03*
X153738Y555957D03*
X157084Y572900D03*
Y550914D03*
X153738Y566699D03*
X123620Y555957D03*
X126580Y572500D03*
X126666Y550914D03*
X123620Y566699D03*
X147045Y555957D03*
X150391Y572900D03*
Y550914D03*
X147045Y566699D03*
X167124Y555957D03*
X169770Y572500D03*
Y550914D03*
X167124Y566699D03*
X163477Y588714D03*
X132959D03*
X157084D03*
X126666D03*
X150391D03*
X169770D03*
X113692Y566000D03*
X119892Y536983D03*
Y547900D03*
Y574700D03*
Y585700D03*
X114150Y585850D03*
X114509Y575658D03*
X116927Y555700D03*
X115883Y548024D03*
X132959Y610300D03*
X130313Y593757D03*
X163391Y610300D03*
X160431Y593757D03*
Y604499D03*
X130313D03*
X157084Y610700D03*
X153738Y593757D03*
Y604499D03*
X126580Y610300D03*
X123620Y593757D03*
Y604499D03*
X150391Y610700D03*
X147045Y593757D03*
Y604499D03*
X167124Y593757D03*
X169770Y610300D03*
X167124Y604499D03*
X114792Y604600D03*
X119892Y612583D03*
X116927Y593500D03*
X193895Y34100D03*
X190549Y27899D03*
X187202Y34100D03*
X183856Y27899D03*
X206581Y33700D03*
X203935Y27899D03*
X230706Y34100D03*
X227360Y27899D03*
X200202Y33700D03*
X197242Y27899D03*
X224013Y34100D03*
X220667Y27899D03*
X234053D03*
X193895Y-3700D03*
X190549Y17157D03*
Y-9901D03*
X193895Y12114D03*
X187202Y-3700D03*
X183856Y17157D03*
Y-9901D03*
X187202Y12114D03*
X206581Y-4100D03*
X203935Y17157D03*
Y-9901D03*
X206581Y12114D03*
X230706Y-3700D03*
X227360Y17157D03*
Y-9901D03*
X230706Y12114D03*
X200202Y-4100D03*
X197242Y17157D03*
Y-9901D03*
X200288Y12114D03*
X224013Y-3700D03*
X220667Y17157D03*
Y-9901D03*
X224013Y12114D03*
X234053Y17157D03*
Y-9901D03*
X193895Y71900D03*
X190549Y92757D03*
Y65699D03*
X193895Y87714D03*
X187202Y71900D03*
X183856Y92757D03*
Y65699D03*
X187202Y87714D03*
X206581Y71500D03*
X203935Y92757D03*
Y65699D03*
X206581Y87714D03*
X230706Y71900D03*
X227360Y92757D03*
Y65699D03*
X230706Y87714D03*
X200202Y71500D03*
X197242Y92757D03*
Y65699D03*
X200288Y87714D03*
X224013Y71900D03*
X220667Y92761D03*
Y65699D03*
X224013Y87714D03*
X234053Y92757D03*
Y65699D03*
X190549Y54957D03*
X193895Y49914D03*
X183856Y54957D03*
X187202Y49914D03*
X203935Y54957D03*
X206581Y49914D03*
X227360Y54957D03*
X230706Y49914D03*
X197242Y54957D03*
X200288Y49914D03*
X220667Y54957D03*
X224013Y49914D03*
X234053Y54957D03*
Y112327D03*
X206600Y372400D03*
X190549Y518157D03*
X193895Y513114D03*
X190549Y528899D03*
X183856Y518157D03*
Y528899D03*
X187202Y513114D03*
X203935Y518157D03*
X206581Y513114D03*
X203935Y528899D03*
X227360Y518157D03*
Y528899D03*
X230706Y513114D03*
X197242Y518157D03*
X200288Y513114D03*
X197242Y528899D03*
X220667Y518161D03*
Y528899D03*
X224013Y513114D03*
X234053Y518157D03*
Y528899D03*
X233292Y498500D03*
X193895Y535100D03*
X187202D03*
X206581Y534700D03*
X230706Y535100D03*
X200202Y534700D03*
X224013Y535100D03*
X190549Y555957D03*
X193895Y572900D03*
Y550914D03*
X190549Y566699D03*
X183856Y555957D03*
X187202Y572900D03*
Y550914D03*
X183856Y566699D03*
X203935Y555957D03*
X206581Y572500D03*
Y550914D03*
X203935Y566699D03*
X227360Y555957D03*
X230706Y572900D03*
Y550914D03*
X227360Y566699D03*
X197242Y555957D03*
X200202Y572500D03*
X200288Y550914D03*
X197242Y566699D03*
X220667Y555961D03*
X224013Y572900D03*
Y550914D03*
X220667Y566699D03*
X234053Y555957D03*
Y566699D03*
X193895Y588714D03*
X187202D03*
X206581D03*
X230706D03*
X200288D03*
X224013D03*
X190549Y593757D03*
X193895Y610700D03*
X190549Y604499D03*
X183856Y593757D03*
X187202Y610700D03*
X183856Y604499D03*
X206581Y610300D03*
X203935Y593757D03*
Y604499D03*
X230706Y610700D03*
X227360Y593757D03*
Y604499D03*
X197242Y593757D03*
X200202Y610300D03*
X197242Y604499D03*
X224013Y610700D03*
X220667Y593761D03*
Y604499D03*
X234053Y593757D03*
Y604499D03*
X243392Y33700D03*
X240746Y27899D03*
X267517Y34100D03*
X264171Y27899D03*
X237013Y33700D03*
X260824Y34100D03*
X257478Y27899D03*
X280203Y33700D03*
X277557Y27899D03*
X273824Y33700D03*
X270864Y27899D03*
X294289D03*
X243392Y-4100D03*
X240746Y17157D03*
Y-9901D03*
X243392Y12114D03*
X267517Y-3700D03*
X264171Y17157D03*
Y-9901D03*
X267517Y12114D03*
X237013Y-4100D03*
X237099Y12114D03*
X260824Y-3700D03*
X257478Y17157D03*
Y-9901D03*
X260824Y12114D03*
X280203Y-4100D03*
X277557Y17157D03*
Y-9901D03*
X280203Y12114D03*
X270864Y17157D03*
X273824Y-4100D03*
X270864Y-9901D03*
X273910Y12114D03*
X294289Y17157D03*
Y-9901D03*
X243392Y71500D03*
X240746Y92757D03*
Y65699D03*
X243392Y87714D03*
X267517Y71900D03*
X264171Y92757D03*
Y65699D03*
X267517Y87714D03*
X237013Y71500D03*
X237099Y87714D03*
X260824Y71900D03*
X257478Y92757D03*
Y65699D03*
X260824Y87714D03*
X280203Y71500D03*
X277557Y92757D03*
Y65699D03*
X280203Y87714D03*
X270864Y92757D03*
X273824Y71500D03*
X270864Y65699D03*
X273910Y87714D03*
X294289Y92757D03*
Y65699D03*
X240746Y54957D03*
X243392Y49914D03*
X264171Y54957D03*
X267517Y49914D03*
X237099D03*
X257478Y54957D03*
X260824Y49914D03*
X277557Y54957D03*
X280203Y49914D03*
X270864Y54957D03*
X273910Y49914D03*
X294289Y54957D03*
X240746Y112327D03*
X243392Y106934D03*
X264171Y112327D03*
X267517Y107284D03*
X237099D03*
X257478Y112327D03*
X260824Y107284D03*
X277557Y112327D03*
X280203Y106934D03*
X270864Y112327D03*
X273910Y107284D03*
X294889Y110927D03*
X274619Y205210D03*
X271239Y207159D03*
X277999Y218860D03*
X281379Y216909D03*
X284759Y218860D03*
X294899Y216909D03*
Y220809D03*
X288139D03*
X284759Y203260D03*
Y211060D03*
X294899Y205210D03*
Y209109D03*
X281379Y205210D03*
Y209109D03*
X291519Y203260D03*
Y211060D03*
X288139Y201309D03*
Y213009D03*
Y205210D03*
Y209109D03*
X267859D03*
X277999Y199360D03*
X274619Y201309D03*
X271239Y203260D03*
X294899Y197409D03*
X274619Y209109D03*
X264179Y257860D03*
X281379Y228610D03*
X288139Y224709D03*
X271239Y257860D03*
X284759Y230559D03*
X288139Y228610D03*
X277999Y222760D03*
X264092Y242260D03*
X271239D03*
X264179Y261760D03*
X271239D03*
X264179Y246160D03*
X271239D03*
Y250060D03*
X277999Y226660D03*
X271239Y253960D03*
X267859Y248109D03*
X281379Y224709D03*
X284759Y222760D03*
X267859Y255909D03*
X281379Y267609D03*
X277999Y238360D03*
X281379Y236409D03*
X284759Y250060D03*
X288139Y248109D03*
X277999Y242260D03*
X284759Y238360D03*
X288139Y263709D03*
X277999Y257860D03*
X281379Y255909D03*
X284759Y269560D03*
X288139Y267609D03*
X277999Y261760D03*
X284759Y257860D03*
X281379Y248109D03*
X288139Y244209D03*
Y259809D03*
X277999Y246160D03*
X288139Y240309D03*
X277999Y265660D03*
X284759Y261760D03*
X281379Y244209D03*
X284759Y242260D03*
X281379Y263709D03*
X294899Y232509D03*
Y236409D03*
Y252009D03*
Y255909D03*
Y240309D03*
Y259809D03*
X239778Y274478D03*
X271239Y277360D03*
Y281260D03*
X267392Y276000D03*
X267359Y279310D03*
Y283209D03*
X288139Y279310D03*
X284759Y281260D03*
X291519D03*
X277999D03*
X274619Y279310D03*
Y283209D03*
X288139D03*
X281379Y279310D03*
Y283209D03*
X294899D03*
Y279310D03*
X267859Y271509D03*
X264179Y273460D03*
X274619Y271509D03*
X294899D03*
Y267609D03*
X291519Y273460D03*
X277999D03*
X271239Y335860D03*
X264179D03*
X271239Y331960D03*
X264179D03*
X271239Y343660D03*
Y339760D03*
X267859Y345609D03*
Y337809D03*
X288139Y333909D03*
X281379Y330009D03*
Y341709D03*
X277999Y339760D03*
X288139Y330009D03*
X284759Y328060D03*
Y339760D03*
X277999Y335860D03*
Y331960D03*
X284759Y335860D03*
X281379Y333909D03*
X288139Y337809D03*
X294899Y341709D03*
Y337809D03*
X271239Y320260D03*
Y324160D03*
X270939Y316160D03*
X267359Y318309D03*
X267859Y326110D03*
X267392Y322000D03*
X270892Y304660D03*
Y311960D03*
Y300760D03*
Y308560D03*
Y292959D03*
Y289060D03*
Y285500D03*
Y296860D03*
X281379Y302709D03*
X288139D03*
X294899D03*
X291519Y304660D03*
X281379Y306609D03*
Y310509D03*
X288139Y306609D03*
Y310509D03*
X284759Y304660D03*
X294899Y310509D03*
Y306609D03*
X281379Y287109D03*
X288139Y291009D03*
X284759Y289060D03*
X291519D03*
Y296860D03*
X288139Y298809D03*
X274619Y306609D03*
Y310509D03*
X277999Y304660D03*
X274619Y302709D03*
Y298809D03*
Y294909D03*
X277999Y289060D03*
X274619Y287109D03*
Y291009D03*
X277999Y296860D03*
X288139Y287109D03*
X281379Y298809D03*
Y294909D03*
X288139D03*
X284759Y296860D03*
X281379Y291009D03*
X294899Y298809D03*
Y294909D03*
Y291009D03*
Y287109D03*
X291519Y312460D03*
X284759D03*
X277999D03*
X274619Y314409D03*
X294899D03*
X281379D03*
X288139D03*
X274619Y318309D03*
X291519Y320260D03*
X284759D03*
X288139Y322209D03*
X281379D03*
X291519Y324160D03*
X277999D03*
X294899Y326109D03*
Y330009D03*
X288139Y372909D03*
X281379Y369010D03*
Y380709D03*
X277999Y378760D03*
X288139Y369010D03*
X284759Y367060D03*
Y378760D03*
X277999Y374860D03*
X294899Y376809D03*
Y380709D03*
X264179Y351460D03*
X271239D03*
X264179Y347560D03*
X271239D03*
X284759Y374860D03*
X277999Y370959D03*
X288139Y376809D03*
X281379Y372909D03*
X284759Y359260D03*
X281379Y361209D03*
X288139Y349509D03*
X284759Y347560D03*
X277999Y355360D03*
Y359260D03*
X284759Y386560D03*
Y394359D03*
X294899Y388509D03*
Y392410D03*
X281379Y388509D03*
Y392410D03*
X291519Y386560D03*
Y394359D03*
X288139Y353409D03*
X281379Y349509D03*
X284759Y355360D03*
X288139Y388509D03*
X277999Y351460D03*
X288139Y396309D03*
Y357309D03*
Y384609D03*
X281379Y353409D03*
X288139Y392410D03*
X294899Y361209D03*
Y365109D03*
Y345609D03*
Y357309D03*
X274619Y400209D03*
X281379D03*
X271239Y394359D03*
X267859Y392410D03*
X294899Y400209D03*
X271239Y398260D03*
X277999D03*
X274619Y396309D03*
X240746Y518157D03*
Y528899D03*
X243392Y513114D03*
X264171Y518157D03*
Y528899D03*
X267517Y513114D03*
X237099D03*
X257478Y518157D03*
Y528899D03*
X260824Y513114D03*
X277557Y518157D03*
X280203Y513114D03*
X277557Y528899D03*
X270864Y518157D03*
X273910Y513114D03*
X270864Y528899D03*
X294289Y518157D03*
Y528899D03*
X239592Y495900D03*
X243392Y495694D03*
X264171Y498487D03*
X267584Y493919D03*
X236892Y490800D03*
X257478Y498487D03*
X260824Y493744D03*
X277557Y498644D03*
X280203Y493244D03*
X271092Y498644D03*
X273992Y493744D03*
X294392Y493100D03*
X243392Y534700D03*
X267517Y535100D03*
X237013Y534700D03*
X260824Y535100D03*
X280203Y534700D03*
X273824D03*
X240746Y555957D03*
X243392Y572500D03*
Y550914D03*
X240746Y566699D03*
X264171Y555957D03*
X267517Y572900D03*
Y550914D03*
X264171Y566699D03*
X237013Y572500D03*
X237099Y550914D03*
X257478Y555957D03*
X260824Y572900D03*
Y550914D03*
X257478Y566699D03*
X277557Y555957D03*
X280203Y572500D03*
Y550914D03*
X277557Y566699D03*
X270864Y555957D03*
X273824Y572500D03*
X273910Y550914D03*
X270864Y566699D03*
X294289Y555957D03*
Y566699D03*
X243392Y588714D03*
X267517D03*
X237099D03*
X260824D03*
X280203D03*
X273910D03*
X240746Y593757D03*
X243392Y610300D03*
X240746Y604499D03*
X267517Y610700D03*
X264171Y593757D03*
Y604499D03*
X237013Y610300D03*
X257478Y593757D03*
X260824Y610700D03*
X257478Y604499D03*
X280203Y610300D03*
X277557Y593757D03*
Y604499D03*
X273824Y610300D03*
X270864Y593757D03*
Y604499D03*
X294289Y593757D03*
Y604499D03*
X308157Y-7180D03*
X307675Y17057D03*
Y28014D03*
X321061D03*
X327754Y35957D03*
X324407Y28014D03*
Y35957D03*
X314368Y28014D03*
X311021Y35957D03*
X304328Y34100D03*
X300982Y27899D03*
X297635Y34100D03*
X334447Y35957D03*
X331100Y28014D03*
X354525Y28022D03*
X354526Y35957D03*
X351179Y28022D03*
X347833Y35957D03*
X344486D03*
Y28022D03*
X337793Y35957D03*
X341140Y28022D03*
X334446Y28014D03*
X321061Y17057D03*
Y-7108D03*
X327754Y9114D03*
Y-1743D03*
X324407Y17057D03*
Y-9901D03*
Y-4536D03*
Y9114D03*
X314368Y-7108D03*
X311021Y-4536D03*
X314368Y17057D03*
X311021Y9114D03*
X304328Y-3700D03*
X300982Y17157D03*
Y-9901D03*
X304328Y12114D03*
X297635Y-3700D03*
Y12114D03*
X334447Y-1743D03*
X334446Y9114D03*
X331100Y-9786D03*
Y17057D03*
X354526Y-7108D03*
Y17057D03*
X354525Y-1742D03*
X351179Y-9901D03*
Y17057D03*
X347833Y9122D03*
Y-1743D03*
X344486Y9122D03*
Y-4536D03*
Y17057D03*
Y-9786D03*
X337793Y9114D03*
Y-4536D03*
X341140Y17057D03*
Y-7108D03*
X334447D03*
Y17057D03*
X321061Y-1743D03*
X314368Y-1843D03*
X331100Y-4536D03*
X327754Y-7108D03*
X317714Y-9786D03*
X311021D03*
X321061Y9114D03*
X311021Y28014D03*
X321061Y35957D03*
X314368D03*
X317714Y28014D03*
X311021Y17057D03*
X317714D03*
X327754D03*
Y28014D03*
X347833Y-7108D03*
X357872Y-9786D03*
X351179Y9122D03*
X341140Y-1743D03*
X337793Y-9901D03*
X357872Y-1858D03*
X341140Y9122D03*
X347833Y17057D03*
X341140Y35957D03*
X337793Y17057D03*
Y28014D03*
X357872D03*
Y17014D03*
X351179Y35957D03*
X347833Y28022D03*
X351179Y-4536D03*
X331100Y35957D03*
Y9114D03*
X314368D03*
X317714Y35957D03*
Y-4536D03*
Y9114D03*
X307928Y67802D03*
X307675Y54857D03*
Y92657D03*
X311021Y84714D03*
X304328Y71900D03*
X300982Y92757D03*
Y65699D03*
X304328Y87714D03*
X297635Y71900D03*
Y87714D03*
X321061Y54857D03*
X327754Y46914D03*
X324407Y54857D03*
Y46914D03*
X314368Y54857D03*
X311021Y46914D03*
X300982Y54957D03*
X304328Y49914D03*
X297635D03*
X334446Y46914D03*
X331100Y54857D03*
X354526D03*
X354525Y46922D03*
X351179Y54857D03*
X347833Y46922D03*
X344486D03*
Y54857D03*
X337793Y46914D03*
X341140Y54857D03*
X334447D03*
X311021Y65814D03*
X314368Y46914D03*
X321061D03*
X331100D03*
X327754Y54857D03*
X311021Y89964D03*
X337793Y54857D03*
X351179Y46922D03*
X347833Y54857D03*
X341140Y46922D03*
X357872Y46914D03*
X317714Y54857D03*
X311021D03*
X317714Y46914D03*
X300982Y109700D03*
X304178Y107684D03*
X297635Y105084D03*
X313637Y105725D03*
X342218Y205210D03*
X298279Y214960D03*
X308418Y216909D03*
Y220809D03*
X305039Y214960D03*
X301659Y213009D03*
Y216909D03*
Y220809D03*
X345598Y207159D03*
X342218Y209109D03*
X348978Y205210D03*
Y216909D03*
X352357Y218860D03*
X345598D03*
X342218Y213009D03*
X338838Y214960D03*
X359117Y211060D03*
Y218860D03*
X355737Y216909D03*
Y213009D03*
X357987Y193507D03*
X338838Y218860D03*
X345598Y214960D03*
X352357D03*
X345598Y203260D03*
X355737Y205210D03*
X342218Y216909D03*
X335458Y220809D03*
X338838Y207158D03*
Y203258D03*
X345598Y211060D03*
X348978Y213009D03*
X338838Y250060D03*
Y230560D03*
X298279Y222760D03*
X305039D03*
X328698Y236409D03*
X301659Y224709D03*
X328698Y248109D03*
Y240309D03*
Y244209D03*
X325318Y238360D03*
Y246160D03*
X335458Y240309D03*
Y244209D03*
X321938Y240309D03*
Y244209D03*
X332078Y238360D03*
Y246160D03*
X342218Y224709D03*
X345598Y230559D03*
X338838Y222760D03*
X352357D03*
X348978Y224709D03*
X355737D03*
X348978Y228610D03*
X352357Y230559D03*
X348978Y236409D03*
Y240309D03*
X352357Y234460D03*
X345598Y242260D03*
Y234460D03*
X342218Y240309D03*
Y228610D03*
Y236409D03*
X298279Y261760D03*
Y230559D03*
X301659Y244209D03*
X305039Y242260D03*
X301659Y232509D03*
X311798Y230559D03*
X318558Y234460D03*
Y222760D03*
X321938Y224709D03*
X305039Y257860D03*
X311798Y234460D03*
X315178Y236409D03*
Y224709D03*
X321938Y228610D03*
X328698Y255909D03*
Y263709D03*
X338838Y257860D03*
Y261760D03*
X325318Y257860D03*
Y261760D03*
X335458Y255909D03*
Y263709D03*
X298279Y250060D03*
X301659Y263709D03*
X305039Y261760D03*
X301659Y252009D03*
X298279Y242260D03*
X305039Y238360D03*
Y253960D03*
X311798Y226660D03*
X332078Y253960D03*
X315178Y263709D03*
X305039Y234460D03*
X321938Y232509D03*
X332078Y265660D03*
X315178Y275409D03*
X301659Y255909D03*
X298279Y238360D03*
X315178Y228610D03*
X332078Y257860D03*
X315178Y267609D03*
X301659Y236409D03*
X318558Y230559D03*
X332078Y261760D03*
X315178Y271509D03*
X298279Y257860D03*
X311798Y265660D03*
Y273460D03*
X321938Y267609D03*
Y271509D03*
X308418Y267609D03*
Y271509D03*
X318558Y265660D03*
Y273460D03*
X352357Y246160D03*
X345598D03*
X359117Y230559D03*
X355737Y228610D03*
Y236409D03*
X352357Y242260D03*
X355737Y240309D03*
X301659Y279310D03*
X298279Y281260D03*
X308418Y283209D03*
X305039Y281260D03*
X308418Y279310D03*
X311798Y281260D03*
X301659Y283209D03*
X348978Y267609D03*
X357057Y277360D03*
Y281260D03*
X345598D03*
X348978Y283209D03*
X345598Y277360D03*
X348978Y279310D03*
Y275409D03*
Y271509D03*
X352357Y265660D03*
X355737Y263709D03*
X342218Y244209D03*
Y232509D03*
X355737Y244209D03*
X348978D03*
X345598Y226660D03*
X352357D03*
X348978Y232509D03*
X355737D03*
X345598Y222760D03*
X332078D03*
X328698Y224709D03*
X332078Y226660D03*
X335458Y228610D03*
X328698D03*
X332078Y230560D03*
X335458Y232510D03*
X311798Y242260D03*
X315178Y244209D03*
X311798Y246160D03*
X315178Y248109D03*
X308418D03*
X352357Y250060D03*
X345598D03*
X318558D03*
X355737Y252009D03*
X348978D03*
X321938D03*
X352357Y253960D03*
X345598D03*
X355737Y255909D03*
X348978D03*
X338838Y273460D03*
X345598Y261760D03*
X338838Y269560D03*
X332078Y273460D03*
X298279D03*
X335458Y275409D03*
X328698D03*
X338838Y277360D03*
X332078D03*
X325318D03*
X335458Y279310D03*
X328698D03*
X321938D03*
X335458Y271509D03*
X342218Y252009D03*
Y248109D03*
X301659Y271509D03*
X328698D03*
X298279Y269560D03*
X348978Y259809D03*
X345598Y257860D03*
X352357D03*
X348978Y337809D03*
X305039Y339760D03*
X298279Y335860D03*
X332078D03*
Y343660D03*
X342218Y337809D03*
Y341709D03*
X328698Y337809D03*
Y341709D03*
X338838Y335860D03*
Y343660D03*
X305039Y335860D03*
X301659Y333909D03*
X335458Y337809D03*
X318558Y328060D03*
Y335860D03*
X301659Y341709D03*
X298279Y339760D03*
X335458Y333909D03*
X318558Y324160D03*
X335458Y341709D03*
X318558Y331960D03*
X305039Y343660D03*
X315178Y326110D03*
Y333909D03*
X325318Y328060D03*
Y331960D03*
X311798Y328060D03*
Y331960D03*
X321938Y326110D03*
Y333909D03*
X308418Y306609D03*
X301659Y310509D03*
Y306609D03*
X311798Y304660D03*
X305039D03*
X321938Y306609D03*
X325318Y304660D03*
Y308560D03*
X298279Y304660D03*
X308418Y302709D03*
X301659D03*
X315178D03*
X321938D03*
X318558Y304660D03*
Y308560D03*
X321938Y291009D03*
X318558Y296860D03*
X315178Y294909D03*
X321938D03*
X301659D03*
X325318Y285160D03*
Y289060D03*
Y296860D03*
X298279D03*
Y289060D03*
X308418Y298809D03*
X301659D03*
X305039Y289060D03*
X308418Y291009D03*
Y287109D03*
X311798Y289060D03*
X308418Y294909D03*
X311798Y296860D03*
X305039D03*
X315178Y287109D03*
X318558Y285160D03*
X321938Y287109D03*
X301659D03*
Y291009D03*
X315178Y298809D03*
X321938D03*
X318558Y289060D03*
X315178Y291009D03*
X332078Y308560D03*
Y304660D03*
X328698Y302709D03*
Y306609D03*
Y287109D03*
Y291009D03*
Y294909D03*
Y298809D03*
X332078Y296860D03*
Y285160D03*
Y289060D03*
X315178Y306609D03*
X308418Y310509D03*
X311798Y312460D03*
X305039D03*
X298279D03*
X308418Y314409D03*
X301659D03*
X335458Y298809D03*
X357057Y296860D03*
X348978Y287109D03*
X345598Y285160D03*
X357057D03*
Y292959D03*
X348978Y298809D03*
Y291009D03*
X345598Y289060D03*
Y292959D03*
Y296860D03*
X348978Y294909D03*
X345598Y300760D03*
X348978Y302709D03*
X357057Y300760D03*
Y308560D03*
X348978Y306609D03*
X345598Y304660D03*
Y308560D03*
X348978Y310509D03*
X357057Y304660D03*
Y289060D03*
X342218Y302709D03*
Y306609D03*
Y291009D03*
Y287109D03*
Y294909D03*
Y298809D03*
X338838Y308560D03*
X335458Y302709D03*
X338838Y304660D03*
X335458Y306609D03*
Y287109D03*
X338838Y289060D03*
Y285160D03*
X335458Y291009D03*
X338838Y296860D03*
X335458Y294909D03*
X348978Y314409D03*
X357057Y312460D03*
X345598D03*
X357987Y327609D03*
X348978Y322209D03*
X355737Y333909D03*
X345598Y316360D03*
X348978Y318309D03*
Y330009D03*
X352357Y331960D03*
X348978Y326110D03*
X357057Y320260D03*
Y324160D03*
Y316360D03*
X328698Y314409D03*
X321938D03*
X332078Y328060D03*
X328698Y322209D03*
Y318309D03*
X332078Y324160D03*
Y320260D03*
Y316360D03*
X325318Y320260D03*
X305039D03*
X321938Y318309D03*
X315178D03*
X318558Y316360D03*
X301659Y322209D03*
X325318Y316360D03*
X305039Y324160D03*
X311798Y320260D03*
X308418Y322209D03*
X301659Y326110D03*
X335458Y314409D03*
Y326110D03*
Y318309D03*
Y322209D03*
X338838Y320260D03*
Y324160D03*
Y328060D03*
X298279Y324160D03*
Y320260D03*
X355737Y345609D03*
X348978Y341709D03*
X352357Y343660D03*
X321938Y341709D03*
X352357Y339760D03*
X321938Y345609D03*
X359117Y343660D03*
X355737Y341709D03*
X342218Y384609D03*
X341892Y396301D03*
X345598Y386560D03*
X298279Y374860D03*
Y382660D03*
X308418Y376809D03*
Y380709D03*
X305039Y374860D03*
Y382660D03*
X301659Y376809D03*
X328698Y353409D03*
X301659Y384609D03*
X328698Y361209D03*
X301659Y372909D03*
X328698Y349509D03*
X301659Y380709D03*
X328698Y357309D03*
X325318Y351460D03*
Y359260D03*
X335458Y353409D03*
Y357309D03*
X321938Y353409D03*
Y357309D03*
X332078Y351460D03*
Y359260D03*
X348978Y388509D03*
X342218Y380709D03*
X351192Y402800D03*
X345598Y378760D03*
X348978Y380709D03*
X345598Y367060D03*
X348978Y372909D03*
X342218D03*
X338838Y374860D03*
Y370959D03*
Y378760D03*
X352357D03*
Y374860D03*
X359117Y386560D03*
X355737Y380709D03*
X359117Y374860D03*
X355737Y372909D03*
X348978Y369010D03*
X352357Y367060D03*
X355737Y384609D03*
X345598Y355360D03*
X348978Y357309D03*
X345598Y351460D03*
X348978Y361209D03*
X345598Y363160D03*
X342218Y357309D03*
Y369010D03*
Y361209D03*
X301659Y365109D03*
X298279Y367060D03*
X305039Y355360D03*
X301659Y353409D03*
X318558Y363160D03*
X311798Y367060D03*
X321938Y372909D03*
X318558Y374860D03*
X315178Y361209D03*
X311798Y363160D03*
X321938Y369010D03*
X315178Y372909D03*
X298279Y347560D03*
X301659Y345609D03*
X305039Y359260D03*
X298279Y355360D03*
X301659Y361209D03*
X318558Y367060D03*
X311798Y370959D03*
X335458Y345609D03*
X305039Y363160D03*
X321938Y365109D03*
X298279Y359260D03*
X315178Y369010D03*
X352357Y351460D03*
Y363160D03*
X359117D03*
X355737Y361209D03*
Y369010D03*
X352357Y355360D03*
X355737Y357309D03*
X359117Y351460D03*
X345598Y370959D03*
X355737Y353409D03*
X348978D03*
X342218Y365109D03*
Y353409D03*
X338838Y367060D03*
X348978Y365109D03*
X355737D03*
X352357Y370959D03*
X338838Y382660D03*
X357987Y402800D03*
X345598Y382660D03*
X352357D03*
X348978Y392410D03*
X355737D03*
X315178Y349509D03*
Y353409D03*
X348978Y345609D03*
X311798Y355360D03*
Y347560D03*
Y351460D03*
X308418Y349509D03*
X342218D03*
X345598Y347560D03*
X315178Y384609D03*
X348978D03*
X315178Y380709D03*
X335458Y376809D03*
X332078Y374860D03*
X345598D03*
X328698Y372909D03*
X332078Y370959D03*
X328698Y369010D03*
X335458D03*
X332078Y367060D03*
X335458Y365109D03*
X338838Y363160D03*
X352357Y347560D03*
X307675Y518057D03*
X311021Y510114D03*
X300982Y518157D03*
Y528899D03*
X304328Y513114D03*
X297635D03*
X301092Y493300D03*
X304392Y494700D03*
X297835Y494944D03*
X311701Y499136D03*
X311021Y515364D03*
X307675Y555857D03*
X311021Y536957D03*
X304328Y535100D03*
X297635D03*
X321061Y566814D03*
Y555857D03*
X327754Y547914D03*
Y574757D03*
X324407Y555857D03*
Y566814D03*
Y547914D03*
Y574757D03*
X314368Y566814D03*
X311021Y574757D03*
X314368Y555857D03*
X311021Y547914D03*
X300982Y555957D03*
X304328Y572900D03*
Y550914D03*
X300982Y566699D03*
X297635Y572900D03*
Y550914D03*
X334446Y547914D03*
X334447Y574757D03*
X331100Y555857D03*
Y566814D03*
X354526Y555857D03*
X354525Y566822D03*
X354526Y574757D03*
X351179Y555857D03*
Y566822D03*
X347833Y547922D03*
Y574757D03*
X344486Y547922D03*
Y574757D03*
Y566822D03*
Y555857D03*
X337793Y547914D03*
Y574757D03*
X341140Y555857D03*
Y566822D03*
X334447Y555857D03*
X334446Y566814D03*
X327754Y585714D03*
X324407D03*
X311021D03*
X304328Y588714D03*
X297635D03*
X334446Y585714D03*
X347833Y585722D03*
X344486D03*
X337793Y585714D03*
X331100Y547914D03*
X321061D03*
X314368D03*
Y536957D03*
X327754Y555857D03*
X317714D03*
X311021D03*
X327754Y566814D03*
X331100Y574757D03*
Y585714D03*
X314368D03*
Y574757D03*
X317714Y566814D03*
X321061Y585714D03*
Y574757D03*
X351179Y547922D03*
X341140D03*
X337793Y555857D03*
X347833D03*
X357910Y555842D03*
X337793Y566814D03*
X341140Y574757D03*
Y585722D03*
X351179Y574757D03*
X357872Y574742D03*
X347833Y566822D03*
X357910Y566814D03*
X351179Y585722D03*
X317714Y547914D03*
Y574757D03*
Y585714D03*
X307675Y593657D03*
X308157Y607220D03*
X321061Y593657D03*
Y607292D03*
X327754Y612457D03*
X324407Y604499D03*
Y593657D03*
Y609864D03*
X314368Y607292D03*
X311021Y609864D03*
X314368Y593657D03*
X304328Y610700D03*
X300982Y593757D03*
Y604499D03*
X297635Y610700D03*
X334447Y612457D03*
X331100Y604614D03*
Y593657D03*
X354526Y607292D03*
X354525Y612358D03*
X351179Y604499D03*
Y593657D03*
X347833Y612357D03*
X344486Y609864D03*
Y604614D03*
Y593657D03*
X337793Y609864D03*
X341140Y607292D03*
Y593657D03*
X334447Y607292D03*
Y593657D03*
X327754Y607292D03*
X331100Y609864D03*
X327754Y593657D03*
X317714D03*
X311021D03*
X317714Y604614D03*
X311021D03*
X314368Y612457D03*
X321061D03*
X337793Y593657D03*
Y604499D03*
X357872Y604614D03*
Y612242D03*
X352109Y609918D03*
X347833Y607292D03*
X341140Y612457D03*
X347833Y593657D03*
X317714Y609864D03*
X404723Y28022D03*
X401377Y35957D03*
X364565Y28014D03*
Y35942D03*
X361218Y28014D03*
X414762Y28021D03*
X398029Y28007D03*
X404723Y35957D03*
X414763D03*
X408069Y28007D03*
X394684Y35957D03*
X404722Y-9901D03*
X404723Y17057D03*
X401376Y9121D03*
X401375Y-1743D03*
X364565Y-9786D03*
Y-1858D03*
Y9114D03*
X361218Y-9786D03*
Y-1858D03*
Y9114D03*
X414761Y-7108D03*
X414762Y17058D03*
X398029Y17042D03*
Y-9901D03*
X404722Y9121D03*
Y-4536D03*
X414763Y9122D03*
X414761Y-1743D03*
X408069Y17042D03*
X408068Y-7108D03*
X394682Y11792D03*
X394683Y-2200D03*
X367911Y-9786D03*
Y-1858D03*
Y9114D03*
Y35942D03*
Y28014D03*
X398029Y-4536D03*
X401375Y-7108D03*
X408068Y-1743D03*
X418108Y-4536D03*
X411415Y-9786D03*
X398029Y9107D03*
X418108Y-9701D03*
X408069Y35942D03*
X411416Y17057D03*
X401376Y17042D03*
X418108D03*
X398029Y35942D03*
X401377Y28022D03*
X418108Y28007D03*
X411416Y28022D03*
X418108Y35942D03*
Y9107D03*
X408069D03*
X376700Y-1300D03*
X371258Y-1858D03*
Y-9800D03*
X411415Y36058D03*
Y-4536D03*
X411416Y9122D03*
X374401Y-11346D03*
X394682Y17157D03*
X394492Y54700D03*
X404723Y54857D03*
X401377Y46922D03*
X364565Y54842D03*
X414763Y54857D03*
X398029Y54842D03*
X404723Y46922D03*
X414763D03*
X408069Y54842D03*
X394682Y49592D03*
X367911Y54842D03*
X366992Y65950D03*
X367742Y73450D03*
X401376Y54842D03*
X408069Y46907D03*
X398029D03*
X411416Y54857D03*
X418108Y54842D03*
Y46907D03*
X367911Y46914D03*
X380600Y37400D03*
X384992Y81600D03*
X411416Y46922D03*
X372637Y207159D03*
X399676D03*
X372637Y211060D03*
X392916D03*
X389537Y213009D03*
X396296D03*
X369257D03*
X396296Y216909D03*
X376017D03*
X365877Y218860D03*
X372637D03*
X362497Y216909D03*
X382777Y213009D03*
X399676Y218860D03*
X386157Y211060D03*
X407706Y216909D03*
X415634Y220096D03*
Y216196D03*
X419214Y218147D03*
Y222047D03*
X379397Y207159D03*
X369257Y216909D03*
X382777D03*
X379397Y218860D03*
X392916D03*
X362497Y213009D03*
X386157Y218860D03*
X389537Y216909D03*
X376017Y213009D03*
X378267Y193507D03*
X386157Y207159D03*
X382777Y201309D03*
X365877Y214960D03*
X372637D03*
X379397D03*
X359117D03*
X365877Y203260D03*
X376017Y205211D03*
X362497Y205210D03*
X386157Y214960D03*
X404392Y199100D03*
X392898Y195041D03*
X392916Y214960D03*
Y203260D03*
X396296Y197359D03*
X399676Y203260D03*
Y214960D03*
Y211060D03*
X415634Y239596D03*
Y243496D03*
X419214Y245447D03*
X396296Y244209D03*
Y240309D03*
X376017Y224709D03*
X372637Y222760D03*
X365877D03*
X369257Y224709D03*
X362497D03*
X386157Y222760D03*
X396296Y228610D03*
X389537Y224709D03*
X399676Y222760D03*
X415634Y227896D03*
Y231797D03*
X419214Y225947D03*
Y229847D03*
X382777Y224709D03*
X379397Y222760D03*
X359117D03*
X392916D03*
X396296Y224709D03*
X379397Y230559D03*
X365877Y242260D03*
X407706Y236409D03*
X372637Y234460D03*
X365877D03*
X372637Y230559D03*
X365877D03*
X369257Y236409D03*
X362497D03*
X369257Y228610D03*
X362497D03*
X382777D03*
X389537Y236409D03*
X399676Y230559D03*
Y234460D03*
X382777Y236409D03*
X392916Y230559D03*
X407706Y224709D03*
Y228610D03*
X376017Y236409D03*
X369257Y240309D03*
X376017D03*
X386157Y230559D03*
X372637Y242260D03*
X379397Y234460D03*
X399676Y238360D03*
X359117Y242260D03*
X362497Y240309D03*
X359117Y234460D03*
Y246160D03*
X386157Y234460D03*
X392916D03*
X389537Y228610D03*
X396296Y236409D03*
X376017Y228610D03*
X372637Y253960D03*
X376017Y252009D03*
X368127Y264300D03*
X364747Y266300D03*
X362497Y259809D03*
X365877Y257860D03*
X369257Y255909D03*
X391787Y254259D03*
X388407Y256500D03*
X374887Y260300D03*
X385027Y254259D03*
X359117Y261760D03*
X371507Y262300D03*
X381647Y256400D03*
X378267Y258400D03*
X395166Y256400D03*
X418084Y253546D03*
X398546Y254259D03*
X405306Y254500D03*
X401926Y256500D03*
X386157Y226660D03*
X389537Y232509D03*
X369257Y244209D03*
X362497D03*
X372637Y226660D03*
X365877D03*
X369257Y232509D03*
X362497D03*
X379397Y226660D03*
X382777Y232509D03*
X376017D03*
X359117Y226660D03*
X407706Y240309D03*
Y232509D03*
X392916Y226660D03*
X396296Y232509D03*
X399676Y226660D03*
Y242260D03*
X362497Y248109D03*
X359117Y250060D03*
Y253960D03*
X389537Y240309D03*
X382777D03*
X392916Y242260D03*
X386157D03*
X379397D03*
X389537Y244209D03*
X382777D03*
X376017D03*
X392916Y246160D03*
X386157D03*
X379397D03*
X372637D03*
X365877D03*
X369257Y248109D03*
X365877Y250060D03*
X362497Y252009D03*
X407706Y244209D03*
X399676Y246160D03*
X388407Y345160D03*
X364747Y331509D03*
X361367Y329560D03*
X371507Y335409D03*
X362497Y337809D03*
X369257Y341709D03*
X368127Y333460D03*
X365877Y339760D03*
X372637Y343660D03*
X374887Y337360D03*
X381647Y341260D03*
X378267Y339309D03*
X385027Y343209D03*
X359117Y335860D03*
X395166Y345160D03*
X401926D03*
X407448Y338641D03*
X394648Y338341D03*
X362497Y345609D03*
X392916Y355360D03*
X396296Y357309D03*
X389537D03*
X372637Y390460D03*
X396296Y384609D03*
X372637Y386560D03*
X392916D03*
X389537Y384609D03*
X399676Y390460D03*
X376017Y372909D03*
X369257Y384609D03*
X396296Y380709D03*
X369257Y372909D03*
X362497D03*
X372637Y378760D03*
X362497Y380709D03*
X372637Y374860D03*
X365877D03*
X376017Y380709D03*
X365877Y378760D03*
X382777Y384609D03*
X386157Y374860D03*
X399676Y378760D03*
X396296Y369010D03*
X386157Y386560D03*
X389537Y372909D03*
X403056Y380709D03*
X399676Y374860D03*
X379397Y386560D03*
X369257Y380709D03*
X382777D03*
Y372909D03*
X379397Y378760D03*
Y374860D03*
X392916Y378760D03*
X362497Y384609D03*
X359117Y378760D03*
X386157D03*
X392916Y374860D03*
X389537Y380709D03*
X396296Y372909D03*
X376017Y384609D03*
X379397Y367060D03*
X365877Y355360D03*
X403056Y361209D03*
X369257Y369010D03*
X362497D03*
X369257Y361209D03*
X362497D03*
X372637Y367060D03*
X365877D03*
X372637Y363160D03*
X365877D03*
X382777Y369010D03*
X389537Y361209D03*
X399676Y367060D03*
Y363160D03*
X382777Y361209D03*
X392916Y367060D03*
X403056Y372909D03*
Y369010D03*
X376017Y361209D03*
X369257Y357309D03*
X376017D03*
X386157Y367060D03*
X372637Y355360D03*
X379397Y363160D03*
X399676Y359260D03*
X359117Y355360D03*
X362497Y357309D03*
X359117Y367060D03*
X386157Y363160D03*
X392916D03*
X389537Y369010D03*
X396296Y361209D03*
X376017Y369010D03*
X391787Y347109D03*
X398546D03*
X379397Y370959D03*
X372637D03*
X365877D03*
X359117D03*
X386157D03*
X362497Y353409D03*
X376017D03*
X369257D03*
X389537Y365109D03*
X382777D03*
X369257D03*
X362497D03*
X376017D03*
X390657Y394359D03*
X391787Y402800D03*
X369257Y392410D03*
X362497D03*
X379397Y382660D03*
X372637D03*
X365877D03*
X359117D03*
X379397Y390460D03*
X378267Y402800D03*
X376017Y392410D03*
X386157Y382660D03*
X392916Y370959D03*
X399676D03*
X396296Y365109D03*
X403056D03*
Y357309D03*
X392916Y382660D03*
Y390460D03*
X399676Y382660D03*
X406568Y402471D03*
X403056Y392410D03*
X411431Y359351D03*
X411086Y355360D03*
X403056Y353409D03*
X369257Y349509D03*
X399676Y355360D03*
X365877Y351460D03*
X372637D03*
X379397D03*
X362497Y349509D03*
X376017D03*
X382777Y353409D03*
X386157Y355360D03*
X403056Y396309D03*
X411086Y394359D03*
Y390460D03*
X399676Y386560D03*
X411086D03*
Y382660D03*
Y378760D03*
X398546Y402900D03*
X382777Y357309D03*
X379397Y355360D03*
X402892Y400400D03*
X365877Y347560D03*
X359117D03*
X386630Y521860D03*
X367911Y529057D03*
X404723Y566822D03*
Y555857D03*
X401376Y547922D03*
X401377Y574757D03*
X361218Y566814D03*
X361320Y555842D03*
X361218Y574742D03*
X414763Y566822D03*
Y555857D03*
X398029Y566807D03*
Y555842D03*
X404723Y547922D03*
Y574757D03*
X414763D03*
Y547922D03*
X408069Y566807D03*
Y555842D03*
X394682Y550592D03*
X394684Y574757D03*
X401377Y585722D03*
X404723D03*
X414763D03*
X394682Y588392D03*
X367692Y547914D03*
Y536200D03*
X418108Y547907D03*
X408069D03*
X398029D03*
X401376Y555842D03*
X418108D03*
X411416Y555857D03*
X398029Y574742D03*
Y585707D03*
X401377Y566822D03*
X418108Y566807D03*
X408069Y574742D03*
Y585707D03*
X418108Y585599D03*
Y574742D03*
X411416Y566822D03*
X376892Y581127D03*
X370596Y585614D03*
X376792Y543700D03*
X411415Y547921D03*
X411416Y574757D03*
Y585722D03*
X394682Y569492D03*
X404723Y593657D03*
X404722Y604499D03*
X401376Y612658D03*
X364565Y604614D03*
X361218D03*
X361964Y593642D03*
X361218Y612242D03*
X414761Y607292D03*
X414763Y593657D03*
X398029Y593642D03*
Y604499D03*
X404722Y609864D03*
X414761Y612657D03*
X408068Y607292D03*
X408069Y593642D03*
X394682Y612657D03*
X408068D03*
X367911Y604614D03*
X418108Y609864D03*
X398029D03*
X401376Y593642D03*
X401375Y607292D03*
X418108Y593642D03*
X411416Y593657D03*
X411415Y604614D03*
X418108Y604499D03*
X378600Y606200D03*
X371312Y604709D03*
X371134Y612453D03*
X411415Y609864D03*
X394682Y607292D03*
X421455Y9121D03*
X421454Y-1817D03*
X438189Y35957D03*
X431494Y28007D03*
X444880Y28022D03*
X444882Y35957D03*
X460912Y33700D03*
X458266Y27899D03*
X481691D03*
X454533Y33700D03*
X451573Y27899D03*
X478344Y34100D03*
X474998Y27899D03*
X428149Y35957D03*
X421456Y28022D03*
X434842Y35957D03*
X424801Y28007D03*
X438189Y28022D03*
X438187Y-4536D03*
Y9120D03*
X431494Y-9901D03*
X444880Y-9786D03*
Y-4536D03*
X431494Y17042D03*
X444880Y17059D03*
Y9122D03*
X460912Y-4100D03*
X458266Y17157D03*
Y-9901D03*
X460912Y12114D03*
X481691Y17157D03*
Y-9901D03*
X451573Y17157D03*
X454533Y-4100D03*
X451573Y-9901D03*
X454619Y12114D03*
X478344Y-3700D03*
X474998Y17157D03*
Y-9901D03*
X478344Y12114D03*
X428147Y-1743D03*
Y9120D03*
X421454Y-7108D03*
X421456Y17057D03*
X434840Y-1743D03*
Y9120D03*
X424801Y-9786D03*
X438187D03*
X424801Y17042D03*
X438187Y17059D03*
X421456Y35957D03*
X431494Y-4536D03*
X424801D03*
X428147Y-7108D03*
X434840D03*
X441533Y-1843D03*
X434842Y17057D03*
X441533Y17042D03*
X431494Y35942D03*
X441533D03*
X428149Y28022D03*
X424801Y35942D03*
X434842Y28268D03*
X441533Y28007D03*
X428149Y17057D03*
X441533Y9107D03*
X424801D03*
X431494D03*
X448226Y11100D03*
X421455Y46921D03*
X460912Y71500D03*
X458266Y92757D03*
Y65699D03*
X460912Y87714D03*
X481691Y92757D03*
Y65699D03*
X454533Y71500D03*
X451573Y92757D03*
Y65699D03*
X454619Y87714D03*
X478344Y71900D03*
X474998Y92757D03*
Y65699D03*
X478344Y87714D03*
X438189Y46922D03*
X431494Y54842D03*
X444880Y54859D03*
Y46922D03*
X458266Y54957D03*
X460912Y49914D03*
X481691Y54957D03*
X451573D03*
X454619Y49564D03*
X474998Y54957D03*
X478344Y49914D03*
X428149Y46922D03*
X421456Y54857D03*
X434842Y46922D03*
X424801Y54842D03*
X438187Y54859D03*
X434842Y54857D03*
X441533Y54842D03*
X424801Y46907D03*
X431494D03*
X441533D03*
X428149Y54857D03*
X436113Y220096D03*
X446253Y222047D03*
X432733D03*
X442873Y220096D03*
X456393D03*
X466533Y222047D03*
X453013D03*
X463153Y220096D03*
X476672D03*
X473292Y222047D03*
X439493Y218147D03*
X459773D03*
X480052D03*
X439493Y222047D03*
X459773D03*
X480052D03*
X425974D03*
X422594Y220096D03*
X480052Y210346D03*
X458400Y276400D03*
X436113Y227896D03*
X446253Y225947D03*
X432733D03*
X442873Y227896D03*
X456393D03*
X466533Y225947D03*
X453013D03*
X463153Y227896D03*
X476672D03*
X473292Y225947D03*
X439493Y229847D03*
X459773D03*
X480052Y225947D03*
X439493D03*
X459773D03*
X480052Y229847D03*
X425974Y225947D03*
X422594Y227896D03*
X466533Y233746D03*
Y241547D03*
X476672Y235696D03*
Y239596D03*
X463153Y235696D03*
Y239596D03*
X473292Y233746D03*
Y241547D03*
X469913Y231797D03*
Y243496D03*
Y235696D03*
Y239596D03*
X425974Y233746D03*
Y241547D03*
X436113Y235696D03*
Y239596D03*
X422594Y235696D03*
Y239596D03*
X432733Y233746D03*
Y241547D03*
X446253Y233746D03*
Y241547D03*
X456393Y235696D03*
Y239596D03*
X442873Y235696D03*
Y239596D03*
X453013Y233746D03*
Y241547D03*
X456393Y247396D03*
Y255196D03*
X466533Y249347D03*
Y253247D03*
X453013Y249347D03*
Y253247D03*
X463153Y247396D03*
Y255196D03*
X476672Y247396D03*
Y255196D03*
X473292Y249347D03*
Y253247D03*
X429354Y231797D03*
X449633D03*
X459773Y245447D03*
X480052D03*
X429354Y243496D03*
X449633D03*
X459773Y257147D03*
X480052D03*
X429354Y235696D03*
X449633D03*
X459773Y249347D03*
X480052D03*
X429354Y239596D03*
X449633D03*
X459773Y253247D03*
X480052D03*
X452865Y270081D03*
X465100Y280300D03*
X434983Y255497D03*
X438363Y257446D03*
X421464Y255497D03*
X431604Y257446D03*
X448503Y263297D03*
X441743Y259397D03*
X455263Y267197D03*
X436113Y247396D03*
X446253Y249347D03*
X442873Y251296D03*
X439493Y249347D03*
X442873Y247396D03*
X439493Y245447D03*
X446253Y253247D03*
X466533Y261047D03*
X463153Y262996D03*
X477792Y276646D03*
Y280547D03*
X469913Y282496D03*
X474413Y274696D03*
X469913Y278596D03*
X466533Y268847D03*
X422594Y247396D03*
X429781Y264793D03*
X459773Y264947D03*
X469913Y266896D03*
Y262996D03*
X473292Y261047D03*
X469913Y259096D03*
X481172Y282496D03*
Y270796D03*
X480052Y264947D03*
X473292D03*
Y268847D03*
X476672Y266896D03*
Y262996D03*
X474413Y344896D03*
X481172Y321496D03*
Y325396D03*
Y317596D03*
Y333196D03*
X463671Y319386D03*
X466734Y287074D03*
X442020Y339220D03*
X438240Y339380D03*
X451883Y342646D03*
X448503Y344597D03*
X481172Y298096D03*
X469913D03*
Y301996D03*
X481172Y305896D03*
X477792Y284447D03*
Y296147D03*
Y300047D03*
Y292247D03*
X481172Y294196D03*
X469913D03*
Y290296D03*
X474413Y329296D03*
X468783Y332897D03*
X474413Y333196D03*
Y325396D03*
X477792Y323446D03*
X430089Y338428D03*
X426494Y338361D03*
X463800Y289500D03*
X464273Y342947D03*
X471033Y339047D03*
X456900Y333000D03*
X481172Y329296D03*
X471033Y342947D03*
X466100Y300021D03*
X460893Y344896D03*
X481172Y286396D03*
X477792Y311747D03*
X469913Y309797D03*
Y313696D03*
Y317596D03*
X477792Y339047D03*
Y335147D03*
Y331247D03*
X481172Y340996D03*
Y337096D03*
X453400Y293686D03*
X477792Y346847D03*
X481172Y348796D03*
X477792Y350747D03*
X443993Y381947D03*
Y389747D03*
X454133Y383896D03*
Y387796D03*
X440613Y383896D03*
Y387796D03*
X450753Y381947D03*
Y389747D03*
X464273Y381947D03*
Y389747D03*
X474413Y383896D03*
Y387796D03*
X460893Y383896D03*
Y387796D03*
X471033Y381947D03*
Y389747D03*
X481172Y383896D03*
Y387796D03*
X447373Y383896D03*
X467653Y379996D03*
X447373Y391696D03*
X467653D03*
X447373Y379996D03*
X467653Y383896D03*
X447373Y387796D03*
X467653D03*
X423714Y389747D03*
Y393647D03*
X433854Y383896D03*
Y387796D03*
X423714Y378047D03*
Y381947D03*
X430474D03*
Y389747D03*
X474413Y368296D03*
Y376096D03*
X481172Y364396D03*
X471033Y370247D03*
Y374146D03*
X481172Y368296D03*
Y376096D03*
X427094Y383896D03*
X477792Y370247D03*
X427094Y391696D03*
X477792Y378047D03*
X427094Y379996D03*
X477792Y366347D03*
X427094Y387796D03*
X477792Y374146D03*
X427094Y364396D03*
X423714Y370247D03*
X437233Y366347D03*
Y370247D03*
X423714Y358547D03*
Y366347D03*
X433854Y364396D03*
Y372197D03*
X454133Y368296D03*
Y376096D03*
X464273Y370247D03*
Y374146D03*
X450753Y370247D03*
Y374146D03*
X460893Y368296D03*
Y376096D03*
X443993Y354647D03*
Y362447D03*
X454133Y356596D03*
Y360496D03*
X440613Y356596D03*
Y360496D03*
X450753Y354647D03*
Y362447D03*
X464273Y354647D03*
Y362447D03*
X474413Y356596D03*
Y360496D03*
X460893Y356596D03*
Y360496D03*
X471033Y354647D03*
Y362447D03*
X430474Y366347D03*
X457513Y370247D03*
X447373Y356596D03*
X467653D03*
X430474Y370247D03*
X457513Y378047D03*
X447373Y364396D03*
X467653D03*
X430474Y362447D03*
X457513Y366347D03*
X447373Y352696D03*
X467653D03*
X430474Y374146D03*
X457513D03*
X447373Y360496D03*
X467653D03*
X421464Y348497D03*
X438363Y346546D03*
X424844D03*
X434983Y348497D03*
X428224D03*
X431604Y346546D03*
X471033Y346847D03*
X464273D03*
X457513Y350747D03*
X430474Y358547D03*
X433854Y356596D03*
X437233Y378047D03*
X440613Y376096D03*
X443993Y374147D03*
Y370247D03*
X481172Y356596D03*
X458266Y518157D03*
X460912Y513114D03*
X458266Y528899D03*
X481691Y518157D03*
Y528899D03*
X451573Y518157D03*
Y528899D03*
X454619Y513114D03*
X474998Y518157D03*
Y528899D03*
X478344Y513114D03*
X421456Y547922D03*
Y585722D03*
X460912Y534700D03*
X454533D03*
X478344Y535100D03*
X438189Y547922D03*
Y574757D03*
X431494Y566807D03*
X444880Y566822D03*
X444882Y574757D03*
X431494Y555842D03*
X444880Y555859D03*
Y547922D03*
X458266Y555957D03*
X460912Y572500D03*
Y550914D03*
X458266Y566699D03*
X481691Y555957D03*
Y566699D03*
X451573Y555957D03*
X454533Y572500D03*
X451573Y566699D03*
X454619Y550914D03*
X474998Y555957D03*
X478344Y572900D03*
Y550914D03*
X474998Y566699D03*
X428149Y547922D03*
Y574757D03*
X421456Y555857D03*
Y566822D03*
X434842Y547922D03*
Y574757D03*
X424801Y566807D03*
X438189Y566822D03*
X424801Y555842D03*
X438187Y555859D03*
X438189Y585722D03*
X444880D03*
X460912Y588714D03*
X454619D03*
X478344D03*
X428149Y585722D03*
X434842D03*
X431494Y574742D03*
Y547907D03*
X424801D03*
X441533D03*
X428149Y555857D03*
X434842D03*
X441533Y555842D03*
Y574742D03*
Y585707D03*
X434842Y566822D03*
X424801Y574742D03*
X431494Y585707D03*
X424801D03*
X441533Y566807D03*
X428149Y566822D03*
X447735Y588394D03*
X421454Y612560D03*
X438187Y609864D03*
X431494Y604499D03*
X444880Y604614D03*
Y609864D03*
X431494Y593642D03*
X444880Y593659D03*
X458266Y593757D03*
X460912Y610300D03*
X458266Y604499D03*
X481691Y593757D03*
Y604499D03*
X454533Y610300D03*
X451573Y593757D03*
Y604499D03*
X478344Y610700D03*
X474998Y593757D03*
Y604499D03*
X428147Y612657D03*
X421454Y607292D03*
X421456Y593657D03*
X434840Y612657D03*
X424801Y604614D03*
X438187D03*
X424801Y593642D03*
X438187Y593659D03*
X441533Y612557D03*
Y607292D03*
X434840D03*
X428147D03*
X424801Y609864D03*
X431494D03*
X434842Y593657D03*
X428149D03*
X441533Y593642D03*
X447766Y612659D03*
X485037Y34100D03*
X497723Y33700D03*
X495077Y27899D03*
X521848Y34100D03*
X518502Y27899D03*
X491344Y33700D03*
X488384Y27899D03*
X515155Y34100D03*
X511809Y27899D03*
X534534Y33700D03*
X531888Y27899D03*
X528155Y33700D03*
X525195Y27899D03*
X485037Y-3700D03*
Y12114D03*
X497723Y-4100D03*
X495077Y17157D03*
Y-9901D03*
X497723Y12114D03*
X521848Y-3700D03*
X518502Y17157D03*
Y-9901D03*
X521848Y12114D03*
X491344Y-4100D03*
X488384Y17157D03*
Y-9901D03*
X491430Y12114D03*
X511809Y17157D03*
X515155Y-3700D03*
X511809Y-9901D03*
X515155Y12114D03*
X534534Y-4100D03*
X531888Y17157D03*
Y-9901D03*
X534534Y12114D03*
X528155Y-4100D03*
X525195Y17157D03*
Y-9901D03*
X528241Y12114D03*
X485037Y71900D03*
Y87714D03*
X497723Y71500D03*
X495077Y92757D03*
Y65699D03*
X497723Y87714D03*
X521848Y71900D03*
X518502Y92757D03*
Y65699D03*
X521848Y87714D03*
X491344Y71500D03*
X488384Y92757D03*
Y65699D03*
X491430Y87714D03*
X511809Y92757D03*
X515155Y71900D03*
X511809Y65699D03*
X515155Y87714D03*
X534534Y71500D03*
X531888Y92757D03*
Y65699D03*
X534534Y87714D03*
X528155Y71500D03*
X525195Y92757D03*
Y65699D03*
X528241Y87714D03*
X485037Y49914D03*
X495077Y54957D03*
X497723Y49914D03*
X518502Y54957D03*
X521848Y49914D03*
X488384Y54957D03*
X491430Y49914D03*
X511809Y54957D03*
X515155Y49914D03*
X531888Y54957D03*
X534534Y49914D03*
X525195Y54957D03*
X528241Y49914D03*
X494927Y112357D03*
X497723Y106964D03*
X518317Y112357D03*
X521113Y106964D03*
X488634Y112357D03*
X491430Y106964D03*
X512024Y112357D03*
X514820Y106964D03*
X531888Y112357D03*
X534534Y106964D03*
X525134Y112357D03*
X528241Y107314D03*
X483432Y216196D03*
Y220096D03*
X511592Y222047D03*
X514972Y220096D03*
X518352Y222047D03*
X521731Y216196D03*
X531871Y218147D03*
X542011Y208396D03*
X531871Y202547D03*
X525111D03*
X528491Y204496D03*
X538631Y202247D03*
X483432Y212296D03*
X525111Y222047D03*
Y210346D03*
X521731Y212296D03*
X514972Y208397D03*
Y212296D03*
X508212Y216196D03*
X501452Y220096D03*
X504832Y214247D03*
X498072Y218147D03*
Y214247D03*
X494692Y220096D03*
X542011Y216196D03*
X538631Y218147D03*
X535251Y212296D03*
X531871Y210346D03*
Y214247D03*
X525111D03*
X518352D03*
Y210345D03*
X514972Y216196D03*
X511592Y214247D03*
X504832Y222047D03*
Y218147D03*
X501452Y216196D03*
X494692Y212296D03*
Y216196D03*
X542011Y212296D03*
Y220096D03*
X535251D03*
Y208397D03*
X528491Y212296D03*
X535251Y216196D03*
X484552Y272747D03*
Y276646D03*
X501452Y270796D03*
X511592Y268847D03*
X514972Y255196D03*
X501452D03*
Y251296D03*
X521731Y270796D03*
X514972Y282496D03*
X521731D03*
X508212D03*
X494692D03*
X491312Y280547D03*
X486812Y261047D03*
X483432Y262996D03*
X518352Y261047D03*
X525111D03*
X514972Y251296D03*
X518352Y272747D03*
X521731Y255196D03*
Y251296D03*
X498072Y264947D03*
X511592Y245447D03*
X514972Y243496D03*
X483432Y227896D03*
Y231797D03*
X486812Y249347D03*
Y253247D03*
X483432Y247396D03*
Y255196D03*
X498072Y280547D03*
X514972Y274696D03*
X525111Y272747D03*
X518352Y257147D03*
X508212Y274696D03*
X504832Y268847D03*
X491312Y272747D03*
X511592D03*
X504832Y276647D03*
X498072Y245447D03*
X494692Y223996D03*
X504832Y225947D03*
X484552Y280547D03*
X518352Y233746D03*
X531871Y241547D03*
Y249347D03*
X528491Y223996D03*
X531871Y237647D03*
X535251Y223996D03*
X542011D03*
X528491Y270796D03*
Y278596D03*
X542011Y270796D03*
X535251Y255196D03*
X531871Y264947D03*
X494692Y266896D03*
X504832Y257147D03*
X508212Y251296D03*
X504832Y249347D03*
X508212Y247396D03*
X518352Y264947D03*
X508212Y243496D03*
X518352Y245447D03*
X531871Y257147D03*
X528491Y255196D03*
X511592Y253247D03*
X525111Y268847D03*
X518352Y241547D03*
Y237647D03*
X521731Y239596D03*
Y243496D03*
X528491Y262996D03*
Y266896D03*
X498072Y249347D03*
X525111D03*
Y245447D03*
X508212Y266896D03*
X521731Y278596D03*
X498072Y276647D03*
X491312D03*
X511592D03*
X504832Y272747D03*
X498072Y253247D03*
Y257147D03*
X518352Y280547D03*
X535251Y243496D03*
X542011Y266896D03*
X538631Y272747D03*
X531871D03*
X538631Y280547D03*
X542011Y282496D03*
X538631Y276646D03*
X535251Y278596D03*
X531871Y280547D03*
X538631Y241547D03*
X542011Y243496D03*
Y251296D03*
Y255196D03*
Y262996D03*
X538631Y261047D03*
X531871Y245447D03*
X538631Y264947D03*
Y268847D03*
X535251Y270796D03*
X542011Y278596D03*
X535251Y274696D03*
Y282496D03*
X528491D03*
X538631Y245447D03*
Y253247D03*
X542011Y259096D03*
X535251Y262996D03*
X511592Y229847D03*
Y225947D03*
Y237647D03*
X508212Y235696D03*
X498072Y229847D03*
X504832Y233746D03*
X494692Y227896D03*
X501452Y235696D03*
X498072Y237647D03*
Y241547D03*
X542011Y227896D03*
Y235696D03*
X535251Y231797D03*
Y227896D03*
X531871Y229847D03*
X525111Y233746D03*
X521731Y223996D03*
X525111Y229847D03*
X514972Y231797D03*
X508212Y227896D03*
X511592Y233746D03*
X504832Y237647D03*
X501452Y227896D03*
Y231797D03*
X494692D03*
X501452Y239596D03*
X494692D03*
X501452Y243496D03*
X542011Y231797D03*
X538631Y233746D03*
Y229847D03*
X531871Y225947D03*
Y233746D03*
X528491Y231797D03*
X525111Y225947D03*
X518352D03*
X521731Y227896D03*
X525111Y257147D03*
X528491Y259096D03*
X525111Y276646D03*
X504832Y280547D03*
X511592D03*
X518352Y276646D03*
Y268847D03*
X498072Y272747D03*
X531871Y253247D03*
X528491Y251296D03*
X525111Y241547D03*
X528491Y239596D03*
X518352Y249347D03*
X513857Y260881D03*
X501452Y262996D03*
X504832Y261047D03*
X501452Y278596D03*
X498072Y268847D03*
X504832Y264947D03*
X494692Y262996D03*
X491312Y264947D03*
X487932Y266896D03*
X491312Y268847D03*
X487932Y270796D03*
X498072Y261047D03*
X494692Y259096D03*
X483432Y239596D03*
X521731Y262996D03*
X525111Y264947D03*
X494692Y274696D03*
X487932Y313696D03*
X491312Y315647D03*
X484552Y319546D03*
Y331247D03*
X501452Y337096D03*
X531871Y331247D03*
X491312Y288347D03*
Y284447D03*
X498072D03*
Y288347D03*
X501452Y286396D03*
X494692Y290296D03*
X498072Y292247D03*
X504832D03*
X518352Y284447D03*
X504832Y288347D03*
Y284447D03*
X508212Y286396D03*
X531871Y315647D03*
X487932Y286396D03*
X514972Y344896D03*
X511592Y342947D03*
X508212Y340996D03*
Y344896D03*
X487932Y290296D03*
X484552Y288347D03*
Y296147D03*
X498072Y339047D03*
X504832Y327347D03*
X508212Y321496D03*
X514972Y340996D03*
X518352Y331247D03*
X521731Y344896D03*
Y321496D03*
X525111Y339047D03*
X535251Y333196D03*
Y325396D03*
X484552Y284447D03*
X487932Y305896D03*
X491312Y303947D03*
X501452Y305896D03*
X494692Y298096D03*
X498072Y307847D03*
X484552Y303947D03*
X487932Y294196D03*
X491312Y296147D03*
X494692Y301996D03*
X487932D03*
X501452Y309797D03*
X487932Y298096D03*
X525111Y323446D03*
X531871D03*
X525111Y327347D03*
X528491Y333196D03*
X521731Y329296D03*
X518352Y335147D03*
X521731Y340996D03*
X525111Y319547D03*
X528491Y321496D03*
Y325396D03*
Y329296D03*
X525111Y331247D03*
X521731Y333196D03*
Y337096D03*
X511592Y311747D03*
X508212Y309797D03*
X511592Y300047D03*
Y303947D03*
X542011Y286396D03*
X531871Y284447D03*
X542011Y290296D03*
X535251Y286396D03*
X542011Y313696D03*
Y309797D03*
X538631Y307847D03*
Y303947D03*
Y300047D03*
X535251Y298096D03*
Y344896D03*
X542011D03*
Y340996D03*
Y337096D03*
X538631Y331247D03*
Y327347D03*
X535251Y317596D03*
X542011D03*
Y305896D03*
X535251D03*
X542011Y301996D03*
X538631Y296147D03*
X531871D03*
X535251Y340996D03*
X538631Y342947D03*
X542011Y333196D03*
Y329296D03*
Y325396D03*
X538631Y323446D03*
X535251Y313696D03*
X538631Y315647D03*
X484552Y311747D03*
Y315647D03*
X511592Y288347D03*
Y292245D03*
X491312Y323446D03*
X535251Y337096D03*
X528491Y340996D03*
X531871Y339047D03*
Y342947D03*
X528491Y344896D03*
X491312Y342947D03*
X528491Y305896D03*
X518352Y311747D03*
X504832D03*
X508212Y305896D03*
Y301996D03*
X504832Y303947D03*
Y300045D03*
X518352Y303947D03*
X514972Y305896D03*
Y309797D03*
X528491Y301996D03*
Y309797D03*
X525111Y311747D03*
Y307847D03*
Y303947D03*
X521731Y305896D03*
Y309797D03*
X518352Y307847D03*
X514972Y313696D03*
X528491D03*
X521731D03*
X487932Y344896D03*
X484552Y342947D03*
X518352Y296147D03*
Y300047D03*
X521731Y294196D03*
X525111Y288347D03*
X528491Y290296D03*
X525111Y296147D03*
Y292245D03*
X521731Y298096D03*
Y290296D03*
Y286396D03*
X518352Y288347D03*
Y292245D03*
X514972Y298096D03*
X501452Y325396D03*
X498072Y323446D03*
Y315647D03*
X501452Y317596D03*
X498072Y335147D03*
X501452Y321496D03*
X498072Y331247D03*
X501452Y329296D03*
Y313696D03*
X498072Y300047D03*
X508212Y298096D03*
X504832Y296147D03*
X498072D03*
X501452Y294196D03*
X511592Y296147D03*
X498072Y311747D03*
X501452Y301996D03*
X494692Y325396D03*
Y321496D03*
X491312Y319547D03*
X494692Y333196D03*
X491312Y335147D03*
X487932Y333196D03*
Y337096D03*
X484552Y339047D03*
Y335147D03*
X491312Y327347D03*
X494692Y329296D03*
X487932D03*
Y340996D03*
X494692Y313696D03*
X484552Y307847D03*
X491312D03*
Y311747D03*
X494692Y305896D03*
Y317596D03*
X487932Y321496D03*
X484552Y327347D03*
X487932Y325396D03*
X484552Y381947D03*
Y389747D03*
X494692Y395597D03*
Y399496D03*
X491312Y401447D03*
Y393647D03*
X487932Y379996D03*
Y391696D03*
Y383896D03*
Y387796D03*
X484552Y374146D03*
X514972Y352696D03*
Y348796D03*
X511592Y350747D03*
Y346847D03*
X508212Y348796D03*
X504832Y362447D03*
X494692Y368296D03*
Y352696D03*
X508212Y356596D03*
X504832Y350747D03*
X511592Y374146D03*
X501452Y383896D03*
X498072Y389747D03*
X494692Y376096D03*
X508212Y379996D03*
X521731Y368296D03*
X518352Y366347D03*
Y358547D03*
X542011Y364396D03*
X538631Y370247D03*
X542011Y372197D03*
Y352696D03*
X525111Y350747D03*
X514972Y399496D03*
X538631Y381947D03*
X531871Y385847D03*
X528491Y391696D03*
X525111Y397546D03*
X531871Y405347D03*
X511592Y362447D03*
X514972Y368296D03*
X508212Y364396D03*
X504832Y370247D03*
X508212Y376096D03*
X501452Y372197D03*
X498072Y378047D03*
X494692Y379996D03*
Y387796D03*
X518352Y350747D03*
Y354647D03*
X511592Y358547D03*
X514972Y360496D03*
Y364396D03*
X511592Y366347D03*
X508212Y368296D03*
Y372197D03*
X504832Y374146D03*
X501452Y376096D03*
X498072Y381947D03*
X494692Y383896D03*
X518352Y346847D03*
X521731Y352696D03*
X511592Y354647D03*
X498072Y370247D03*
Y374146D03*
X504832Y397546D03*
Y393647D03*
X511592D03*
X501452Y387796D03*
X511592Y385847D03*
X518352D03*
Y381947D03*
Y378047D03*
X508212Y395597D03*
X504832Y389747D03*
X508212Y391696D03*
X504832Y385847D03*
X511592Y381947D03*
X514972Y383896D03*
X521731Y379996D03*
X518352Y374146D03*
Y405347D03*
X525111D03*
Y401447D03*
X528491Y395597D03*
X535251Y399496D03*
X531871Y393647D03*
X538631Y389747D03*
Y385847D03*
X518352Y401447D03*
X521731Y403396D03*
X528491Y399496D03*
X531871Y397546D03*
X535251Y395597D03*
Y391696D03*
Y387796D03*
X542011Y383896D03*
X528491Y387796D03*
X521731D03*
Y391696D03*
X518352Y393647D03*
X514972Y395597D03*
X511592Y389747D03*
X528491Y379996D03*
Y383896D03*
X525111Y385847D03*
X521731Y383896D03*
X525111Y389747D03*
X521731Y395597D03*
X514972Y391696D03*
Y387796D03*
X528491Y376096D03*
X531871Y381947D03*
X542011Y391696D03*
Y395597D03*
Y387796D03*
X535251Y348796D03*
X538631Y346847D03*
X525111Y370247D03*
X531871D03*
X525111Y362447D03*
X528491Y360496D03*
Y356596D03*
X535251Y352696D03*
X525111Y378047D03*
Y374146D03*
Y366347D03*
X528491Y368296D03*
X521731Y364396D03*
X525111Y358547D03*
X531871Y354647D03*
Y350747D03*
X521731Y376096D03*
X528491Y372197D03*
X542011Y379996D03*
X538631Y354647D03*
Y358547D03*
Y362447D03*
X531871D03*
Y366347D03*
X535251Y372197D03*
Y376096D03*
Y379996D03*
X538631Y350747D03*
X542011Y356596D03*
X535251Y360496D03*
X531871Y358547D03*
X535251Y364396D03*
Y368296D03*
X538631Y374146D03*
X531871Y378047D03*
X525111Y346847D03*
X528491Y348796D03*
Y352696D03*
X487932Y356596D03*
X491312Y354647D03*
X511592Y401447D03*
X508212Y383896D03*
X514972Y376096D03*
X504832Y401446D03*
X487932Y352696D03*
X484552Y354647D03*
Y350747D03*
Y358547D03*
X487932Y348796D03*
X485037Y513114D03*
X495077Y518157D03*
X497723Y513114D03*
X495077Y528899D03*
X518502Y518157D03*
X521848Y513114D03*
X518502Y528899D03*
X488384Y518157D03*
Y528899D03*
X491430Y513114D03*
X511809Y518157D03*
Y528899D03*
X515155Y513114D03*
X531888Y518157D03*
X534534Y513114D03*
X531888Y528899D03*
X525195Y518157D03*
X528241Y513114D03*
X525195Y528899D03*
X494777Y498487D03*
X497723Y490894D03*
X517902Y498487D03*
X521048Y493844D03*
X488384Y498487D03*
X491430Y491144D03*
X511809Y498487D03*
X514755Y493744D03*
X530792Y498387D03*
X534534Y493394D03*
X524595Y498387D03*
X528191Y493544D03*
X485037Y535100D03*
X497723Y534700D03*
X521848Y535100D03*
X491344Y534700D03*
X515155Y535100D03*
X534534Y534700D03*
X528155D03*
X485037Y572900D03*
Y550914D03*
X495077Y555957D03*
X497723Y572500D03*
Y550914D03*
X495077Y566699D03*
X518502Y555957D03*
X521848Y572900D03*
Y550914D03*
X518502Y566699D03*
X488384Y555957D03*
X491344Y572500D03*
X491430Y550914D03*
X488384Y566699D03*
X511809Y555957D03*
X515155Y572900D03*
Y550914D03*
X511809Y566699D03*
X531888Y555957D03*
X534534Y572500D03*
Y550914D03*
X531888Y566699D03*
X525195Y555957D03*
X528155Y572500D03*
X528241Y550914D03*
X525195Y566699D03*
X485037Y588714D03*
X497723D03*
X521848D03*
X491430D03*
X515155D03*
X534534D03*
X528241D03*
X485037Y610700D03*
X495077Y593757D03*
X498092Y611200D03*
X495077Y604499D03*
X521848Y610700D03*
X518502Y593757D03*
Y604499D03*
X488384Y593757D03*
X491724Y611668D03*
X488384Y604499D03*
X515155Y610700D03*
X511809Y593757D03*
Y604499D03*
X534534Y610300D03*
X531888Y593757D03*
Y604499D03*
X528155Y610300D03*
X525195Y593757D03*
Y604499D03*
X558659Y34100D03*
X555313Y27899D03*
X551966Y34100D03*
X548620Y27899D03*
X571345Y33700D03*
X568699Y27899D03*
X595470Y34100D03*
X592124Y27899D03*
X564966Y33700D03*
X562006Y27899D03*
X588777Y34100D03*
X585431Y27899D03*
X558659Y-3700D03*
X555313Y17157D03*
Y-9901D03*
X558659Y12114D03*
X551966Y-3700D03*
X548620Y17157D03*
Y-9901D03*
X551966Y12114D03*
X571345Y-4100D03*
X568699Y17157D03*
Y-9901D03*
X571345Y12114D03*
X595470Y-3700D03*
X592124Y17157D03*
Y-9901D03*
X595470Y12114D03*
X564966Y-4100D03*
X561868Y17019D03*
X562006Y-9901D03*
X565052Y12114D03*
X588777Y-3700D03*
X585431Y17157D03*
Y-9901D03*
X588777Y12114D03*
X598817Y17057D03*
X602163Y9157D03*
Y-1743D03*
Y36057D03*
Y27899D03*
X605510D03*
Y-9901D03*
Y16999D03*
Y-1743D03*
Y9157D03*
Y36057D03*
X558659Y71900D03*
X555313Y92757D03*
Y65699D03*
X558659Y87714D03*
X551966Y71900D03*
X548620Y92757D03*
Y65699D03*
X551966Y87714D03*
X571345Y71500D03*
X568699Y92757D03*
Y65699D03*
X571345Y87714D03*
X595470Y71900D03*
X592124Y92757D03*
Y65699D03*
X595470Y87714D03*
X564966Y71500D03*
X562006Y92757D03*
Y65699D03*
X565266Y87374D03*
X588777Y71900D03*
X585431Y92757D03*
Y65699D03*
X588777Y87714D03*
X555313Y54957D03*
X558659Y49914D03*
X548620Y54957D03*
X551966Y49914D03*
X568699Y54957D03*
X571345Y49914D03*
X592124Y54957D03*
X595470Y49914D03*
X562006Y54957D03*
X565052Y49914D03*
X585431Y54957D03*
X588777Y49914D03*
X598817Y92657D03*
X602163Y84757D03*
Y54799D03*
Y46957D03*
X598817Y54857D03*
X602163Y73857D03*
X605510Y92599D03*
Y65699D03*
Y54799D03*
Y46957D03*
Y84757D03*
Y73857D03*
X603163Y103971D03*
X555313Y112357D03*
X558659Y107314D03*
X548620Y112357D03*
X551966Y107314D03*
X605028Y119000D03*
X604977Y110200D03*
X558911Y218147D03*
X555531Y220096D03*
X548771D03*
X545391Y218147D03*
Y214247D03*
X552151Y222047D03*
X548771Y216196D03*
X603273Y198896D03*
X600286Y202921D03*
X599773Y199596D03*
X592300Y220500D03*
X552151Y237647D03*
X555531Y231797D03*
X548771Y227896D03*
X552151Y245447D03*
X548771Y251296D03*
X545391Y237647D03*
X548771Y282496D03*
Y270796D03*
Y262996D03*
X545391Y276646D03*
Y245447D03*
Y253247D03*
X548771Y259096D03*
X545391Y241547D03*
X548771Y247396D03*
X545391Y249347D03*
Y257147D03*
Y261047D03*
Y229847D03*
X548771Y231797D03*
X562616Y223996D03*
X555531Y259096D03*
Y266896D03*
X558911Y268847D03*
X552151D03*
Y276646D03*
X555531Y278596D03*
Y282496D03*
X562640Y231735D03*
X555531Y243496D03*
X552151Y253247D03*
X558911Y249347D03*
Y257147D03*
Y225947D03*
X555531Y262996D03*
X552151Y264947D03*
X555531Y270796D03*
X552151Y272747D03*
X548771Y274696D03*
X552151Y280547D03*
X562630Y227896D03*
X558911Y241547D03*
X555531Y251296D03*
X558911Y253247D03*
X555531Y255196D03*
Y227896D03*
Y223996D03*
X548771D03*
Y321496D03*
X545391Y323446D03*
X548771Y337096D03*
X545391Y342947D03*
X548771Y329296D03*
X552151Y331247D03*
Y335147D03*
Y342947D03*
X548771Y344896D03*
Y333196D03*
X552151Y339047D03*
X555531Y340996D03*
X548771Y290296D03*
Y294196D03*
X545391Y284447D03*
X560884Y290296D03*
X555831Y294196D03*
X552151Y292245D03*
X545391Y327347D03*
Y311747D03*
Y339047D03*
X552151Y319547D03*
Y315647D03*
Y311747D03*
X548771Y305896D03*
X552151Y300047D03*
X548771Y301996D03*
X562591Y340996D03*
X558911Y339047D03*
X559211Y331103D03*
X555531Y329296D03*
X559211Y323446D03*
X555531Y321496D03*
X548771Y317596D03*
X555831Y313696D03*
X552151Y307847D03*
Y303947D03*
X555831Y301996D03*
X548771Y298096D03*
X555531Y344896D03*
X562591Y337096D03*
X555531D03*
X559211Y327347D03*
X552151D03*
X555531Y325396D03*
X555831Y317446D03*
X559212Y385847D03*
X552151Y346847D03*
Y393647D03*
X545391Y389747D03*
X548771Y387796D03*
X545391Y393647D03*
X552151Y385847D03*
X559212Y389747D03*
X555531Y352696D03*
Y348796D03*
X552151Y354647D03*
X558911Y350747D03*
X545391Y378047D03*
X552151Y374146D03*
X545391D03*
X548771Y364396D03*
Y360496D03*
Y356596D03*
Y383896D03*
Y376096D03*
Y372196D03*
X545391Y370247D03*
Y362447D03*
X552151Y358547D03*
X548771Y352696D03*
X545391Y381947D03*
X548771Y379996D03*
X559211Y366347D03*
X552151D03*
Y370247D03*
X555531Y379996D03*
X552151Y381947D03*
X558911Y354647D03*
X563500Y360500D03*
X552151Y362447D03*
X555531Y372197D03*
X548990Y403670D03*
X555750Y399770D03*
X545391Y350747D03*
X548771Y348796D03*
X562591D03*
X592216Y445152D03*
X595070Y447970D03*
X555313Y518157D03*
X558659Y513114D03*
X555313Y528899D03*
X548620Y518157D03*
Y528899D03*
X551966Y513114D03*
X568699Y518157D03*
X571345Y513114D03*
X568699Y528899D03*
X592124Y518157D03*
X595470Y513114D03*
X592124Y528899D03*
X562006Y518157D03*
Y528899D03*
X565266Y512774D03*
X585431Y518157D03*
X588777Y513114D03*
X585431Y528899D03*
X554792Y498487D03*
X558659Y496144D03*
X548492Y498400D03*
X551366Y493344D03*
X602163Y510157D03*
X598817Y518057D03*
X605510Y528899D03*
Y517999D03*
Y510157D03*
X558659Y535100D03*
X551966D03*
X571345Y534700D03*
X595470Y535100D03*
X564966Y534700D03*
X588777Y535100D03*
X555313Y555957D03*
X558659Y572900D03*
Y550914D03*
X555313Y566699D03*
X548620Y555957D03*
X551966Y572900D03*
Y550914D03*
X548620Y566699D03*
X568699Y555957D03*
X571345Y572500D03*
Y550914D03*
X568699Y566699D03*
X592124Y555957D03*
X595470Y572900D03*
Y550914D03*
X592124Y566699D03*
X562006Y555957D03*
X564966Y572500D03*
X565266Y550574D03*
X562006Y566699D03*
X585431Y555957D03*
X588777Y572900D03*
Y550914D03*
X585431Y566699D03*
X558659Y588714D03*
X551966D03*
X571345D03*
X595470D03*
X565052D03*
X588777D03*
X602163Y574857D03*
Y566699D03*
Y555799D03*
X598817Y555857D03*
X602163Y547957D03*
Y537057D03*
Y585757D03*
X605510Y555799D03*
Y566699D03*
Y585757D03*
Y547957D03*
Y574857D03*
Y537057D03*
X558659Y610700D03*
X555313Y593757D03*
Y604499D03*
X551966Y610700D03*
X548620Y593757D03*
Y604499D03*
X571345Y610300D03*
X568699Y593757D03*
Y604499D03*
X592124Y593757D03*
X595470Y610700D03*
X592124Y604499D03*
X564966Y610300D03*
X562006Y593757D03*
Y604499D03*
X585431Y593757D03*
X588777Y610700D03*
X585431Y604499D03*
X598817Y593657D03*
X602163Y612657D03*
X605510Y604499D03*
Y593599D03*
Y612657D03*
X661494Y32946D03*
X657250Y-2050D03*
X608856Y16999D03*
X612203D03*
Y9157D03*
X608856D03*
X615549D03*
X608856Y-9901D03*
X612203D03*
X608856Y-1743D03*
X612203D03*
X615549D03*
Y36057D03*
X608856D03*
X612203D03*
Y27899D03*
X608856D03*
X659747Y-12132D03*
X615549Y27899D03*
Y-9901D03*
Y16999D03*
X659700Y22900D03*
X665396Y23000D03*
X615549Y84757D03*
X608856D03*
X612203D03*
X608856Y92599D03*
X612203D03*
X608856Y46957D03*
X612203D03*
X608856Y54799D03*
X615549Y46957D03*
X612203Y54799D03*
X608856Y65699D03*
X612203D03*
X615549Y73857D03*
X608856D03*
X612203D03*
X652718Y93881D03*
X664471Y86061D03*
X662352Y89566D03*
X615549Y92599D03*
Y65699D03*
Y54799D03*
X626040Y98281D03*
X608600Y103000D03*
X613602Y118047D03*
Y109247D03*
X633800Y119000D03*
X658055Y141493D03*
X647555Y143643D03*
X651055Y142893D03*
X654555Y142193D03*
X642673Y139811D03*
X644055Y144493D03*
X635673Y141318D03*
X639173Y140618D03*
X632173Y142018D03*
X628673Y142718D03*
X609482Y124568D03*
X618800Y100100D03*
X644750Y175650D03*
X660600Y170000D03*
Y175000D03*
X611148Y206994D03*
X618648Y219494D03*
Y214494D03*
X608648Y204494D03*
X613648D03*
X610273Y197496D03*
X613773Y196796D03*
X613082Y200676D03*
X609860Y201356D03*
X654950Y253446D03*
X627529Y280441D03*
X618279Y251393D03*
X624500Y240500D03*
X639320Y268000D03*
X643500Y274868D03*
X633410Y269610D03*
Y274610D03*
X651235Y249165D03*
X641665Y281139D03*
X643100Y253700D03*
X649800Y252600D03*
X656100Y275500D03*
X606148Y229494D03*
X617235Y247735D03*
X614456Y244956D03*
X637681Y337390D03*
X628525Y287832D03*
X631250Y289650D03*
X639622Y290210D03*
X643823Y289650D03*
X658500Y284500D03*
X632869Y293720D03*
X648900Y336600D03*
X646520Y297400D03*
X664267Y292668D03*
X637143Y322000D03*
X637561Y312000D03*
Y317000D03*
X637600Y302000D03*
Y307000D03*
X646700Y308850D03*
X658900Y339150D03*
X628950Y293550D03*
X654600Y296000D03*
X662238Y296146D03*
X659694Y351206D03*
X664194D03*
X649194D03*
X654194D03*
X649600Y391200D03*
X640300Y437600D03*
X608800Y463475D03*
Y468475D03*
X609191Y451454D03*
X615300Y457900D03*
X641150Y484300D03*
X653800Y496600D03*
X618430Y491550D03*
X623400Y476300D03*
X629300Y490000D03*
X648500Y477400D03*
X662640Y528330D03*
X608856Y517999D03*
X612203D03*
Y528899D03*
X608856D03*
X615549Y510157D03*
X608856D03*
X612203D03*
X612515Y498752D03*
X609284Y480055D03*
X636500Y493924D03*
X627000Y478300D03*
X611250Y476750D03*
X618800Y474500D03*
X615549Y517999D03*
Y528899D03*
X639120Y475620D03*
X658900Y509300D03*
X639197Y490367D03*
X623600Y521700D03*
X608856Y574857D03*
X612203D03*
X615549D03*
X612203Y566699D03*
X608856D03*
Y555799D03*
X612203D03*
Y547957D03*
X615549D03*
X608856D03*
Y537057D03*
X615549D03*
X612203D03*
X615549Y585757D03*
X612203D03*
X608856D03*
X660217Y576734D03*
X615549Y555799D03*
Y566699D03*
X662000Y589000D03*
X608856Y593599D03*
X612203D03*
X608856Y604499D03*
X612203D03*
X608856Y612657D03*
X615549D03*
X612203D03*
X615549Y604499D03*
Y593599D03*
X665000Y598500D03*
X631741Y615759D03*
X723715Y23462D03*
X692500Y15300D03*
X708000Y26600D03*
X700500D03*
X724837Y13852D03*
X714300Y-1900D03*
X680200Y13100D03*
X675235Y36797D03*
X719400Y14300D03*
X679936Y18406D03*
X670227Y34277D03*
X670400Y26100D03*
X701100Y8100D03*
X704450Y4950D03*
X720572Y88700D03*
X715130Y79574D03*
X697200Y79500D03*
X697100Y90600D03*
X670795Y89189D03*
X716894Y84047D03*
X701500Y85500D03*
X694600Y85000D03*
X698300Y85300D03*
X709560Y84648D03*
X689500Y37900D03*
X685000Y46650D03*
X670503Y115884D03*
X670600Y144900D03*
Y150000D03*
X705292Y195729D03*
X701956Y195294D03*
X701129Y192106D03*
X709341Y190507D03*
X725725Y241560D03*
X697255Y267098D03*
X710500Y224500D03*
X700400Y257200D03*
X710272Y281911D03*
X706800Y281900D03*
X704500Y252500D03*
X700800Y261300D03*
X690130Y277380D03*
X715200Y258900D03*
X704090Y256080D03*
X689960Y260500D03*
X700000Y233700D03*
X710900Y231660D03*
X677800Y254100D03*
X667700Y275600D03*
X710700Y260200D03*
X710675Y263425D03*
X679300Y261700D03*
X712400Y324400D03*
X711900Y327700D03*
X697120Y305349D03*
Y300349D03*
X704404Y315875D03*
Y310875D03*
X697521Y325500D03*
Y320500D03*
X724000Y291700D03*
X686140Y298260D03*
X695000Y289500D03*
X686600Y335600D03*
X670800Y292600D03*
X667900Y339000D03*
X697352Y335500D03*
Y330500D03*
X705800Y301600D03*
X674700Y339200D03*
X688100Y308600D03*
X688924Y288147D03*
X674469Y287375D03*
X674194Y358467D03*
X683417Y364972D03*
X686619Y392600D03*
X683100Y392200D03*
X691240Y390039D03*
X687427Y384926D03*
X676900Y381800D03*
X669194Y351206D03*
X674194D03*
X679194D03*
X684194D03*
X695700Y346300D03*
X680370Y427770D03*
X680200Y432100D03*
X687400Y411200D03*
X674300Y489500D03*
X679700Y489400D03*
X718546Y500283D03*
X696000Y496800D03*
X669300Y504000D03*
X708500Y512500D03*
X680000Y511800D03*
X686200Y511700D03*
X700500Y512850D03*
X690500Y523300D03*
X675500Y521900D03*
X721894Y501346D03*
X726040Y506080D03*
X696600Y581400D03*
X722200Y571300D03*
X718200Y581000D03*
X680029Y577503D03*
X680910Y582000D03*
X693200Y575900D03*
X717612Y598554D03*
X722406Y598950D03*
X756176Y-4300D03*
X782567Y33700D03*
X779921Y27899D03*
X776188Y33700D03*
X773228Y27899D03*
X782567Y-4100D03*
X779921Y17157D03*
X782567Y12114D03*
X779921Y-9901D03*
X776188Y-4100D03*
X773228Y17157D03*
X776274Y12114D03*
X773228Y-9901D03*
X729500Y23500D03*
X764100Y17100D03*
X760100Y17255D03*
X769881Y9157D03*
X763500Y23940D03*
X765900Y35800D03*
X765400Y-9800D03*
X766300Y-1800D03*
X729600Y17991D03*
X734256D03*
X755000Y17255D03*
X753100Y92111D03*
X782567Y71500D03*
X779921Y92757D03*
Y65699D03*
X782567Y87714D03*
X776188Y71500D03*
X773228Y92757D03*
Y65699D03*
X776274Y87714D03*
X779921Y54957D03*
X782567Y49914D03*
X773228Y54957D03*
X776274Y49914D03*
X764100Y55100D03*
X751600Y41000D03*
X755500Y55200D03*
X769881Y46957D03*
X763500Y59700D03*
X766500Y102900D03*
X752900Y101000D03*
X769044Y191348D03*
X770300Y204930D03*
X771232Y214033D03*
X749126Y220843D03*
X761580Y220160D03*
X748700Y257500D03*
X771650Y246451D03*
Y278451D03*
X759700Y232000D03*
X739400Y253400D03*
X739500Y247500D03*
X731662Y247716D03*
X730000Y254675D03*
X737750Y298894D03*
X771600Y310600D03*
X771700Y342501D03*
X729405Y290725D03*
X737912Y315500D03*
X741512Y315538D03*
X736000Y303400D03*
X757956Y328095D03*
X741250Y298856D03*
X743600Y304100D03*
X771400Y374400D03*
X760500Y359800D03*
X765007Y348363D03*
X732000Y380000D03*
X739933Y447401D03*
X756000Y525950D03*
X779921Y518157D03*
Y528899D03*
X782567Y513114D03*
X773228Y518157D03*
Y528899D03*
X776274Y513114D03*
X743483Y492937D03*
X764400Y528600D03*
X738648Y492050D03*
X763544Y522236D03*
X769500Y510100D03*
X766535Y517900D03*
X763706Y514250D03*
X782567Y534700D03*
X776188D03*
X779921Y555957D03*
X782567Y572500D03*
Y550914D03*
X779921Y566699D03*
X773228Y555957D03*
X776188Y572500D03*
X776274Y550914D03*
X773228Y566699D03*
X782567Y588714D03*
X776274D03*
X763300Y566000D03*
X769500Y536983D03*
X755000Y566000D03*
X769500Y547900D03*
Y574700D03*
Y585700D03*
X764117Y575658D03*
X765100Y537110D03*
X766535Y555700D03*
X732600Y573950D03*
X763450Y585200D03*
X765900Y587300D03*
X782567Y610300D03*
X779921Y593757D03*
Y604499D03*
X776188Y610300D03*
X773228Y593757D03*
Y604499D03*
X764400Y604600D03*
X739307Y598850D03*
X755800Y604600D03*
X769500Y612583D03*
X766535Y593500D03*
X733032Y604000D03*
X843503Y34100D03*
X840157Y27899D03*
X812999Y33700D03*
X810039Y27899D03*
X836810Y34100D03*
X833464Y27899D03*
X849810Y33700D03*
X846850Y27899D03*
X806692Y34100D03*
X803346Y27899D03*
X799999Y34100D03*
X796653Y27899D03*
X819378Y33700D03*
X816732Y27899D03*
X843503Y-3700D03*
X840157Y17157D03*
Y-9901D03*
X843503Y12114D03*
X812999Y-4100D03*
X810039Y17157D03*
Y-9901D03*
X813085Y12114D03*
X833464Y17157D03*
X836810Y-3700D03*
X833464Y-9901D03*
X836810Y12114D03*
X849810Y-4100D03*
X846850Y17157D03*
Y-9901D03*
X849896Y12114D03*
X806692Y-3700D03*
X803346Y17157D03*
Y-9901D03*
X806692Y12114D03*
X799999Y-3700D03*
X796653Y17157D03*
Y-9901D03*
X799999Y12114D03*
X816732Y17157D03*
X819378Y-4100D03*
Y12114D03*
X816732Y-9901D03*
X843503Y71900D03*
X840157Y92757D03*
Y65699D03*
X843503Y87714D03*
X812999Y71500D03*
X810039Y92757D03*
Y65699D03*
X813085Y87714D03*
X836810Y71900D03*
X833464Y92757D03*
Y65699D03*
X836810Y87714D03*
X849810Y71500D03*
X846850Y92757D03*
Y65699D03*
X849896Y87714D03*
X806692Y71900D03*
X803346Y92757D03*
Y65699D03*
X806692Y87714D03*
X799999Y71900D03*
X796653Y92757D03*
Y65699D03*
X799999Y87714D03*
X816732Y92757D03*
X819378Y71500D03*
X816732Y65699D03*
X819378Y87714D03*
X840157Y54957D03*
X843503Y49914D03*
X810039Y54957D03*
X813085Y49914D03*
X833464Y54957D03*
X836810Y49914D03*
X846850Y54957D03*
X849896Y49914D03*
X803346Y54957D03*
X806692Y49914D03*
X796653Y54957D03*
X799999Y49914D03*
X816732Y54957D03*
X819378Y49914D03*
X798337Y181216D03*
X799300Y195600D03*
X813700D03*
Y198900D03*
X799620Y186547D03*
X804470Y186814D03*
X824000Y402863D03*
X797000Y404700D03*
X851430Y367468D03*
X805600Y403900D03*
X840871Y391380D03*
X837272Y391420D03*
X827800Y402863D03*
X832300D03*
X805367Y407400D03*
X797780Y423484D03*
X840157Y518157D03*
Y528899D03*
X843503Y513114D03*
X810039Y518157D03*
X813085Y513114D03*
X810039Y528899D03*
X833464Y518157D03*
Y528899D03*
X836810Y513114D03*
X846850Y518157D03*
X849896Y513114D03*
X846850Y528899D03*
X803346Y518157D03*
X806692Y513114D03*
X803346Y528899D03*
X796653Y518157D03*
X799999Y513114D03*
X796653Y528899D03*
X816732Y518157D03*
Y528899D03*
X819378Y513114D03*
X843503Y535100D03*
X812999Y534700D03*
X836810Y535100D03*
X849810Y534700D03*
X806692Y535100D03*
X799999D03*
X819378Y534700D03*
X840157Y555957D03*
X843503Y572900D03*
Y550914D03*
X840157Y566699D03*
X810039Y555957D03*
X812999Y572500D03*
X813085Y550914D03*
X810039Y566699D03*
X833464Y555957D03*
X836810Y572900D03*
Y550914D03*
X833464Y566699D03*
X846850Y555957D03*
X849810Y572500D03*
X849896Y550914D03*
X846850Y566699D03*
X803346Y555957D03*
X806692Y572900D03*
Y550914D03*
X803346Y566699D03*
X796653Y555957D03*
X799999Y572900D03*
Y550914D03*
X796653Y566699D03*
X816732Y555957D03*
X819378Y572500D03*
X816732Y566699D03*
X819378Y550914D03*
X843503Y588714D03*
X813085D03*
X836810D03*
X849896D03*
X806692D03*
X799999D03*
X819378D03*
X840157Y593757D03*
X843503Y610700D03*
X840157Y604499D03*
X812999Y610300D03*
X810039Y593757D03*
Y604499D03*
X833464Y593757D03*
X836810Y610700D03*
X833464Y604499D03*
X846850Y593757D03*
X849810Y610300D03*
X846850Y604499D03*
X806692Y610700D03*
X803346Y593757D03*
Y604499D03*
X799999Y610700D03*
X796653Y593757D03*
Y604499D03*
X816732Y593757D03*
X819378Y610300D03*
X816732Y604499D03*
X856189Y33700D03*
X853543Y27899D03*
X880314Y34100D03*
X876968Y27899D03*
X873621Y34100D03*
X870275Y27899D03*
X893000Y33700D03*
X890354Y27899D03*
X913779D03*
X886621Y33700D03*
X883661Y27899D03*
X910432Y34100D03*
X907086Y27899D03*
X856189Y-4100D03*
X853543Y17157D03*
Y-9901D03*
X856189Y12114D03*
X880314Y-3700D03*
X876968Y17157D03*
Y-9901D03*
X880314Y12114D03*
X873621Y-3700D03*
X870275Y17157D03*
Y-9901D03*
X873621Y12114D03*
X893000Y-4100D03*
X890354Y17157D03*
X893000Y12114D03*
X890354Y-9901D03*
X913779Y17157D03*
Y-9901D03*
X883661Y17157D03*
X886621Y-4100D03*
X886707Y12114D03*
X883661Y-9901D03*
X907086Y17157D03*
X910432Y-3700D03*
X907086Y-9901D03*
X910432Y12114D03*
X856189Y71500D03*
X853543Y92757D03*
Y65699D03*
X856189Y87714D03*
X876968Y92757D03*
X880314Y71900D03*
X876968Y65699D03*
X880314Y87714D03*
X873621Y71900D03*
X870275Y92761D03*
Y65699D03*
X873621Y87714D03*
X893000Y71500D03*
X890354Y92757D03*
X893000Y87714D03*
X890354Y65699D03*
X913779Y92757D03*
Y65699D03*
X886621Y71500D03*
X883661Y92757D03*
X886707Y87714D03*
X883661Y65699D03*
X910432Y71900D03*
X907086Y92757D03*
X910432Y87714D03*
X907086Y65699D03*
X853543Y54957D03*
X856189Y49914D03*
X876968Y54957D03*
X880314Y49914D03*
X870275Y54957D03*
X873621Y49914D03*
X890354Y54957D03*
X893000Y49914D03*
X913779Y54957D03*
X883661D03*
X886707Y49914D03*
X907086Y54957D03*
X910432Y49914D03*
X890354Y112327D03*
X893000Y106934D03*
X913779Y112327D03*
X883661D03*
X886707Y107284D03*
X907086Y112327D03*
X910432Y107284D03*
X913787Y257860D03*
X913700Y242260D03*
X913787Y261760D03*
Y246160D03*
Y273460D03*
Y335860D03*
Y331960D03*
X882008Y321100D03*
X913787Y351460D03*
Y347560D03*
X853543Y518157D03*
Y528899D03*
X856189Y513114D03*
X876968Y518157D03*
Y528899D03*
X880314Y513114D03*
X870275Y518161D03*
Y528899D03*
X873621Y513114D03*
X890354Y518157D03*
Y528899D03*
X893000Y513114D03*
X913779Y518157D03*
Y528899D03*
X883661Y518157D03*
Y528899D03*
X886707Y513114D03*
X907086Y518157D03*
Y528899D03*
X910432Y513114D03*
X889200Y495900D03*
X893000Y495694D03*
X913779Y498487D03*
X882900Y498500D03*
X886500Y490800D03*
X907086Y498487D03*
X910432Y493744D03*
X856189Y534700D03*
X880314Y535100D03*
X873621D03*
X893000Y534700D03*
X886621D03*
X910432Y535100D03*
X853543Y555957D03*
X856189Y572500D03*
Y550914D03*
X853543Y566699D03*
X876968Y555957D03*
X880314Y572900D03*
X876968Y566699D03*
X880314Y550914D03*
X870275Y555961D03*
X873621Y572900D03*
Y550914D03*
X870275Y566699D03*
X893000Y572500D03*
X890354Y555957D03*
X893000Y550914D03*
X890354Y566699D03*
X913779Y555957D03*
Y566699D03*
X886621Y572500D03*
X883661Y555957D03*
X886707Y550914D03*
X883661Y566699D03*
X910432Y572900D03*
X907086Y555957D03*
X910432Y550914D03*
X907086Y566699D03*
X856189Y588714D03*
X880314D03*
X873621D03*
X893000D03*
X886707D03*
X910432D03*
X853543Y593757D03*
X856189Y610300D03*
X853543Y604499D03*
X876968Y593757D03*
X880314Y610700D03*
X876968Y604499D03*
X870275Y593761D03*
X873621Y610700D03*
X870275Y604499D03*
X893000Y610300D03*
X890354Y593757D03*
Y604499D03*
X913779Y593757D03*
Y604499D03*
X886621Y610300D03*
X883661Y593757D03*
Y604499D03*
X907086Y593757D03*
X910432Y610700D03*
X907086Y604499D03*
X957765Y-7180D03*
X957283Y28014D03*
Y17057D03*
X970669Y28014D03*
X974015D03*
Y35957D03*
X963976Y28014D03*
X960629Y35957D03*
X917125Y34100D03*
X929811Y33700D03*
X927165Y27899D03*
X953936Y34100D03*
X950590Y27899D03*
X923432Y33700D03*
X920472Y27899D03*
X947243Y34100D03*
X943897Y27899D03*
X970669Y-7108D03*
Y17057D03*
X974015D03*
Y-9901D03*
Y9114D03*
Y-4536D03*
X963976Y-7108D03*
X960629Y-4536D03*
X963976Y17057D03*
X960629Y9114D03*
X917125Y-3700D03*
Y12114D03*
X929811Y-4100D03*
X927165Y17157D03*
Y-9901D03*
X929811Y12114D03*
X953936Y-3700D03*
X950590Y17157D03*
Y-9901D03*
X953936Y12114D03*
X923432Y-4100D03*
X920472Y17157D03*
Y-9901D03*
X923518Y12114D03*
X947243Y-3700D03*
X943897Y17157D03*
Y-9901D03*
X947243Y12114D03*
X960629Y-9786D03*
X963976Y-1843D03*
X970669Y-1743D03*
X967322Y-9786D03*
X963976Y9114D03*
X970669D03*
Y35957D03*
X967322Y28014D03*
X960629Y17057D03*
X963976Y35957D03*
X960629Y28014D03*
X967322Y17057D03*
Y35957D03*
Y-4536D03*
Y9114D03*
X957536Y67802D03*
X957283Y54857D03*
Y92657D03*
X963976Y65814D03*
Y92657D03*
X960629Y84714D03*
X917125Y71900D03*
Y87714D03*
X929811Y71500D03*
X927165Y92757D03*
Y65699D03*
X929811Y87714D03*
X953936Y71900D03*
X950590Y92757D03*
Y65699D03*
X953936Y87714D03*
X923432Y71500D03*
X920472Y92757D03*
Y65699D03*
X923518Y87714D03*
X947243Y71900D03*
X943897Y92757D03*
Y65699D03*
X947243Y87714D03*
X970669Y54857D03*
X974015D03*
Y46914D03*
X963976Y54857D03*
X960629Y46914D03*
X917125Y49914D03*
X927165Y54957D03*
X929811Y49914D03*
X950590Y54957D03*
X953936Y49914D03*
X920472Y54957D03*
X923518Y49914D03*
X943897Y54957D03*
X947243Y49914D03*
X960629Y65814D03*
X970669Y46914D03*
X967322Y54857D03*
X963976Y46914D03*
X960629Y54857D03*
Y89964D03*
X967322Y46914D03*
X917125Y107284D03*
X927165Y112327D03*
X929811Y106934D03*
X950590Y109700D03*
X953786Y107684D03*
X920472Y112327D03*
X923518Y107284D03*
X944497Y110927D03*
X947243Y105084D03*
X963245Y105725D03*
X924227Y205210D03*
X920847Y207159D03*
X927607Y218860D03*
X930987Y216909D03*
X934367Y218860D03*
X947887Y214960D03*
X958026Y216909D03*
Y220809D03*
X944507Y216909D03*
Y220809D03*
X954647Y214960D03*
X951267Y213009D03*
X937747Y220809D03*
X951267Y216909D03*
Y220809D03*
X934367Y203260D03*
Y211060D03*
X944507Y205210D03*
Y209109D03*
X930987Y205210D03*
Y209109D03*
X941127Y203260D03*
Y211060D03*
X937747Y201309D03*
Y213009D03*
Y205210D03*
Y209109D03*
X917467D03*
X927607Y199360D03*
X924227Y201309D03*
X944507Y197409D03*
X924227Y209109D03*
X920847Y203260D03*
X930987Y228610D03*
X937747Y224709D03*
X920847Y257860D03*
X934367Y230559D03*
X937747Y228610D03*
X927607Y222760D03*
X947887D03*
X954647D03*
X920847Y242260D03*
Y261760D03*
Y246160D03*
Y250060D03*
X927607Y226660D03*
X951267Y224709D03*
X920847Y253960D03*
X917467Y248109D03*
X930987Y224709D03*
X934367Y222760D03*
X917467Y255909D03*
X974926Y238360D03*
Y246160D03*
X971546Y240309D03*
Y244209D03*
X930987Y267609D03*
X927607Y238360D03*
X930987Y236409D03*
X934367Y250060D03*
X937747Y248109D03*
X927607Y242260D03*
X934367Y238360D03*
X937747Y263709D03*
X927607Y257860D03*
X930987Y255909D03*
X934367Y269560D03*
X937747Y267609D03*
X927607Y261760D03*
X934367Y257860D03*
X930987Y248109D03*
X937747Y244209D03*
Y259809D03*
X927607Y246160D03*
X937747Y240309D03*
X927607Y265660D03*
X934367Y261760D03*
X930987Y244209D03*
X934367Y242260D03*
X930987Y263709D03*
X947887Y261760D03*
X944507Y232509D03*
X947887Y230559D03*
X951267Y244209D03*
X954647Y242260D03*
X944507Y236409D03*
X951267Y232509D03*
X961406Y230559D03*
X968166Y234460D03*
Y222760D03*
X971546Y224709D03*
X954647Y257860D03*
X961406Y234460D03*
X964786Y236409D03*
Y224709D03*
X971546Y228610D03*
X974926Y257860D03*
Y261760D03*
X944507Y252009D03*
X947887Y250060D03*
X951267Y263709D03*
X954647Y261760D03*
X944507Y255909D03*
X951267Y252009D03*
X947887Y242260D03*
X954647Y238360D03*
Y253960D03*
X944507Y240309D03*
X961406Y226660D03*
X964786Y263709D03*
X954647Y234460D03*
X971546Y232509D03*
X964786Y275409D03*
X944507Y259809D03*
X951267Y255909D03*
X947887Y238360D03*
X964786Y228610D03*
Y267609D03*
X951267Y236409D03*
X968166Y230559D03*
X964786Y271509D03*
X947887Y257860D03*
X961406Y265660D03*
Y273460D03*
X971546Y267609D03*
Y271509D03*
X958026Y267609D03*
Y271509D03*
X968166Y265660D03*
Y273460D03*
X937747Y279310D03*
X917000Y276000D03*
X920847Y277360D03*
X924227Y279310D03*
Y283209D03*
X927607Y281260D03*
X920847D03*
X916967Y279310D03*
X934367Y281260D03*
X930987Y279310D03*
Y283209D03*
X937747D03*
X944507D03*
Y279310D03*
X958026D03*
X954647Y281260D03*
X958026Y283209D03*
X951267Y279310D03*
Y283209D03*
X961406Y281260D03*
X941127D03*
X947887D03*
X917467Y271509D03*
X961406Y242260D03*
X964786Y244209D03*
X961406Y246160D03*
X964786Y248109D03*
X958026D03*
X968166Y250060D03*
X971546Y252009D03*
X944507Y267609D03*
X947887Y269560D03*
X951267Y271509D03*
X947887Y273460D03*
X941127D03*
X927607D03*
X974926Y277360D03*
X971546Y279310D03*
X944507Y271509D03*
X924227D03*
X920847Y335860D03*
Y331960D03*
Y343660D03*
Y339760D03*
X917467Y345609D03*
Y337809D03*
X937747Y333909D03*
X930987Y330009D03*
Y341709D03*
X927607Y339760D03*
X937747Y330009D03*
X934367Y328060D03*
Y339760D03*
X927607Y335860D03*
Y331960D03*
X934367Y335860D03*
X930987Y333909D03*
X937747Y337809D03*
X954647Y339760D03*
X947887Y335860D03*
X954647D03*
X951267Y333909D03*
X944507Y341709D03*
Y337809D03*
X968166Y328060D03*
Y335860D03*
X951267Y341709D03*
X947887Y339760D03*
X968166Y324160D03*
Y331960D03*
X954647Y343660D03*
X964786Y326110D03*
Y333909D03*
X974926Y328060D03*
Y331960D03*
X961406Y328060D03*
Y331960D03*
X971546Y326110D03*
Y333909D03*
X937747Y287109D03*
X920500Y304660D03*
Y300760D03*
X930987Y302709D03*
X924227D03*
X920500Y311960D03*
X927607Y304660D03*
X924227Y306609D03*
X930987D03*
Y310509D03*
X934367Y304660D03*
X924227Y310509D03*
X920500Y308560D03*
Y289060D03*
X934367Y296860D03*
X930987Y294909D03*
X920500Y296860D03*
Y292959D03*
X927607Y296860D03*
X924227Y298809D03*
X930987D03*
X920500Y285500D03*
X924227Y287109D03*
X930987D03*
X934367Y289060D03*
X924227Y291009D03*
X930987D03*
X927607Y289060D03*
X937747Y302709D03*
Y306609D03*
Y310509D03*
Y291009D03*
Y294909D03*
Y298809D03*
Y314409D03*
X924227D03*
X930987D03*
X934367Y312460D03*
X927607D03*
X920847Y324160D03*
X924227Y318309D03*
X920547Y316160D03*
X917167Y318309D03*
Y322209D03*
X917467Y326110D03*
X920847Y320260D03*
X971546Y294909D03*
X964786Y291009D03*
X951267Y287109D03*
X958026D03*
X961406Y296860D03*
X964786Y298809D03*
Y302709D03*
X971546D03*
X961406Y304660D03*
X958026Y302709D03*
X951267D03*
X968166Y308560D03*
X964786Y306609D03*
X968166Y304660D03*
X971546Y306609D03*
X974926Y304660D03*
Y308560D03*
X951267Y310509D03*
X954647Y304660D03*
X958026Y306609D03*
Y310509D03*
X951267Y306609D03*
X944507Y302709D03*
Y306609D03*
Y310509D03*
X941127Y304660D03*
X947887D03*
X944507Y294909D03*
Y287109D03*
X971546Y298809D03*
X974926Y285160D03*
Y296860D03*
Y289060D03*
X968166Y285160D03*
X964786Y287109D03*
X944507Y291009D03*
X941127Y289060D03*
Y296860D03*
X944507Y298809D03*
X947887Y289060D03*
Y296860D03*
X968166D03*
X964786Y294909D03*
X971546Y291009D03*
Y287109D03*
X968166Y289060D03*
X961406D03*
X958026Y298809D03*
X951267D03*
Y291009D03*
X958026D03*
X954647Y289060D03*
Y296860D03*
X958026Y294909D03*
X951267D03*
X944507Y314409D03*
X951267D03*
X958026D03*
X961406Y312460D03*
X954647D03*
X941127D03*
X947887D03*
X951267Y326110D03*
X958026Y322209D03*
X954647Y320260D03*
X961406D03*
X954647Y324160D03*
X951267Y322209D03*
X964786Y318309D03*
X971546D03*
X974926Y320260D03*
X968166Y316360D03*
X974926D03*
X971546Y314409D03*
X947887Y324160D03*
Y320260D03*
X941127D03*
X934367D03*
X937747Y322209D03*
X930987D03*
X941127Y324160D03*
X927607D03*
X944507Y326110D03*
Y330009D03*
X971546Y341709D03*
Y345609D03*
X937747Y372909D03*
X930987Y369010D03*
Y380709D03*
X927607Y378760D03*
X937747Y369010D03*
X934367Y367060D03*
Y378760D03*
X927607Y374860D03*
X947887D03*
Y382660D03*
X958026Y376809D03*
Y380709D03*
X944507Y376809D03*
Y380709D03*
X954647Y374860D03*
Y382660D03*
X920847Y351460D03*
Y347560D03*
X934367Y374860D03*
X951267Y376809D03*
X927607Y370959D03*
X951267Y384609D03*
X937747Y376809D03*
X951267Y372909D03*
X930987D03*
X951267Y380709D03*
X974926Y351460D03*
Y359260D03*
X971546Y353409D03*
Y357309D03*
X934367Y359260D03*
X930987Y361209D03*
X937747Y349509D03*
X934367Y347560D03*
X927607Y355360D03*
Y359260D03*
X934367Y386560D03*
Y394359D03*
X944507Y388509D03*
Y392410D03*
X930987Y388509D03*
Y392410D03*
X941127Y386560D03*
Y394359D03*
X937747Y353409D03*
X930987Y349509D03*
X934367Y355360D03*
X937747Y388509D03*
X927607Y351460D03*
X937747Y396309D03*
Y357309D03*
Y384609D03*
X930987Y353409D03*
X937747Y392410D03*
X951267Y365109D03*
X947887Y367060D03*
X954647Y355360D03*
X951267Y353409D03*
X944507Y361209D03*
Y365109D03*
X968166Y363160D03*
X961406Y367060D03*
X971546Y372909D03*
X968166Y374860D03*
X964786Y361209D03*
X961406Y363160D03*
X971546Y369010D03*
X964786Y372909D03*
X947887Y347560D03*
X944507Y345609D03*
X951267D03*
X954647Y359260D03*
X947887Y355360D03*
X951267Y361209D03*
X968166Y367060D03*
X944507Y357309D03*
X961406Y370959D03*
X954647Y363160D03*
X971546Y365109D03*
X947887Y359260D03*
X964786Y369010D03*
Y349509D03*
Y353409D03*
X961406Y355360D03*
Y347560D03*
Y351460D03*
X924227Y400209D03*
X930987D03*
X920847Y394359D03*
X917467Y392410D03*
X944507Y400209D03*
X964786Y384609D03*
Y380709D03*
X920847Y398260D03*
X927607D03*
X958026Y349509D03*
X924227Y396309D03*
X957283Y518057D03*
X960629Y510114D03*
X917125Y513114D03*
X927165Y518157D03*
Y528899D03*
X929811Y513114D03*
X950590Y518157D03*
Y528899D03*
X953936Y513114D03*
X920472Y518157D03*
Y528899D03*
X923518Y513114D03*
X943897Y518157D03*
Y528899D03*
X947243Y513114D03*
X917192Y493919D03*
X927165Y498644D03*
X929811Y493244D03*
X950700Y493300D03*
X954000Y494700D03*
X920700Y498644D03*
X923600Y493744D03*
X944000Y493100D03*
X947443Y494944D03*
X960629Y515364D03*
X961309Y499136D03*
X957283Y555857D03*
X960629Y536957D03*
X917125Y535100D03*
X929811Y534700D03*
X953936Y535100D03*
X923432Y534700D03*
X947243Y535100D03*
X970669Y555857D03*
Y566814D03*
X974015Y555857D03*
Y566814D03*
Y547914D03*
Y574757D03*
X963976Y566814D03*
X960629Y574757D03*
X963976Y555857D03*
X960629Y547914D03*
X917125Y572900D03*
Y550914D03*
X929811Y572500D03*
X927165Y555957D03*
Y566699D03*
X929811Y550914D03*
X953936Y572900D03*
X950590Y555957D03*
X953936Y550914D03*
X950590Y566699D03*
X923432Y572500D03*
X920472Y555957D03*
Y566699D03*
X923518Y550914D03*
X947243Y572900D03*
X943897Y555957D03*
X947243Y550914D03*
X943897Y566699D03*
X974015Y585714D03*
X960629D03*
X917125Y588714D03*
X929811D03*
X953936D03*
X923518D03*
X947243D03*
X963976Y536957D03*
Y547914D03*
X970669D03*
X967322Y555857D03*
X960629D03*
X970669Y585714D03*
Y574757D03*
X963976Y585714D03*
Y574757D03*
X967322Y566814D03*
Y574757D03*
Y547914D03*
Y585714D03*
X957765Y607220D03*
X957283Y593657D03*
X970669D03*
Y607292D03*
X974015Y593657D03*
Y604499D03*
Y609864D03*
X963976Y607292D03*
X960629Y609864D03*
X963976Y593657D03*
X917125Y610700D03*
X929811Y610300D03*
X927165Y593757D03*
Y604499D03*
X953936Y610700D03*
X950590Y593757D03*
Y604499D03*
X923432Y610300D03*
X920472Y593757D03*
Y604499D03*
X947243Y610700D03*
X943897Y593757D03*
Y604499D03*
X967322Y593657D03*
X963976Y612457D03*
X970669D03*
X960629Y604614D03*
X967322D03*
X960629Y593657D03*
X967322Y609864D03*
X1026700Y1700D03*
X977362Y35957D03*
X1014173Y28014D03*
Y35942D03*
X1010826Y28014D03*
X984055Y35957D03*
X980708Y28014D03*
X1004133Y28022D03*
X1004134Y35957D03*
X1000787Y28022D03*
X997441Y35957D03*
X994094D03*
Y28022D03*
X987401Y35957D03*
X990748Y28022D03*
X984054Y28014D03*
X977362Y-1743D03*
Y9114D03*
X1014173Y-9786D03*
Y-1858D03*
Y9114D03*
X1010826Y-9786D03*
Y-1858D03*
Y9114D03*
X984055Y-1743D03*
X984054Y9114D03*
X980708Y-9786D03*
Y17057D03*
X1004134Y-7108D03*
Y17057D03*
X1004133Y-1742D03*
X1000787Y-9901D03*
Y17057D03*
X997441Y-1743D03*
Y9122D03*
X994094Y-4536D03*
Y9122D03*
Y-9786D03*
Y17057D03*
X987401Y9114D03*
Y-4536D03*
X990748Y-7108D03*
Y17057D03*
X984055Y-7108D03*
Y17057D03*
X980708Y-4536D03*
X987401Y-9901D03*
X997441Y-7108D03*
X990748Y-1743D03*
X977362Y-7108D03*
X980708Y9114D03*
X990748Y9122D03*
X977362Y28014D03*
X987401D03*
Y17057D03*
X977362D03*
X990748Y35957D03*
X980708D03*
X997441Y28022D03*
Y17057D03*
X1000787Y-4536D03*
Y9122D03*
X1017519Y-1858D03*
Y-9786D03*
X1007480Y-1858D03*
X1017519Y9114D03*
X1007480Y-9786D03*
X1000787Y35957D03*
X1007480Y17014D03*
Y28014D03*
X1017519D03*
Y35942D03*
X1025670Y6640D03*
X1020866Y-1858D03*
X1027202Y-11005D03*
X1028639Y-6615D03*
X977362Y46914D03*
X1014173Y54842D03*
X984054Y46914D03*
X980708Y54857D03*
X1004134D03*
X1004133Y46922D03*
X1000787Y54857D03*
X997441Y46922D03*
X994094D03*
Y54857D03*
X987401Y46914D03*
X990748Y54857D03*
X984055D03*
X987401D03*
X977362D03*
X990748Y46922D03*
X980708Y46914D03*
X997441Y54857D03*
X1000787Y46922D03*
X1017519Y54842D03*
X1007480Y46914D03*
X1016600Y65950D03*
X1035000Y81200D03*
X1017350Y73450D03*
X1030300Y63200D03*
X1022245Y207159D03*
X991826Y205210D03*
X1022245Y211060D03*
X995206Y207159D03*
X991826Y209109D03*
X998586Y205210D03*
X1018865Y213009D03*
X998586Y216909D03*
X1001965Y218860D03*
X995206D03*
X991826Y213009D03*
X988446Y214960D03*
X1025625Y216909D03*
X1015485Y218860D03*
X1022245D03*
X1012105Y216909D03*
X1032385Y213009D03*
X1035765Y211060D03*
X1029005Y207159D03*
X1018865Y216909D03*
X1032385D03*
X1029005Y218860D03*
X1008725Y211060D03*
X1012105Y213009D03*
X1008725Y218860D03*
X1005345Y216909D03*
Y213009D03*
X1035765Y218860D03*
X1025625Y213009D03*
X995206Y203260D03*
X988446Y218860D03*
X995206Y214960D03*
X1001965D03*
X1035765D03*
X1027875Y193507D03*
X1032385Y201309D03*
X1015485Y203260D03*
Y214960D03*
X1022245D03*
X1012105Y205210D03*
X1025625Y205211D03*
X1029005Y214960D03*
X1035765Y207159D03*
X1007595Y193507D03*
X1005345Y205210D03*
X1008725Y214960D03*
X991826Y216909D03*
X985066Y220809D03*
X988446Y207158D03*
Y203258D03*
X995206Y211060D03*
X998586Y213009D03*
X988446Y250060D03*
Y230560D03*
X978306Y236409D03*
Y248109D03*
Y240309D03*
Y244209D03*
X985066Y240309D03*
Y244209D03*
X981686Y238360D03*
Y246160D03*
X991826Y224709D03*
X995206Y230559D03*
X1025625Y224709D03*
X988446Y222760D03*
X1022245D03*
X1015485D03*
X1018865Y224709D03*
X1012105D03*
X1035765Y222760D03*
X1001965D03*
X998586Y224709D03*
X1032385D03*
X1029005Y222760D03*
X1008725D03*
X1005345Y224709D03*
X998586Y228610D03*
X1001965Y230559D03*
X998586Y236409D03*
Y240309D03*
X1029005Y230559D03*
X1015485Y242260D03*
X1001965Y234460D03*
X995206Y242260D03*
Y234460D03*
X991826Y240309D03*
Y228610D03*
Y236409D03*
X1022245Y234460D03*
X1015485D03*
X1022245Y230559D03*
X1015485D03*
X1018865Y236409D03*
X1012105D03*
X1018865Y228610D03*
X1012105D03*
X1032385D03*
Y236409D03*
X978306Y255909D03*
Y263709D03*
X988446Y257860D03*
Y261760D03*
X985066Y255909D03*
Y263709D03*
X981686Y253960D03*
Y265660D03*
Y257860D03*
Y261760D03*
X1025625Y236409D03*
X1018865Y240309D03*
X1001965Y246160D03*
X995206D03*
X1025625Y240309D03*
X1035765Y230559D03*
X1022245Y242260D03*
X1029005Y234460D03*
X1008725Y242260D03*
X1012105Y240309D03*
X1008725Y230559D03*
Y234460D03*
X1005345Y228610D03*
Y236409D03*
X1001965Y242260D03*
X1005345Y240309D03*
X1008725Y246160D03*
X1035765Y234460D03*
X1025625Y228610D03*
X995206Y277360D03*
Y281260D03*
X998586Y267609D03*
Y271509D03*
Y275409D03*
Y279310D03*
Y283209D03*
X1022245Y253960D03*
X1025625Y252009D03*
X1017735Y264300D03*
X1014355Y266300D03*
X1021115Y262300D03*
X1024495Y260300D03*
X1027875Y258400D03*
X1031255Y256400D03*
X1034635Y254259D03*
X1005345Y263709D03*
X1001965Y265660D03*
X1008725Y261760D03*
X1006665Y277360D03*
Y281260D03*
X1015485Y257860D03*
X1018865Y255909D03*
X1012105Y259809D03*
X998586Y244209D03*
Y232509D03*
X991826Y244209D03*
Y232509D03*
X995206Y226660D03*
X1032385Y232509D03*
X1035765Y226660D03*
X1018865Y244209D03*
X1012105D03*
X1018865Y232509D03*
X1015485Y226660D03*
X1022245D03*
X1012105Y232509D03*
X1025625D03*
X1029005Y226660D03*
X1005345Y244209D03*
X1008725Y226660D03*
X1005345Y232509D03*
X1001965Y226660D03*
X995206Y222760D03*
X981686D03*
X978306Y224709D03*
X981686Y226660D03*
X985066Y228610D03*
X978306D03*
X981686Y230559D03*
X985066Y232509D03*
X1012105Y248109D03*
X1008725Y250060D03*
X1001965D03*
X995206D03*
X1005345Y252009D03*
X998586D03*
X1008725Y253960D03*
X1001965D03*
X995206D03*
X1005345Y255909D03*
X998586D03*
X1001965Y257860D03*
X995206D03*
X998586Y259809D03*
X995206Y261760D03*
X988446Y269560D03*
X985066Y271509D03*
X978306D03*
X988446Y273460D03*
X981686D03*
X985066Y275409D03*
X978306D03*
X988446Y277360D03*
X981686D03*
X985066Y279310D03*
X978306D03*
X1032385Y240309D03*
X1035765Y242260D03*
X1029005D03*
X1032385Y244209D03*
X1025625D03*
X1035765Y246160D03*
X1029005D03*
X1022245D03*
X1015485D03*
X1018865Y248109D03*
X1015485Y250060D03*
X1012105Y252009D03*
X991826D03*
Y248109D03*
X998586Y337809D03*
X981686Y335860D03*
Y343660D03*
X991826Y337809D03*
Y341709D03*
X978306Y337809D03*
Y341709D03*
X988446Y335860D03*
Y343660D03*
X985066Y337809D03*
Y333909D03*
Y341709D03*
X995206Y296860D03*
X985066Y294909D03*
Y287109D03*
X988446Y285160D03*
X991826Y287109D03*
X978306Y298809D03*
Y287109D03*
X981686Y285160D03*
X978306Y294909D03*
X981686Y296860D03*
Y289060D03*
X978306Y291009D03*
X998586Y302709D03*
Y306609D03*
Y310509D03*
Y287109D03*
Y294909D03*
Y291009D03*
Y298809D03*
X985066Y302709D03*
X978306D03*
X988446Y304660D03*
Y308560D03*
X985066Y306609D03*
X995206Y304660D03*
Y308560D03*
X991826Y306609D03*
X978306D03*
X981686Y308560D03*
Y304660D03*
X995206Y300760D03*
X991826Y302709D03*
X995206Y292959D03*
X988446Y296860D03*
X991826Y294909D03*
X995206Y289060D03*
X988446D03*
X991826Y291009D03*
X985066D03*
X995206Y285160D03*
X985066Y298809D03*
X991826D03*
X998586Y314409D03*
X995206Y312460D03*
X998586Y318309D03*
Y322209D03*
Y326110D03*
Y330009D03*
X995206Y316360D03*
X1006665Y300760D03*
Y304660D03*
Y308560D03*
Y285160D03*
Y296860D03*
Y289060D03*
Y292959D03*
X1008725Y335860D03*
X1005345Y333909D03*
X1001965Y331960D03*
X1007595Y327609D03*
X1021115Y335409D03*
X1018865Y341709D03*
X1017735Y333460D03*
X1015485Y339760D03*
X1024495Y337360D03*
X1012105Y337809D03*
X1006665Y312460D03*
X1014355Y331509D03*
X1010975Y329560D03*
X1027875Y339309D03*
X1034635Y343209D03*
X1031255Y341260D03*
X1006665Y324160D03*
Y316360D03*
Y320260D03*
X1022245Y343660D03*
X981686Y324160D03*
X988446Y320260D03*
X985066Y322209D03*
Y318309D03*
X988446Y324160D03*
Y328060D03*
X981686D03*
X985066Y326110D03*
X981686Y320260D03*
X978306Y322209D03*
Y318309D03*
X981686Y316360D03*
X978306Y314409D03*
X985066D03*
X998586Y341709D03*
Y345609D03*
X1001965Y343660D03*
Y339760D03*
X1008725Y343660D03*
X1012105Y345609D03*
X1005345Y341709D03*
X991826Y384609D03*
X991500Y396301D03*
X1022245Y390460D03*
X995206Y386560D03*
X978306Y353409D03*
Y361209D03*
Y349509D03*
Y357309D03*
X985066Y353409D03*
Y357309D03*
X981686Y351460D03*
Y359260D03*
X1022245Y386560D03*
X998586Y388509D03*
X991826Y380709D03*
X1000800Y402800D03*
X995206Y378760D03*
X998586Y380709D03*
X1025625Y372909D03*
X1018865Y384609D03*
X995206Y367060D03*
X998586Y372909D03*
X991826D03*
X988446Y374860D03*
Y370959D03*
Y378760D03*
X1018865Y372909D03*
X1012105D03*
X1022245Y378760D03*
X1012105Y380709D03*
X1022245Y374860D03*
X1015485D03*
X1025625Y380709D03*
X1015485Y378760D03*
X1032385Y384609D03*
X1035765Y374860D03*
Y386560D03*
X1029005D03*
X1018865Y380709D03*
X1001965Y378760D03*
Y374860D03*
X1032385Y380709D03*
Y372909D03*
X1029005Y378760D03*
Y374860D03*
X1008725Y386560D03*
X1012105Y384609D03*
X1008725Y378760D03*
X1005345Y380709D03*
X1008725Y374860D03*
X1005345Y372909D03*
X998586Y369010D03*
X1001965Y367060D03*
X1005345Y384609D03*
X1035765Y378760D03*
X1025625Y384609D03*
X995206Y355360D03*
X998586Y357309D03*
X1029005Y367060D03*
X1015485Y355360D03*
X995206Y351460D03*
X998586Y361209D03*
X995206Y363160D03*
X991826Y357309D03*
Y369010D03*
Y361209D03*
X1018865Y369010D03*
X1012105D03*
X1018865Y361209D03*
X1012105D03*
X1022245Y367060D03*
X1015485D03*
X1022245Y363160D03*
X1015485D03*
X1032385Y369010D03*
Y361209D03*
X985066Y345609D03*
X1025625Y361209D03*
X1018865Y357309D03*
X1001965Y351460D03*
Y363160D03*
X1025625Y357309D03*
X1035765Y367060D03*
X1022245Y355360D03*
X1029005Y363160D03*
X1008725Y355360D03*
X1012105Y357309D03*
X1008725Y363160D03*
Y367060D03*
X1005345Y361209D03*
Y369010D03*
X1001965Y355360D03*
X1005345Y357309D03*
X1008725Y351460D03*
X1035765Y363160D03*
X1025625Y369010D03*
X988446Y367060D03*
X998586Y365109D03*
Y353409D03*
X991826Y365109D03*
X995206Y370959D03*
X991826Y353409D03*
X998586Y392410D03*
X988446Y382660D03*
X995206D03*
X1005345Y365109D03*
X1008725Y370959D03*
X1001965D03*
X1005345Y353409D03*
X1018865Y365109D03*
X1012105D03*
X1025625D03*
X1022245Y370959D03*
X1015485D03*
X1018865Y353409D03*
X1012105D03*
X1025625D03*
X1029005Y370959D03*
X1035765D03*
X1032385Y365109D03*
X1007595Y402800D03*
X1008725Y382660D03*
X1001965D03*
X1005345Y392410D03*
X1029005Y390460D03*
X1025625Y392410D03*
X1022245Y382660D03*
X1015485D03*
X1012105Y392410D03*
X1018865D03*
X1029005Y382660D03*
X1035765D03*
X1027875Y402800D03*
X1005345Y345609D03*
X1018865Y349509D03*
X1032385Y353409D03*
X1035765Y355360D03*
X998586Y384609D03*
X985066Y376809D03*
X981686Y374860D03*
X995206D03*
X978306Y372909D03*
X981686Y370959D03*
X978306Y369010D03*
X985066D03*
X981686Y367060D03*
X985066Y365109D03*
X988446Y363160D03*
X1032385Y357309D03*
X1029005Y355360D03*
X1015485Y351460D03*
X1022245D03*
X1029005D03*
X991826Y349509D03*
X1012105D03*
X1025625D03*
X995206Y347560D03*
X1001965D03*
X1015485D03*
X1008725D03*
X1017519Y529057D03*
X1035000Y521556D03*
X977362Y547914D03*
Y574757D03*
X1010826Y566814D03*
X1010928Y555842D03*
X1010826Y574742D03*
X984054Y547914D03*
X984055Y574757D03*
X980708Y555857D03*
Y566814D03*
X1004134Y555857D03*
X1004133Y566822D03*
X1004134Y574757D03*
X1000787Y555857D03*
Y566822D03*
X997441Y547922D03*
Y574757D03*
X994094Y547922D03*
Y574757D03*
Y555857D03*
Y566822D03*
X987401Y547914D03*
Y574757D03*
X990748Y555857D03*
Y566822D03*
X984055Y555857D03*
X984054Y566814D03*
X977362Y585714D03*
X984054D03*
X997441Y585722D03*
X994094D03*
X987401Y585714D03*
X990748Y547922D03*
X980708Y547914D03*
X977362Y555857D03*
X987401D03*
X997441D03*
X977362Y566814D03*
X990748Y574757D03*
Y585722D03*
X980708Y585714D03*
Y574757D03*
X997441Y566822D03*
X987401Y566814D03*
X1000787Y547922D03*
X1017300Y536200D03*
Y547914D03*
X1019277Y585714D03*
X1000787Y585722D03*
Y574757D03*
X1007518Y555842D03*
Y566814D03*
X1007480Y574742D03*
X1026500Y581000D03*
X1026400Y543700D03*
X977362Y612457D03*
X1014173Y604614D03*
X1010826D03*
X1011572Y593642D03*
X1010826Y612242D03*
X984055Y612457D03*
X980708Y604614D03*
Y593657D03*
X1004134Y607292D03*
X1004133Y612358D03*
X1000787Y604499D03*
Y593657D03*
X997441Y612357D03*
X994094Y609864D03*
Y593657D03*
Y604614D03*
X987401Y609864D03*
X990748Y593657D03*
Y607292D03*
X984055D03*
Y593657D03*
X977362D03*
X987401D03*
X997441D03*
Y607292D03*
X977362D03*
X990748Y612457D03*
X980708Y609864D03*
X987401Y604499D03*
X1007480Y612242D03*
X1000787Y609864D03*
X1007480Y604614D03*
X1029777Y613581D03*
X1020800Y612600D03*
X1071062Y-1817D03*
X1071064Y9122D03*
X1054331Y28022D03*
X1050985Y35957D03*
X1087797D03*
X1064371Y28022D03*
X1081102Y28007D03*
X1094488Y28022D03*
X1094490Y35957D03*
X1047637Y28007D03*
X1054331Y35957D03*
X1077757D03*
X1064371D03*
X1071064Y28022D03*
X1057677Y28007D03*
X1084450Y35957D03*
X1074409Y28007D03*
X1087797Y28022D03*
X1044292Y35957D03*
X1054330Y-9901D03*
X1054331Y17057D03*
X1050985Y9122D03*
X1050983Y-1743D03*
X1087797Y9122D03*
X1087795Y-4536D03*
X1064369Y-7108D03*
X1081102Y-9901D03*
X1094488Y-9786D03*
Y-4536D03*
X1064371Y17057D03*
X1081102Y17042D03*
X1094488Y17059D03*
Y9122D03*
X1047637Y-9901D03*
X1054331Y9122D03*
X1054330Y-4536D03*
X1077757Y9122D03*
X1077755Y-1743D03*
X1064371Y9122D03*
X1064369Y-1743D03*
X1071062Y-7108D03*
X1071064Y17057D03*
X1057677Y17042D03*
X1057676Y-7108D03*
X1084450Y9122D03*
X1084448Y-1743D03*
X1074409Y-9786D03*
X1087795D03*
X1074409Y17042D03*
X1087795Y17059D03*
X1044290Y11792D03*
X1044291Y-2200D03*
X1047637Y-4536D03*
X1057676Y-1743D03*
X1047637Y9107D03*
X1057677D03*
X1050983Y-7108D03*
X1050985Y28022D03*
X1047637Y35942D03*
X1050984Y17042D03*
X1057677Y35942D03*
X1061023Y-9786D03*
X1067716Y-4536D03*
Y-9901D03*
X1081102Y-4536D03*
X1074409D03*
X1084448Y-7108D03*
X1077755D03*
X1091141Y-1843D03*
X1067716Y9107D03*
X1091141D03*
X1074409D03*
X1081102D03*
X1071064Y35957D03*
X1061024Y17057D03*
Y28022D03*
X1067716Y35942D03*
Y28007D03*
Y17042D03*
X1091141Y35942D03*
Y17042D03*
X1081102Y35942D03*
X1077757Y28022D03*
X1074409Y35942D03*
X1084450Y28098D03*
Y17057D03*
X1077757D03*
X1091141Y28007D03*
X1097834Y11100D03*
X1061024Y35957D03*
X1061023Y-4536D03*
X1061024Y9122D03*
X1044100Y54700D03*
X1071064Y46922D03*
X1054331Y54857D03*
X1050985Y46922D03*
X1087797D03*
X1064371Y54857D03*
X1081102Y54842D03*
X1094488Y54859D03*
Y46922D03*
X1047637Y54842D03*
X1054331Y46922D03*
X1077757D03*
X1064371D03*
X1071064Y54857D03*
X1057677Y54842D03*
X1084450Y46922D03*
X1074409Y54842D03*
X1087795Y54859D03*
X1044290Y49592D03*
X1050984Y54842D03*
X1047637Y46907D03*
X1057677D03*
X1061024Y54857D03*
X1067716Y54842D03*
Y46907D03*
X1091141Y54842D03*
X1084450Y54857D03*
X1077757D03*
X1081102Y46907D03*
X1074409D03*
X1091141D03*
X1061024Y46922D03*
X1044290Y68964D03*
X1049284Y207159D03*
X1085721Y220096D03*
X1095861Y222047D03*
X1082341D03*
X1092481Y220096D03*
X1089101Y218147D03*
Y222047D03*
X1042524Y211060D03*
X1039145Y213009D03*
X1045904D03*
Y216909D03*
X1049284Y218860D03*
X1057314Y216909D03*
X1065242Y220096D03*
Y216196D03*
X1075582Y222047D03*
X1072202Y220096D03*
X1068822Y218147D03*
Y222047D03*
X1042524Y218860D03*
X1039145Y216909D03*
X1042524Y214960D03*
X1042506Y195041D03*
X1045904Y197359D03*
X1054000Y199100D03*
X1042524Y203260D03*
X1049284Y214960D03*
Y203260D03*
Y211060D03*
X1065242Y239596D03*
Y243496D03*
X1068822Y245447D03*
X1045904Y244209D03*
Y240309D03*
X1085721Y227896D03*
X1095861Y225947D03*
X1082341D03*
X1092481Y227896D03*
X1089101Y229847D03*
Y225947D03*
X1045904Y228610D03*
X1039145Y224709D03*
X1049284Y222760D03*
X1075582Y225947D03*
X1065242Y227896D03*
Y231797D03*
X1072202Y227896D03*
X1068822Y225947D03*
Y229847D03*
X1042524Y222760D03*
X1045904Y224709D03*
X1057314Y236409D03*
X1039145D03*
X1049284Y230559D03*
Y234460D03*
X1042524Y230559D03*
X1057314Y224709D03*
Y228610D03*
X1075582Y233746D03*
Y241547D03*
X1085721Y235696D03*
Y239596D03*
X1072202Y235696D03*
Y239596D03*
X1082341Y233746D03*
Y241547D03*
X1095861Y233746D03*
Y241547D03*
X1092481Y235696D03*
Y239596D03*
X1078962Y231797D03*
X1099241D03*
X1078962Y243496D03*
X1099241D03*
X1078962Y235696D03*
X1099241D03*
X1078962Y239596D03*
X1099241D03*
X1049284Y238360D03*
X1042524Y234460D03*
X1039145Y228610D03*
X1045904Y236409D03*
X1038015Y256500D03*
X1041395Y254259D03*
X1048154D03*
X1051534Y256500D03*
X1044774Y256400D03*
X1054914Y254500D03*
X1067692Y254000D03*
X1071072Y255728D03*
X1087971Y257800D03*
X1091351Y259600D03*
X1094731Y261500D03*
X1098111Y263400D03*
X1084591Y255497D03*
X1081212Y257600D03*
X1092481Y247396D03*
X1089101Y245447D03*
X1085721Y247396D03*
X1089101Y249347D03*
X1092481Y251296D03*
X1095861Y249347D03*
Y253247D03*
X1042524Y226660D03*
X1039145Y232509D03*
X1057314Y240309D03*
X1049284Y226660D03*
X1045904Y232509D03*
X1057314D03*
X1072202Y247396D03*
X1079859Y265000D03*
X1049284Y242260D03*
X1039145Y240309D03*
X1042524Y242260D03*
X1039145Y244209D03*
X1042524Y246160D03*
X1057314Y244209D03*
X1049284Y246160D03*
X1038015Y345160D03*
X1044774D03*
X1051534D03*
X1098111Y344597D03*
X1044256Y338341D03*
X1076435Y343595D03*
X1042524Y355360D03*
X1045904Y357309D03*
X1039145D03*
X1045904Y384609D03*
X1093601Y381947D03*
Y389747D03*
X1090221Y383896D03*
Y387796D03*
X1096981Y383896D03*
Y391696D03*
Y379996D03*
Y387796D03*
X1042524Y386560D03*
X1039145Y384609D03*
X1049284Y390460D03*
X1045904Y380709D03*
X1049284Y378760D03*
X1045904Y369010D03*
X1039145Y372909D03*
X1052664Y380709D03*
X1049284Y374860D03*
X1073322Y389747D03*
Y393647D03*
X1083462Y383896D03*
Y387796D03*
X1073322Y378047D03*
Y381947D03*
X1080082D03*
Y389747D03*
X1076702Y383896D03*
Y391696D03*
Y379996D03*
Y387796D03*
X1042524Y378760D03*
Y374860D03*
X1039145Y380709D03*
X1045904Y372909D03*
X1052664Y361209D03*
X1039145D03*
X1049284Y367060D03*
Y363160D03*
X1042524Y367060D03*
X1052664Y372909D03*
Y369010D03*
X1076702Y364396D03*
X1073322Y370247D03*
X1086841Y366347D03*
Y370247D03*
X1073322Y358547D03*
Y366347D03*
X1083462Y364396D03*
Y372197D03*
X1093601Y354647D03*
Y362447D03*
X1090221Y356596D03*
Y360496D03*
X1080082Y366347D03*
X1096981Y356596D03*
X1080082Y370247D03*
X1096981Y364396D03*
X1080082Y362447D03*
X1096981Y352696D03*
X1080082Y374146D03*
X1096981Y360496D03*
X1049284Y359260D03*
X1042524Y363160D03*
X1039145Y369010D03*
X1045904Y361209D03*
X1041395Y347109D03*
X1048154D03*
X1071072Y348497D03*
X1087971Y346546D03*
X1074452D03*
X1081212D03*
X1077832Y348497D03*
X1084591D03*
X1052664Y357309D03*
X1049284Y370959D03*
X1042524D03*
X1045904Y365109D03*
X1039145D03*
X1052664D03*
Y392410D03*
X1040265Y394359D03*
X1049284Y382660D03*
X1042524D03*
Y390460D03*
X1056176Y402471D03*
X1041395Y402800D03*
X1061039Y359351D03*
X1060963Y370959D03*
X1060694Y355360D03*
X1061055Y363160D03*
X1052664Y353409D03*
X1064371Y367060D03*
X1052664Y396309D03*
X1060694Y394359D03*
Y390460D03*
X1049284Y386560D03*
X1060694D03*
Y382660D03*
Y378760D03*
X1048154Y402900D03*
X1086841Y378047D03*
X1090221Y376096D03*
X1093601Y374146D03*
Y370247D03*
X1049284Y355360D03*
X1080082Y358547D03*
X1083462Y356596D03*
X1052500Y400400D03*
X1071064Y547922D03*
Y585722D03*
X1054331Y555857D03*
Y566822D03*
X1050984Y547922D03*
X1050985Y574757D03*
X1087797Y547922D03*
Y574757D03*
X1064371Y566822D03*
X1081102Y566807D03*
X1094488Y566822D03*
X1094490Y574757D03*
X1064371Y555857D03*
X1081102Y555842D03*
X1094488Y555859D03*
Y547922D03*
X1047637Y555842D03*
Y566807D03*
X1054331Y547922D03*
Y574757D03*
X1077757Y547922D03*
Y574757D03*
X1064371Y547922D03*
Y574757D03*
X1071064Y555857D03*
Y566822D03*
X1057677Y555842D03*
Y566807D03*
X1084450Y547922D03*
Y574757D03*
X1074409Y566807D03*
X1087797Y566822D03*
X1074409Y555842D03*
X1087795Y555859D03*
X1044290Y550592D03*
X1044292Y574757D03*
X1050985Y585722D03*
X1087797D03*
X1094488D03*
X1054331D03*
X1077757D03*
X1064371D03*
X1084450D03*
X1044290Y588392D03*
X1067716Y547907D03*
X1057677D03*
X1047637D03*
X1057677Y574742D03*
Y585707D03*
X1047637Y574742D03*
Y585707D03*
X1050985Y566822D03*
X1050984Y555842D03*
X1074409Y547907D03*
X1081102D03*
X1091141D03*
X1071064Y574757D03*
X1061024Y555857D03*
Y566822D03*
X1077757Y555857D03*
X1084450D03*
X1091141Y555842D03*
X1067716D03*
X1081102Y574742D03*
Y585707D03*
X1074409D03*
X1091141Y574742D03*
Y585707D03*
X1067716Y574742D03*
Y585599D03*
Y566807D03*
X1091141D03*
X1074409Y574742D03*
X1084450Y566822D03*
X1077757D03*
X1097343Y588394D03*
X1061024Y574757D03*
Y547922D03*
Y585722D03*
X1044290Y569492D03*
X1071062Y612560D03*
X1054331Y593657D03*
X1054330Y604499D03*
X1050984Y612658D03*
X1087795Y609864D03*
X1064369Y607292D03*
X1081102Y604499D03*
X1094488Y604614D03*
Y609864D03*
X1064371Y593657D03*
X1081102Y593642D03*
X1094488Y593659D03*
X1047637Y604499D03*
Y593642D03*
X1054330Y609864D03*
X1077755Y612657D03*
X1064369D03*
X1071064Y593657D03*
X1071062Y607292D03*
X1057677Y593642D03*
X1057676Y607292D03*
X1084448Y612657D03*
X1074409Y604614D03*
X1087795D03*
X1074409Y593642D03*
X1087795Y593659D03*
X1044291Y612658D03*
X1091141Y612557D03*
X1057676Y612657D03*
X1050984Y593642D03*
X1047637Y609864D03*
X1050983Y607292D03*
X1061024Y593657D03*
X1061023Y604614D03*
X1077757Y593657D03*
X1084450D03*
X1067716Y593642D03*
Y609864D03*
Y604499D03*
X1081102Y609864D03*
X1091141Y593642D03*
Y607292D03*
X1084448D03*
X1077755D03*
X1074409Y609864D03*
X1097374Y612659D03*
X1061023Y609864D03*
X1044290Y607292D03*
X1110520Y33700D03*
X1107874Y27899D03*
X1134645Y34100D03*
X1131299Y27899D03*
X1104141Y33700D03*
X1101181Y27899D03*
X1127952Y34100D03*
X1124606Y27899D03*
X1147331Y33700D03*
X1144685Y27899D03*
X1140952Y33700D03*
X1137992Y27899D03*
X1110520Y-4100D03*
X1107874Y17157D03*
Y-9901D03*
X1110520Y12114D03*
X1134645Y-3700D03*
X1131299Y17157D03*
Y-9901D03*
X1134645Y12114D03*
X1101181Y17157D03*
X1104141Y-4100D03*
X1104227Y12114D03*
X1101181Y-9901D03*
X1127952Y-3700D03*
X1124606Y17157D03*
Y-9901D03*
X1127952Y12114D03*
X1147331Y-4100D03*
X1144685Y17157D03*
Y-9901D03*
X1147331Y12114D03*
X1140952Y-4100D03*
X1137992Y17157D03*
Y-9901D03*
X1141038Y12114D03*
X1110520Y71500D03*
X1107874Y92757D03*
Y65699D03*
X1110520Y87714D03*
X1134645Y71900D03*
X1131299Y92757D03*
Y65699D03*
X1134645Y87714D03*
X1101181Y92757D03*
X1104141Y71500D03*
X1101181Y65699D03*
X1104227Y87714D03*
X1127952Y71900D03*
X1124606Y92757D03*
Y65699D03*
X1127952Y87714D03*
X1147331Y71500D03*
X1144685Y92757D03*
Y65699D03*
X1147331Y87714D03*
X1140952Y71500D03*
X1137992Y92757D03*
Y65699D03*
X1141038Y87714D03*
X1107874Y54957D03*
X1110520Y49914D03*
X1131299Y54957D03*
X1134645Y49914D03*
X1101181Y54957D03*
X1104227Y49564D03*
X1124606Y54957D03*
X1127952Y49914D03*
X1144685Y54957D03*
X1147331Y49914D03*
X1137992Y54957D03*
X1141038Y49914D03*
X1144535Y112357D03*
X1147331Y106964D03*
X1138242Y112357D03*
X1141038Y106964D03*
X1106001Y220096D03*
X1116141Y222047D03*
X1102621D03*
X1112761Y220096D03*
X1126280D03*
X1122900Y222047D03*
X1133040Y216196D03*
Y220096D03*
X1109381Y218147D03*
X1129660D03*
X1109381Y222047D03*
X1129660D03*
Y210346D03*
X1133040Y212296D03*
X1144300Y216196D03*
Y212296D03*
X1147680Y218147D03*
X1154440Y214247D03*
X1151060Y220096D03*
X1157820Y216196D03*
X1144300Y220096D03*
X1147680Y214247D03*
X1151060Y216196D03*
X1154440Y218147D03*
Y222047D03*
X1161200Y214247D03*
X1134160Y272747D03*
Y276646D03*
X1151060Y270796D03*
Y255196D03*
Y251296D03*
X1154440Y280547D03*
X1157820Y282496D03*
X1144300D03*
X1140920Y280547D03*
X1136420Y261047D03*
X1133040Y262996D03*
X1147680Y264947D03*
X1106001Y227896D03*
X1116141Y225947D03*
X1102621D03*
X1112761Y227896D03*
X1126280D03*
X1133040D03*
Y231797D03*
X1122900Y225947D03*
X1109381Y229847D03*
X1129660Y225947D03*
X1109381D03*
X1129660Y229847D03*
X1116141Y233746D03*
Y241547D03*
X1126280Y235696D03*
Y239596D03*
X1112761Y235696D03*
Y239596D03*
X1122900Y233746D03*
Y241547D03*
X1119521Y231797D03*
Y243496D03*
Y235696D03*
Y239596D03*
X1106001Y235696D03*
Y239596D03*
X1102621Y233746D03*
Y241547D03*
X1106001Y247396D03*
Y255196D03*
X1116141Y249347D03*
Y253247D03*
X1102621Y249347D03*
Y253247D03*
X1112761Y247396D03*
Y255196D03*
X1126280Y247396D03*
Y255196D03*
X1136420Y249347D03*
Y253247D03*
X1122900Y249347D03*
Y253247D03*
X1133040Y247396D03*
Y255196D03*
X1109381Y245447D03*
X1129660D03*
X1109381Y257147D03*
X1129660D03*
X1109381Y249347D03*
X1129660D03*
X1109381Y253247D03*
X1129660D03*
X1147680Y280547D03*
X1157820Y274696D03*
X1154440Y268847D03*
X1140920Y272747D03*
X1114340Y280560D03*
X1154440Y276647D03*
X1101491Y265400D03*
X1104871Y267300D03*
X1119521Y282496D03*
X1116141Y268847D03*
X1112761Y262996D03*
X1116141Y261047D03*
X1119521Y278596D03*
X1144300Y223996D03*
X1154440Y225947D03*
X1147680Y245447D03*
X1127400Y280547D03*
Y276646D03*
X1134160Y280547D03*
X1102336Y274819D03*
X1108125Y276799D03*
X1144300Y266896D03*
X1154440Y257147D03*
X1157820Y251296D03*
X1154440Y249347D03*
X1157820Y247396D03*
X1107600Y271900D03*
X1147680Y249347D03*
X1157820Y266896D03*
X1147680Y276647D03*
X1140920D03*
X1161200Y276646D03*
X1154440Y272747D03*
X1147680Y253247D03*
Y257147D03*
X1109381Y264947D03*
X1151060Y243496D03*
X1144300Y239596D03*
X1151060Y235696D03*
X1144300Y227896D03*
X1154440Y233746D03*
X1147680Y229847D03*
X1154440Y237647D03*
X1157820Y227896D03*
X1147680Y241547D03*
Y237647D03*
X1151060Y239596D03*
X1144300Y231797D03*
X1151060D03*
Y227896D03*
X1157820Y235696D03*
X1161200Y237647D03*
Y280547D03*
X1130780Y282496D03*
X1119521Y266896D03*
Y262996D03*
X1122900Y261047D03*
X1119521Y259096D03*
X1157820Y243496D03*
X1147680Y272747D03*
X1151060Y278596D03*
X1133040Y239596D03*
X1137540Y266896D03*
X1147680Y268847D03*
X1137540Y270796D03*
X1140920Y268847D03*
Y264947D03*
X1144300Y262996D03*
X1126280Y266896D03*
X1129660Y264947D03*
X1122900D03*
Y268847D03*
X1126280Y262996D03*
X1154440Y264947D03*
X1147680Y261047D03*
X1144300Y259096D03*
X1151060Y262996D03*
X1154440Y261047D03*
X1144300Y274696D03*
X1124021Y344896D03*
X1130780Y321496D03*
X1137540Y313696D03*
X1130780Y325396D03*
X1140920Y315647D03*
X1134160Y319547D03*
X1130780Y317596D03*
Y333196D03*
X1134160Y331247D03*
X1151060Y337096D03*
X1140920Y288347D03*
Y284447D03*
X1147680D03*
Y288347D03*
X1151060Y286396D03*
X1144300Y290296D03*
X1147680Y292247D03*
X1154440D03*
Y288347D03*
Y284447D03*
X1157820Y286396D03*
X1114839Y320075D03*
X1113132Y291702D03*
X1113500Y323400D03*
X1137540Y286396D03*
X1101491Y342646D03*
X1119521Y301996D03*
Y298096D03*
Y294196D03*
Y290296D03*
X1118391Y332897D03*
X1127400Y284447D03*
Y300047D03*
X1130780Y294196D03*
X1127400Y296147D03*
Y292247D03*
X1130780Y298096D03*
Y305896D03*
X1137540Y290296D03*
X1134160Y296147D03*
Y288347D03*
X1124021Y325396D03*
X1127400Y323446D03*
X1124021Y329296D03*
Y333196D03*
X1154440Y327347D03*
X1147680Y339047D03*
X1157820Y321496D03*
X1134160Y284447D03*
X1157820Y309797D03*
X1120641Y339047D03*
X1113881Y342947D03*
X1130780Y329296D03*
Y286396D03*
X1134160Y311747D03*
Y315647D03*
X1161200Y288347D03*
Y292247D03*
X1140920Y323446D03*
X1147680Y307847D03*
X1151060Y309797D03*
Y305896D03*
X1144300Y301996D03*
Y298096D03*
X1137540Y301996D03*
X1134160Y303947D03*
X1137540Y298096D03*
X1140920Y303947D03*
X1137540Y305896D03*
X1140920Y296147D03*
X1137540Y294196D03*
X1120641Y342947D03*
X1140920D03*
X1110501Y344896D03*
X1119521Y309797D03*
Y313696D03*
Y317596D03*
X1127400Y311747D03*
X1154440D03*
X1157820Y305896D03*
X1154440Y303947D03*
X1157820Y301996D03*
X1154440Y300047D03*
X1134160Y307847D03*
X1151060Y294196D03*
X1147680Y300047D03*
Y296147D03*
X1140920Y307847D03*
Y311747D03*
X1151060Y301996D03*
X1144300Y305896D03*
X1147680Y311747D03*
X1157820Y298096D03*
X1154440Y296147D03*
X1134160Y335147D03*
Y339047D03*
X1140920Y319547D03*
X1144300Y313696D03*
X1151060D03*
X1144300Y325396D03*
Y321496D03*
X1151060Y329296D03*
X1147680Y335147D03*
Y331247D03*
X1140920Y335147D03*
X1144300Y333196D03*
X1151060Y325396D03*
Y321496D03*
X1147680Y323446D03*
X1137540Y329296D03*
X1144300D03*
X1140920Y327347D03*
X1130780Y340996D03*
Y337096D03*
X1127400Y331247D03*
Y335147D03*
Y339047D03*
X1147680Y315647D03*
X1151060Y317596D03*
X1137540Y337096D03*
Y340996D03*
Y333196D03*
X1134160Y342947D03*
X1137540Y344896D03*
X1144300Y317596D03*
X1137540Y321496D03*
X1134160Y327347D03*
X1137540Y325396D03*
X1109200Y325100D03*
X1127400Y346847D03*
X1130780Y348796D03*
X1127400Y350747D03*
X1103741Y383896D03*
Y387796D03*
X1100361Y381947D03*
Y389747D03*
X1113881Y381947D03*
Y389747D03*
X1124021Y383896D03*
Y387796D03*
X1110501Y383896D03*
Y387796D03*
X1120641Y381947D03*
Y389747D03*
X1134160Y381947D03*
Y389747D03*
X1144300Y395597D03*
Y399496D03*
X1130780Y383896D03*
Y387796D03*
X1140920Y401447D03*
Y393647D03*
X1117261Y379996D03*
X1137540D03*
X1117261Y391696D03*
X1137540D03*
X1117261Y383896D03*
X1137540D03*
X1117261Y387796D03*
X1137540D03*
X1124021Y368296D03*
Y376096D03*
X1130780Y364396D03*
X1134160Y374146D03*
X1120641Y370247D03*
Y374146D03*
X1130780Y368296D03*
Y376096D03*
X1127400Y370247D03*
Y378047D03*
Y366347D03*
Y374146D03*
X1103741Y368296D03*
Y376096D03*
X1113881Y370247D03*
Y374146D03*
X1100361Y370247D03*
Y374146D03*
X1110501Y368296D03*
Y376096D03*
X1103741Y356596D03*
Y360496D03*
X1100361Y354647D03*
Y362447D03*
X1113881Y354647D03*
Y362447D03*
X1124021Y356596D03*
Y360496D03*
X1110501Y356596D03*
Y360496D03*
X1120641Y354647D03*
Y362447D03*
X1107121Y370247D03*
X1117261Y356596D03*
X1107121Y378047D03*
X1117261Y364396D03*
X1107121Y366347D03*
X1117261Y352696D03*
X1107121Y374146D03*
X1117261Y360496D03*
X1157820Y356596D03*
X1144300Y352696D03*
X1154440Y350747D03*
Y362447D03*
X1144300Y368296D03*
X1157820Y379996D03*
X1147680Y389747D03*
X1144300Y376096D03*
X1151060Y383896D03*
X1161200Y362447D03*
X1157820Y364396D03*
X1154440Y370246D03*
X1157820Y376096D03*
X1151060Y372196D03*
X1147680Y378047D03*
X1144300Y379996D03*
Y387796D03*
X1161200Y358547D03*
Y366347D03*
X1157820Y368296D03*
Y372196D03*
X1154440Y374146D03*
X1151060Y376096D03*
X1147680Y381947D03*
X1144300Y383896D03*
X1161200Y354647D03*
X1107121Y350747D03*
X1113881Y346847D03*
X1147680Y370247D03*
Y374146D03*
X1120641Y346847D03*
X1161200Y389747D03*
X1154440Y397546D03*
Y393647D03*
X1151060Y387796D03*
X1157820Y395597D03*
X1154440Y389747D03*
X1157820Y391696D03*
X1154440Y385847D03*
X1140920Y354647D03*
X1161201Y401447D03*
X1157820Y383896D03*
X1137540Y356596D03*
X1156699Y401447D03*
X1134160Y358547D03*
X1137540Y352696D03*
X1130780Y356596D03*
X1134160Y354647D03*
Y350747D03*
X1137540Y348796D03*
X1107874Y518157D03*
Y528899D03*
X1110520Y513114D03*
X1131299Y518157D03*
Y528899D03*
X1134645Y513114D03*
X1101181Y518157D03*
X1104227Y513114D03*
X1101181Y528899D03*
X1124606Y518157D03*
Y528899D03*
X1127952Y513114D03*
X1144685Y518157D03*
X1147331Y513114D03*
X1144685Y528899D03*
X1137992Y518157D03*
X1141038Y513114D03*
X1137992Y528899D03*
X1144385Y498487D03*
X1147331Y490894D03*
X1137992Y498487D03*
X1141038Y491144D03*
X1110520Y534700D03*
X1134645Y535100D03*
X1104141Y534700D03*
X1127952Y535100D03*
X1147331Y534700D03*
X1140952D03*
X1107874Y555957D03*
X1110520Y572500D03*
Y550914D03*
X1107874Y566699D03*
X1131299Y555957D03*
X1134645Y572900D03*
Y550914D03*
X1131299Y566699D03*
X1101181Y555957D03*
X1104141Y572500D03*
X1104227Y550914D03*
X1101181Y566699D03*
X1124606Y555957D03*
X1127952Y572900D03*
Y550914D03*
X1124606Y566699D03*
X1147331Y572500D03*
X1144685Y555957D03*
X1147331Y550914D03*
X1144685Y566699D03*
X1140952Y572500D03*
X1137992Y555957D03*
X1141038Y550914D03*
X1137992Y566699D03*
X1110520Y588714D03*
X1134645D03*
X1104227D03*
X1127952D03*
X1147331D03*
X1141038D03*
X1110520Y610300D03*
X1107874Y593757D03*
Y604499D03*
X1134645Y610700D03*
X1131299Y593757D03*
Y604499D03*
X1101181Y593757D03*
X1104141Y610300D03*
X1101181Y604499D03*
X1124606Y593757D03*
X1127952Y610700D03*
X1124606Y604499D03*
X1147700Y611200D03*
X1144685Y593757D03*
Y604499D03*
X1137992Y593757D03*
X1141332Y611668D03*
X1137992Y604499D03*
X1171456Y34100D03*
X1168110Y27899D03*
X1164763Y34100D03*
X1161417Y27899D03*
X1184142Y33700D03*
X1181496Y27899D03*
X1208267Y34100D03*
X1204921Y27899D03*
X1177763Y33700D03*
X1174803Y27899D03*
X1201574Y34100D03*
X1198228Y27899D03*
X1220953Y33700D03*
X1218307Y27899D03*
X1214574Y33700D03*
X1211614Y27899D03*
X1171456Y-3700D03*
X1168110Y17157D03*
Y-9901D03*
X1171456Y12114D03*
X1164763Y-3700D03*
X1161417Y17157D03*
Y-9901D03*
X1164763Y12114D03*
X1184142Y-4100D03*
X1181496Y17157D03*
X1184142Y12114D03*
X1181496Y-9901D03*
X1204921Y17157D03*
X1208267Y-3700D03*
X1204921Y-9901D03*
X1208267Y12114D03*
X1177763Y-4100D03*
X1174803Y17157D03*
Y-9901D03*
X1177849Y12114D03*
X1198228Y17157D03*
X1201574Y-3700D03*
Y12114D03*
X1198228Y-9901D03*
X1220953Y-4100D03*
X1218307Y17157D03*
Y-9901D03*
X1220953Y12114D03*
X1214574Y-4100D03*
X1211614Y17157D03*
Y-9901D03*
X1214660Y12114D03*
X1171456Y71900D03*
X1168110Y92757D03*
Y65699D03*
X1171456Y87714D03*
X1164763Y71900D03*
X1161417Y92757D03*
Y65699D03*
X1164763Y87714D03*
X1181496Y92757D03*
X1184142Y71500D03*
Y87714D03*
X1181496Y65699D03*
X1208267Y71900D03*
X1204921Y92757D03*
X1208267Y87714D03*
X1204921Y65699D03*
X1177763Y71500D03*
X1174803Y92757D03*
Y65699D03*
X1177849Y87714D03*
X1201574Y71900D03*
X1198228Y92757D03*
X1201574Y87714D03*
X1198228Y65699D03*
X1220953Y71500D03*
X1218307Y92757D03*
X1220953Y87714D03*
X1218307Y65699D03*
X1214574Y71500D03*
X1211614Y92757D03*
X1214874Y87374D03*
X1211614Y65699D03*
X1168110Y54957D03*
X1171456Y49914D03*
X1161417Y54957D03*
X1164763Y49914D03*
X1181496Y54957D03*
X1184142Y49914D03*
X1204921Y54957D03*
X1208267Y49914D03*
X1174803Y54957D03*
X1177849Y49914D03*
X1198228Y54957D03*
X1201574Y49914D03*
X1218307Y54957D03*
X1220953Y49914D03*
X1211614Y54957D03*
X1214660Y49914D03*
X1167925Y112357D03*
X1170721Y106964D03*
X1161632Y112357D03*
X1164428Y106964D03*
X1181496Y112357D03*
X1184142Y106964D03*
X1204921Y112357D03*
X1208267Y107314D03*
X1174742Y112357D03*
X1177849Y107314D03*
X1198228Y112357D03*
X1201574Y107314D03*
X1208519Y218147D03*
X1167960Y222047D03*
X1164580Y220096D03*
X1161200Y222047D03*
X1171339Y216196D03*
X1181479Y218147D03*
X1191619Y208397D03*
X1209033Y183907D03*
X1188239Y202247D03*
X1181479Y202547D03*
X1174719D03*
X1178099Y204496D03*
X1181479Y214247D03*
X1178099Y212296D03*
X1184859Y208397D03*
Y220096D03*
X1191619Y216196D03*
X1194999Y214247D03*
Y218147D03*
X1198379Y220096D03*
X1201759Y222047D03*
X1164580Y212296D03*
Y208397D03*
X1167960Y214247D03*
X1174719Y210346D03*
X1184859Y216196D03*
X1181479Y210346D03*
X1184859Y212296D03*
X1188239Y218147D03*
X1191619Y220096D03*
Y212296D03*
X1198379Y216196D03*
X1205139Y220096D03*
X1164580Y216196D03*
X1167960Y210346D03*
X1171339Y212296D03*
X1174719Y214247D03*
Y222047D03*
X1221767Y175858D03*
X1220580Y179810D03*
X1161200Y268847D03*
X1164580Y255196D03*
X1171339Y270796D03*
X1164580Y282496D03*
X1167960Y280547D03*
X1171339Y282496D03*
X1167960Y261047D03*
X1174719D03*
X1164580Y251296D03*
X1167960Y272747D03*
X1171339Y255196D03*
Y251296D03*
X1161200Y245447D03*
X1164580Y243496D03*
Y274696D03*
X1174719Y272747D03*
X1167960Y257147D03*
X1161200Y272747D03*
X1191619Y223996D03*
X1178099D03*
X1167960Y233746D03*
X1178099Y270796D03*
Y278596D03*
X1181479Y249347D03*
Y237647D03*
Y241547D03*
X1184859Y223996D03*
X1201759Y237647D03*
X1198379Y227896D03*
X1205139Y231797D03*
X1201759Y245447D03*
X1194999Y237647D03*
X1198379Y251296D03*
X1181479Y264947D03*
X1184859Y255196D03*
X1191619Y270796D03*
X1198379Y262996D03*
X1194999Y276646D03*
X1198379Y282496D03*
Y270796D03*
X1178099Y266896D03*
X1162300Y264947D03*
X1167960Y249347D03*
X1181479Y257147D03*
X1178099Y255196D03*
X1161200Y253247D03*
X1174719Y268847D03*
X1167960Y241547D03*
Y245447D03*
Y237647D03*
X1171339Y239596D03*
Y243496D03*
X1174719Y241547D03*
X1178099Y239596D03*
X1174719Y249347D03*
Y245447D03*
X1171339Y278596D03*
X1178099Y262996D03*
X1205139Y255196D03*
X1208519Y249347D03*
X1201759Y253247D03*
X1205139Y243496D03*
X1212199Y239596D03*
X1205139Y235696D03*
X1212199Y227896D03*
X1208519Y225947D03*
X1205139Y282496D03*
X1201759Y280547D03*
X1198379Y274696D03*
X1201759Y272747D03*
X1205139Y270796D03*
X1201759Y264947D03*
X1205139Y262996D03*
X1208519Y257147D03*
Y253247D03*
X1205139Y251296D03*
X1208519Y241547D03*
Y237647D03*
X1205139Y239596D03*
X1212199Y231797D03*
Y223996D03*
X1205139Y278596D03*
X1201759Y276646D03*
Y268847D03*
X1208519D03*
X1205139Y266896D03*
Y259096D03*
Y223996D03*
X1198379D03*
X1205139Y227896D03*
X1178099Y282496D03*
X1184859Y262996D03*
X1191619Y259096D03*
X1194999Y261047D03*
Y257147D03*
X1188239Y253247D03*
X1194999Y249347D03*
X1198379Y247396D03*
X1191619Y243496D03*
X1188239Y241547D03*
X1181479Y245447D03*
X1184859Y278596D03*
X1188239Y276646D03*
Y280547D03*
X1181479Y272747D03*
X1188239Y268847D03*
X1191619Y266896D03*
X1181479Y280547D03*
X1188239Y261047D03*
X1191619Y262996D03*
X1198379Y259096D03*
X1191619Y255196D03*
Y251296D03*
X1194999Y253247D03*
Y245447D03*
Y241547D03*
X1188239Y245447D03*
X1184859Y243496D03*
Y282496D03*
Y274696D03*
X1191619Y282496D03*
Y278596D03*
X1184859Y270796D03*
X1188239Y272747D03*
Y264947D03*
X1174719Y229847D03*
X1167960Y225947D03*
X1174719Y233746D03*
X1181479Y229847D03*
X1184859Y227896D03*
Y231797D03*
X1191619Y235696D03*
Y227896D03*
X1198379Y231797D03*
X1161200Y233746D03*
Y229847D03*
X1171339Y227896D03*
Y223996D03*
X1174719Y225947D03*
X1178099Y231797D03*
X1181479Y233746D03*
Y225947D03*
X1188239Y229847D03*
Y233746D03*
X1191619Y231797D03*
X1194999Y229847D03*
X1161200Y225947D03*
X1164580Y231797D03*
X1174719Y257147D03*
X1178099Y259096D03*
X1174719Y276646D03*
X1167960D03*
Y268847D03*
X1181479Y253247D03*
X1178099Y251296D03*
X1167960Y264947D03*
X1171339Y262996D03*
X1174719Y264947D03*
X1208519Y229847D03*
X1184859Y337096D03*
X1178099Y340996D03*
X1181479Y339047D03*
Y342947D03*
X1178099Y344896D03*
X1201759Y331247D03*
Y335147D03*
Y342947D03*
X1198379Y344896D03*
Y333196D03*
X1201759Y339047D03*
X1205139Y340996D03*
X1181479Y331247D03*
X1167960Y284447D03*
X1198379Y321496D03*
X1194999Y323446D03*
X1181479Y315647D03*
X1171339Y344896D03*
X1174719Y339047D03*
X1164580Y340996D03*
X1167960Y331247D03*
X1171339Y321496D03*
X1184859Y325396D03*
Y333196D03*
X1198379Y337096D03*
Y329296D03*
X1194999Y342947D03*
X1174719Y323446D03*
X1181479D03*
X1174719Y327347D03*
X1178099Y333196D03*
X1171339Y329296D03*
X1167960Y335147D03*
X1171339Y340996D03*
X1174719Y319547D03*
X1178099Y321496D03*
Y325396D03*
Y329296D03*
X1174719Y331247D03*
X1171339Y333196D03*
Y337096D03*
X1161200Y311747D03*
X1198379Y290296D03*
Y294196D03*
X1161200Y300047D03*
Y303947D03*
X1201759Y292247D03*
X1205439Y290296D03*
Y294196D03*
Y286596D03*
X1208819Y284447D03*
X1184859Y286396D03*
X1191619D03*
X1194999Y284447D03*
X1181479D03*
X1191619Y290296D03*
Y313696D03*
Y309797D03*
X1188239Y307847D03*
Y303947D03*
Y300047D03*
X1184859Y298096D03*
Y344896D03*
X1191619D03*
Y340996D03*
Y337096D03*
X1188239Y331247D03*
X1194999Y327347D03*
X1188239D03*
X1184859Y317596D03*
X1191619D03*
X1194999Y311747D03*
X1191619Y305896D03*
X1184859D03*
X1191619Y301996D03*
X1188239Y296147D03*
X1181479D03*
X1184859Y340996D03*
X1188239Y342947D03*
X1194999Y339047D03*
X1191619Y333196D03*
Y329296D03*
Y325396D03*
X1188239Y323446D03*
X1184859Y313696D03*
X1188239Y315647D03*
X1174719Y303947D03*
X1167960D03*
X1178099Y309797D03*
X1171339Y305896D03*
X1164580Y309797D03*
Y305896D03*
X1167960Y307847D03*
Y311747D03*
X1171339Y309797D03*
X1178099Y301996D03*
X1174719Y311747D03*
Y307847D03*
X1178099Y305896D03*
Y313696D03*
X1171339D03*
X1164580D03*
X1174719Y292247D03*
Y288347D03*
X1171339Y286396D03*
Y290296D03*
X1167960Y300047D03*
X1164580Y298096D03*
X1167960Y296147D03*
Y292247D03*
Y288347D03*
X1161200Y296147D03*
X1178099Y290296D03*
X1171339Y298096D03*
Y294196D03*
X1174719Y296147D03*
Y346847D03*
X1178099Y348796D03*
Y352696D03*
X1201759Y346847D03*
X1167960Y358547D03*
X1174719Y350747D03*
X1167960Y366347D03*
X1171339Y368296D03*
X1161200Y374146D03*
X1178099Y391696D03*
X1174719Y397546D03*
X1164580Y399496D03*
X1188239Y370247D03*
X1191619Y372197D03*
Y364396D03*
Y352696D03*
X1181479Y385847D03*
Y405347D03*
X1188239Y381947D03*
X1208819Y385847D03*
X1164580Y368296D03*
X1167960Y350747D03*
Y354647D03*
X1164580Y360496D03*
Y364396D03*
X1167960Y346847D03*
X1171339Y352696D03*
X1184859Y348796D03*
X1188239Y346847D03*
X1178099Y387796D03*
X1171339D03*
Y391696D03*
X1167960Y393647D03*
X1164580Y395597D03*
X1178099Y379996D03*
Y383896D03*
X1174719Y385847D03*
X1171339Y383896D03*
X1174719Y389747D03*
X1171339Y395596D03*
X1164580Y391696D03*
Y387796D03*
X1178099Y376096D03*
X1181479Y381947D03*
X1188239Y354647D03*
Y358547D03*
Y362447D03*
X1181479D03*
Y366347D03*
X1184859Y372197D03*
Y376096D03*
Y379996D03*
X1188239Y350747D03*
X1191619Y356596D03*
X1184859Y360496D03*
X1181479Y358547D03*
X1184859Y364396D03*
Y368296D03*
X1188239Y374146D03*
X1181479Y378047D03*
X1174719Y370247D03*
X1181479D03*
X1171339Y364396D03*
X1178099Y360496D03*
Y356596D03*
X1184859Y352696D03*
X1161200Y393647D03*
Y385847D03*
X1167960D03*
Y381947D03*
Y378047D03*
X1174719D03*
Y374146D03*
Y366347D03*
X1178099Y368296D03*
X1174719Y362447D03*
Y358547D03*
X1181479Y354647D03*
Y350747D03*
X1161200Y381947D03*
X1164580Y383896D03*
X1171339Y379996D03*
X1167960Y374146D03*
X1171339Y376096D03*
X1178099Y372197D03*
X1167960Y405347D03*
X1194999Y378047D03*
X1201759Y374146D03*
X1194999D03*
X1198379Y364396D03*
Y360496D03*
Y356596D03*
X1174719Y405347D03*
Y401447D03*
X1178099Y395596D03*
X1184859Y399496D03*
X1181479Y393647D03*
X1188239Y389747D03*
Y385847D03*
X1191619Y379996D03*
X1198379Y383896D03*
X1167960Y401447D03*
X1198379Y376096D03*
Y372197D03*
X1194999Y370247D03*
Y362447D03*
X1201759Y358547D03*
X1198379Y352696D03*
X1171339Y403396D03*
X1178099Y399496D03*
X1181479Y397546D03*
X1184859Y395596D03*
Y391696D03*
Y387796D03*
X1191619Y383896D03*
X1194999Y381947D03*
X1198379Y379996D03*
X1164580Y376096D03*
X1194999Y350747D03*
X1198379Y348796D03*
X1168110Y518157D03*
X1171456Y513114D03*
X1168110Y528899D03*
X1161417Y518157D03*
Y528899D03*
X1164763Y513114D03*
X1181496Y518157D03*
Y528899D03*
X1184142Y513114D03*
X1204921Y518157D03*
X1208267Y513114D03*
X1204921Y528899D03*
X1174803Y518157D03*
Y528899D03*
X1177849Y513114D03*
X1198228Y518157D03*
X1201574Y513114D03*
X1198228Y528899D03*
X1218307Y518157D03*
X1220953Y513114D03*
X1218307Y528899D03*
X1211614Y518157D03*
X1214874Y512774D03*
X1211614Y528899D03*
X1167510Y498487D03*
X1170656Y493844D03*
X1161417Y498487D03*
X1164363Y493744D03*
X1180400Y498387D03*
X1184142Y493394D03*
X1204400Y498487D03*
X1208267Y496144D03*
X1174203Y498387D03*
X1177799Y493544D03*
X1198100Y498400D03*
X1200974Y493344D03*
X1171456Y535100D03*
X1164763D03*
X1184142Y534700D03*
X1208267Y535100D03*
X1177763Y534700D03*
X1201574Y535100D03*
X1220953Y534700D03*
X1214574D03*
X1171456Y572900D03*
X1168110Y555957D03*
X1171456Y550914D03*
X1168110Y566699D03*
X1164763Y572900D03*
X1161417Y555957D03*
X1164763Y550914D03*
X1161417Y566699D03*
X1184142Y572500D03*
X1181496Y555957D03*
X1184142Y550914D03*
X1181496Y566699D03*
X1208267Y572900D03*
X1204921Y555957D03*
X1208267Y550914D03*
X1204921Y566699D03*
X1177763Y572500D03*
X1174803Y555957D03*
X1177849Y550914D03*
X1174803Y566699D03*
X1201574Y572900D03*
X1198228Y555957D03*
X1201574Y550914D03*
X1198228Y566699D03*
X1218307Y555957D03*
X1220953Y572500D03*
Y550914D03*
X1218307Y566699D03*
X1211614Y555957D03*
X1214574Y572500D03*
X1214874Y550574D03*
X1211614Y566699D03*
X1171456Y588714D03*
X1164763D03*
X1184142D03*
X1208267D03*
X1177849D03*
X1201574D03*
X1220953D03*
X1214660D03*
X1168110Y593757D03*
X1171456Y610700D03*
X1168110Y604499D03*
X1161417Y593757D03*
X1164763Y610700D03*
X1161417Y604499D03*
X1181496Y593757D03*
X1184142Y610300D03*
X1181496Y604499D03*
X1208267Y610700D03*
X1204921Y593757D03*
Y604499D03*
X1174803Y593757D03*
X1177763Y610300D03*
X1174803Y604499D03*
X1198228Y593757D03*
X1201574Y610700D03*
X1198228Y604499D03*
X1218307Y593757D03*
X1220953Y610300D03*
X1218307Y604499D03*
X1211614Y593757D03*
X1214574Y610300D03*
X1211614Y604499D03*
X1245078Y34100D03*
X1241732Y27899D03*
X1238385Y34100D03*
X1235039Y27899D03*
X1245078Y-3700D03*
X1241732Y17157D03*
Y-9901D03*
X1245078Y12114D03*
X1238385Y-3700D03*
X1235039Y17157D03*
Y-9901D03*
X1238385Y12114D03*
X1251771Y27899D03*
Y36057D03*
X1248425Y17057D03*
X1258464Y36057D03*
Y27899D03*
X1265157Y36057D03*
X1261811D03*
Y27899D03*
Y16999D03*
X1258464D03*
X1265157Y9157D03*
X1251771D03*
Y-1743D03*
X1261811Y-9901D03*
X1258464D03*
X1261811Y-1743D03*
X1265157D03*
X1258464D03*
X1255118Y-9901D03*
Y27899D03*
Y16999D03*
Y-1743D03*
Y36057D03*
Y9157D03*
X1265157Y27899D03*
Y-9901D03*
Y16999D03*
X1276346Y-10250D03*
X1245078Y71900D03*
X1241732Y92757D03*
X1245078Y87714D03*
X1241732Y65699D03*
X1238385Y71900D03*
X1235039Y92757D03*
X1238385Y87714D03*
X1235039Y65699D03*
X1241732Y54957D03*
X1245078Y49914D03*
X1235039Y54957D03*
X1238385Y49914D03*
X1251771Y54799D03*
X1248425Y54857D03*
X1251771Y46957D03*
X1258464D03*
Y54799D03*
X1261811Y46957D03*
Y54799D03*
Y65699D03*
X1258464D03*
X1251771Y84757D03*
X1248425Y92657D03*
X1265157Y73857D03*
X1261811D03*
X1258464D03*
X1261811Y84757D03*
X1258464D03*
X1265157D03*
X1251771Y73857D03*
X1261811Y92599D03*
X1258464D03*
X1255118Y65699D03*
Y54799D03*
Y92599D03*
Y46957D03*
Y84757D03*
Y73857D03*
X1265157Y65699D03*
Y92599D03*
Y54799D03*
X1270350Y98300D03*
X1268111Y58040D03*
X1251344Y127925D03*
X1259950Y144650D03*
X1277100Y122670D03*
X1272100Y141603D03*
X1264550Y114670D03*
X1277100Y114800D03*
X1261030Y105350D03*
X1277600Y106200D03*
X1248616Y133817D03*
X1237704Y148423D03*
X1268576Y117788D03*
X1250200Y122900D03*
X1251980Y106960D03*
X1262569Y147201D03*
X1243948Y154916D03*
X1269810Y154398D03*
X1275470Y99390D03*
X1252000Y145300D03*
X1257800Y120800D03*
X1255400Y108000D03*
X1252437Y140192D03*
X1249025Y130460D03*
X1240000Y129500D03*
X1259200Y168350D03*
X1281799Y193190D03*
X1267800Y161800D03*
X1271400Y161900D03*
X1240309D03*
X1267050Y169800D03*
X1233902Y173337D03*
X1241381Y172040D03*
X1246655Y176395D03*
X1263300Y169450D03*
X1268404Y246304D03*
X1279393Y247602D03*
X1270478Y243490D03*
X1277504Y250346D03*
X1272761Y240220D03*
X1283720Y223870D03*
X1249230Y402022D03*
X1262700Y461804D03*
X1262900Y466504D03*
X1277978Y491571D03*
X1241732Y518157D03*
Y528899D03*
X1245078Y513114D03*
X1235039Y518157D03*
X1238385Y513114D03*
X1235039Y528899D03*
X1278573Y519596D03*
X1265157Y510157D03*
X1261811Y517999D03*
X1258464Y510157D03*
Y517999D03*
X1261811Y510157D03*
X1248425Y518057D03*
X1251771Y510157D03*
X1258464Y528899D03*
X1261811D03*
X1255120Y518000D03*
Y510158D03*
X1271300Y510600D03*
X1271105Y498516D03*
X1274576Y510235D03*
X1265157Y528876D03*
Y517999D03*
X1262843Y497553D03*
X1258140Y474540D03*
X1271571Y479000D03*
X1271662Y487326D03*
X1256320Y490660D03*
X1258126Y469540D03*
X1271640Y474420D03*
X1271647Y482500D03*
X1256350Y486080D03*
X1245078Y535100D03*
X1238385D03*
X1241732Y555957D03*
X1245078Y572900D03*
Y550914D03*
X1241732Y566699D03*
X1238385Y572900D03*
X1235039Y555957D03*
X1238385Y550914D03*
X1235039Y566699D03*
X1245078Y588714D03*
X1238385D03*
X1265157Y547957D03*
X1261811D03*
X1258464D03*
X1251771D03*
X1265157Y537057D03*
X1261811D03*
X1251771D03*
X1258464D03*
X1265157Y585757D03*
X1261811D03*
X1258464D03*
X1251771D03*
X1261811Y555799D03*
X1258464D03*
X1251771D03*
X1248425Y555857D03*
X1251771Y566699D03*
Y574857D03*
X1265157D03*
X1261811D03*
X1258464D03*
X1261811Y566699D03*
X1258464D03*
X1273200Y582200D03*
X1255120Y555144D03*
Y574834D03*
Y537034D03*
X1265157Y566676D03*
Y555799D03*
X1277200Y539100D03*
X1270400Y593600D03*
X1241732Y593757D03*
X1245078Y610700D03*
X1241732Y604499D03*
X1238385Y610700D03*
X1235039Y593757D03*
Y604499D03*
X1258464Y593599D03*
X1261811D03*
X1248425Y593657D03*
X1251771Y612657D03*
X1258464Y604499D03*
X1261811D03*
X1265157Y612657D03*
X1261811D03*
X1258464D03*
X1255120Y593600D03*
Y612634D03*
X1265157Y604476D03*
Y593599D03*
X1293600Y-17000D03*
X1293816Y-13533D03*
X1292692Y1008D03*
X1296908Y36900D03*
X1287700Y-16700D03*
X1303774Y-18842D03*
X1298422Y74000D03*
X1330300Y83500D03*
X1336850Y76450D03*
X1327168Y61483D03*
X1304685Y78827D03*
X1298754Y83233D03*
X1336900Y61600D03*
X1343260Y53770D03*
X1327500Y51547D03*
X1327452Y55544D03*
X1309700Y83300D03*
X1336500Y81100D03*
X1324127Y50827D03*
X1337400Y72000D03*
X1338500Y96000D03*
X1343500Y87500D03*
X1335120Y94450D03*
X1301219Y89141D03*
X1304500Y40066D03*
X1296935Y51335D03*
X1323000Y83000D03*
X1328500Y92500D03*
X1308400Y79600D03*
X1306900Y131744D03*
X1301900Y124400D03*
X1325125Y100001D03*
X1310098Y150040D03*
X1293700Y121800D03*
X1295700Y144450D03*
X1327900Y142918D03*
X1301770Y101300D03*
X1345257Y100000D03*
X1320500Y145000D03*
X1325100D03*
X1287790Y156575D03*
X1310175Y154696D03*
X1299907Y159808D03*
X1295500Y159970D03*
X1300300Y169900D03*
X1315130Y164870D03*
X1315180Y169950D03*
X1326474Y216500D03*
X1338224Y209051D03*
X1305171Y164767D03*
X1310061Y165235D03*
X1344462Y209272D03*
X1323030Y216531D03*
X1330100Y165000D03*
Y170000D03*
X1340100Y165000D03*
X1345100D03*
Y170000D03*
X1340100D03*
X1335100D03*
Y165000D03*
X1320100D03*
X1325100D03*
X1320100Y170000D03*
X1325100D03*
X1345050Y272350D03*
X1300444Y267919D03*
X1309462Y240229D03*
X1288800Y233900D03*
X1320289Y237671D03*
X1331400Y237900D03*
X1342400D03*
X1315100Y237645D03*
X1325900Y237900D03*
X1336900D03*
X1320400Y232118D03*
X1331400D03*
X1342400D03*
X1314900D03*
X1325900D03*
X1336900D03*
X1331650Y317250D03*
X1338700Y284700D03*
X1323750Y319750D03*
X1320900Y321300D03*
X1335250Y344250D03*
X1319310Y300795D03*
X1336336Y333825D03*
X1302768Y296942D03*
X1331720Y334810D03*
X1326300Y341309D03*
X1341375Y314675D03*
Y319675D03*
X1341740Y306760D03*
X1336240D03*
X1316600Y305500D03*
X1306290Y298255D03*
X1308887Y285015D03*
X1319888Y290205D03*
X1323688D03*
X1345700Y285300D03*
X1341740Y301243D03*
X1336240D03*
X1335400Y284900D03*
X1302203Y314439D03*
X1315496Y361190D03*
X1342570Y368220D03*
X1326014Y347732D03*
X1296468Y437500D03*
X1325100Y457500D03*
Y452500D03*
X1320100Y457500D03*
Y452500D03*
X1315100D03*
X1310100D03*
X1315100Y457500D03*
X1305100D03*
Y452500D03*
X1310100Y457500D03*
X1330100D03*
Y452500D03*
X1300315Y427902D03*
X1335100Y427500D03*
Y432500D03*
X1300438Y433001D03*
X1318054Y460507D03*
X1340100Y432500D03*
X1304200Y466600D03*
Y462030D03*
X1329419Y464337D03*
X1344761Y498282D03*
X1309870Y499254D03*
X1287770Y501897D03*
X1340986Y511187D03*
X1341050Y498275D03*
X1299450Y484950D03*
X1320300Y498300D03*
X1322260Y477492D03*
X1329419Y469337D03*
X1322360Y472592D03*
X1316100Y543400D03*
X1308500Y540784D03*
X1324707Y545493D03*
X1327956Y545655D03*
X1318500Y539900D03*
X1305500Y542500D03*
X1296295Y615596D03*
X1301384Y618119D03*
X1400616Y13795D03*
X1376094Y4406D03*
X1380678Y-422D03*
X1380950Y30232D03*
X1379025Y-9799D03*
X1407422Y13139D03*
X1377009Y39753D03*
X1347500Y83000D03*
X1355500D03*
X1359500D03*
X1358500Y74500D03*
X1363500Y77400D03*
X1370975Y67225D03*
X1370849Y59349D03*
X1371910Y48800D03*
X1351500Y83000D03*
X1367700Y86450D03*
X1371500Y63200D03*
X1351488Y74000D03*
X1347000Y87500D03*
X1360700Y86550D03*
X1372300Y86400D03*
X1406546Y43116D03*
X1353500Y96959D03*
X1348615Y96239D03*
X1357000Y86640D03*
X1383171Y57549D03*
X1401300Y149600D03*
X1384600Y108500D03*
X1381359Y108496D03*
X1388100Y108500D03*
X1371500Y101000D03*
X1404200Y119200D03*
X1402500Y116300D03*
X1399100Y166900D03*
X1396933Y215763D03*
X1353569Y208960D03*
X1348569D03*
X1367789Y209216D03*
X1384671Y214832D03*
X1402020Y165561D03*
X1350100Y170000D03*
X1380100Y165000D03*
X1355100Y170000D03*
X1360100D03*
X1355100Y165000D03*
X1360100D03*
X1350100D03*
X1365100Y170000D03*
Y165000D03*
X1370100D03*
X1375100Y170000D03*
X1370100D03*
X1375100Y165000D03*
X1380100Y170000D03*
X1399852Y252353D03*
X1407274Y245652D03*
X1353400Y237900D03*
X1364400D03*
X1375400D03*
X1347900D03*
X1358900D03*
X1369900D03*
X1380900D03*
X1391900D03*
X1353400Y232118D03*
X1364400D03*
X1375400D03*
X1347900D03*
X1358900D03*
X1369900D03*
X1380900D03*
X1365246Y285931D03*
X1363700Y321600D03*
X1367200D03*
X1352400Y285000D03*
X1396470Y330014D03*
X1392400Y330800D03*
X1400400Y335400D03*
X1388450Y331250D03*
X1359200Y322200D03*
X1364260Y331619D03*
X1349134Y317436D03*
X1360294Y315025D03*
X1371090Y315395D03*
X1380904Y315947D03*
X1392226Y315658D03*
X1400558Y320157D03*
X1349134Y321145D03*
X1360294Y318825D03*
X1371090Y319195D03*
X1380904Y319747D03*
X1392226Y319458D03*
X1400558Y316357D03*
X1353142Y306760D03*
X1364044Y306690D03*
X1374840Y307130D03*
X1386048Y307310D03*
X1397635Y307630D03*
X1347642Y306760D03*
X1358544Y306690D03*
X1369340Y307130D03*
X1380548Y307310D03*
X1392135Y307630D03*
X1403037D03*
X1368200Y284000D03*
X1353672Y299605D03*
X1364014Y300815D03*
X1374820Y301219D03*
X1386101Y301465D03*
X1397635Y302051D03*
X1347892Y299741D03*
X1358514Y300815D03*
X1369320Y301219D03*
X1380601Y301465D03*
X1392135Y302051D03*
X1355300Y321675D03*
X1381431Y284259D03*
X1394370Y384230D03*
X1378207Y394568D03*
X1394260Y351170D03*
X1389500Y360500D03*
X1391845Y348325D03*
X1388300Y346200D03*
X1371600Y368700D03*
X1380872Y378098D03*
X1380900Y383164D03*
X1388900Y387800D03*
X1378200Y346900D03*
X1377028Y458125D03*
X1372028D03*
X1360100Y447500D03*
Y452500D03*
Y457500D03*
X1385100Y452500D03*
Y447500D03*
X1390100Y457500D03*
X1389900Y447400D03*
X1390100Y452500D03*
X1395100Y432500D03*
Y447500D03*
Y427500D03*
X1349800Y458200D03*
X1350100Y447500D03*
Y452500D03*
X1375100Y447500D03*
X1362560Y463478D03*
X1370100Y452500D03*
X1375100D03*
X1385100Y427500D03*
Y442500D03*
Y437500D03*
X1390100Y432500D03*
X1389900Y427400D03*
X1385100Y432500D03*
X1365100D03*
Y427500D03*
Y437500D03*
X1380100Y442500D03*
Y437500D03*
X1370100D03*
X1375100D03*
X1370100Y447500D03*
X1403027Y520231D03*
X1355800Y508500D03*
X1395242Y520301D03*
X1347546Y476897D03*
X1380741Y487489D03*
X1360863Y481673D03*
X1362841Y492823D03*
X1383263Y493673D03*
X1381041Y482575D03*
X1360741Y486523D03*
X1362880Y497556D03*
X1383241Y498595D03*
X1347081Y507919D03*
X1396035Y514863D03*
X1347196Y472941D03*
X1354462Y474141D03*
X1350500Y475100D03*
X1386241Y487323D03*
X1366341Y481823D03*
X1368441Y492723D03*
X1388741Y493623D03*
X1386241Y482623D03*
X1366309Y486618D03*
X1368441Y497523D03*
X1388719Y498745D03*
X1399721Y537509D03*
X1379053Y581864D03*
X1390595Y549328D03*
X1382000Y589500D03*
X1375600Y589700D03*
X1396158Y537595D03*
X1380890Y615820D03*
X1386921Y620689D03*
X1390851D03*
X1382100Y592800D03*
X1410600Y9100D03*
X1425081Y48412D03*
X1411546Y43116D03*
X1453700Y83750D03*
X1457000Y82000D03*
X1420337Y45477D03*
X1416837D03*
X1451021Y151626D03*
X1438348Y155908D03*
X1468700Y163100D03*
X1458569Y192143D03*
X1458908Y187699D03*
X1459548Y221731D03*
X1446331Y197285D03*
X1422281Y221479D03*
X1447999Y205645D03*
X1451366Y165296D03*
X1408247Y206270D03*
X1422196Y218052D03*
X1452728Y243306D03*
X1452200Y254500D03*
X1430365Y262624D03*
X1448500Y257700D03*
X1458318Y243000D03*
X1426905Y267045D03*
X1464150Y235550D03*
X1455600Y254826D03*
X1433057Y257388D03*
X1447154Y251710D03*
X1441750Y236800D03*
X1467040Y260357D03*
X1466006Y265300D03*
X1461400Y264700D03*
X1426658Y274252D03*
X1461348Y244350D03*
X1444850Y242730D03*
X1440910Y316693D03*
X1458400Y318500D03*
X1408250Y333000D03*
X1463610Y321329D03*
X1413387Y320033D03*
Y316233D03*
X1408537Y307630D03*
X1413720Y307634D03*
X1419333Y307598D03*
X1443500Y327900D03*
X1468399Y324930D03*
X1408537Y302046D03*
X1419220Y301983D03*
X1444311Y324366D03*
X1462776Y318200D03*
X1466970Y320235D03*
X1420075Y388402D03*
X1413735Y391302D03*
X1420075Y383375D03*
X1420515Y368585D03*
X1420075Y393402D03*
X1413735Y396302D03*
X1420075Y378375D03*
X1420515Y373585D03*
X1452699Y404060D03*
X1457300Y373600D03*
X1444400Y371600D03*
X1413400Y361300D03*
X1464400Y390800D03*
X1450400Y354300D03*
X1448000Y431500D03*
X1431900Y437100D03*
X1447700Y442500D03*
X1431900Y448000D03*
X1448000Y437000D03*
X1431900Y442600D03*
X1447500Y448000D03*
X1431900Y453500D03*
X1414107Y447267D03*
X1458300Y442675D03*
X1431690Y521530D03*
X1410486Y529792D03*
X1458060Y495020D03*
X1464553Y508872D03*
X1428500Y521000D03*
X1461267Y489790D03*
X1412941Y489523D03*
X1413193Y482532D03*
X1436600Y482900D03*
X1436541Y494423D03*
X1412741Y494223D03*
X1413041Y477423D03*
X1436396Y477691D03*
X1436441Y489323D03*
X1451533Y527867D03*
X1460661Y484891D03*
X1418241Y489523D03*
X1418441Y482523D03*
X1441842Y482924D03*
X1442041Y494423D03*
X1441252Y548631D03*
X1451150Y569900D03*
Y573200D03*
X1439822Y537382D03*
X1429026Y541026D03*
X1428281Y546119D03*
X1413600Y531300D03*
X1432560Y561160D03*
X1436160Y561200D03*
X1428791Y535512D03*
X1419600Y531500D03*
X1410950Y589670D03*
X1441409Y561117D03*
X1453533Y532667D03*
X1426870Y530800D03*
X1423800Y534800D03*
X1425243Y562260D03*
X1421560Y563455D03*
X1460200Y606200D03*
X1477100Y2400D03*
X1522600Y-6500D03*
X1504400Y20300D03*
X1481600Y5300D03*
X1501900Y-9124D03*
X1485242Y4589D03*
X1506300Y-6600D03*
X1521092Y21665D03*
X1520700Y7100D03*
X1513700Y7082D03*
X1470862Y38209D03*
X1519599Y86117D03*
X1524557Y88336D03*
X1505673Y146346D03*
X1473354Y153246D03*
X1485210Y134837D03*
X1476761Y157400D03*
X1483366Y120746D03*
Y115902D03*
X1484113Y128513D03*
X1485755Y131671D03*
X1518376Y111499D03*
X1476761Y152725D03*
X1490178Y112315D03*
X1518438Y100926D03*
X1494939Y159500D03*
X1510184Y142614D03*
X1503466Y142486D03*
X1500703Y158233D03*
X1514425Y134180D03*
X1520150Y127600D03*
X1475200Y142600D03*
X1496038Y154229D03*
X1488300Y158300D03*
X1500643Y154819D03*
X1513136Y157081D03*
X1496726Y120588D03*
X1496658Y115088D03*
X1500700Y127250D03*
X1500806Y133339D03*
X1518514Y130991D03*
X1524900Y139100D03*
X1526310Y142190D03*
X1524284Y112773D03*
X1474717Y110370D03*
X1482455Y124222D03*
X1502000Y147500D03*
X1490674Y98787D03*
X1524744Y133656D03*
X1496713Y174853D03*
X1504706Y164871D03*
X1511100Y186275D03*
X1492597Y172636D03*
X1488900Y172576D03*
X1474883Y182275D03*
X1478089Y182650D03*
X1470382Y188372D03*
X1472758Y216495D03*
X1513900Y218000D03*
X1519243Y191627D03*
X1487716Y218650D03*
X1477388Y172988D03*
X1497237Y217281D03*
X1497493Y162078D03*
X1512700Y205100D03*
X1488300Y161700D03*
X1498022Y221900D03*
X1512525Y208944D03*
X1492136Y199125D03*
X1493200Y162700D03*
X1512500Y199837D03*
X1510638Y166240D03*
X1516872Y208863D03*
X1491438Y221137D03*
X1510800Y193330D03*
X1515060Y192443D03*
X1507524Y218600D03*
X1472200Y243000D03*
X1482004Y222483D03*
X1525650Y248700D03*
X1470950Y229669D03*
X1526150Y234300D03*
X1486926Y247834D03*
X1496030Y267665D03*
X1516549Y234278D03*
X1516613Y240656D03*
X1521962Y278650D03*
X1512790Y240099D03*
X1499681Y279910D03*
X1486574Y267127D03*
X1507003Y272249D03*
X1492753Y273724D03*
X1484000Y257500D03*
X1492697Y267303D03*
X1475004Y246287D03*
X1474520Y251740D03*
X1482400Y248000D03*
X1487500Y244500D03*
X1505946Y254432D03*
X1519300Y245196D03*
X1499070Y255934D03*
X1470556Y256900D03*
X1469829Y266909D03*
X1484700Y251800D03*
X1527657Y278700D03*
X1503842Y245678D03*
X1504772Y259229D03*
X1523580Y237960D03*
X1496812Y273718D03*
X1479700Y224801D03*
X1504461Y274426D03*
X1520413Y239498D03*
X1489546Y279902D03*
X1491265Y226492D03*
X1483457Y244568D03*
X1474096Y256706D03*
X1497082Y277987D03*
X1526936Y307015D03*
X1529734Y319714D03*
X1473231Y320250D03*
X1499723Y300106D03*
X1471562Y325531D03*
X1512182Y293317D03*
X1497179Y306372D03*
X1508455Y313041D03*
X1523935Y318901D03*
X1493400Y300800D03*
X1514067Y315626D03*
X1484100Y330115D03*
X1501550Y293750D03*
X1482550Y333600D03*
X1487000Y333300D03*
X1503538Y318068D03*
X1518006Y286706D03*
X1499987Y288487D03*
X1496628Y288440D03*
X1520766Y341000D03*
X1505000Y340990D03*
X1508650Y287500D03*
X1510851Y340113D03*
X1497509Y303120D03*
X1500840Y319870D03*
X1504370Y330970D03*
X1518060Y317520D03*
X1470276Y330774D03*
X1493268Y293943D03*
X1496900Y293900D03*
X1525677Y311835D03*
X1499829Y341250D03*
X1530500Y287700D03*
X1510584Y330640D03*
X1526900Y292866D03*
X1470257Y321929D03*
X1495300Y297300D03*
X1493290Y287984D03*
X1478524Y318900D03*
X1483506Y326061D03*
X1493500Y304400D03*
X1514100Y321792D03*
X1517115Y330005D03*
X1507025Y391034D03*
X1493375Y380894D03*
X1505075D03*
X1501175Y394414D03*
X1499225Y391034D03*
Y384274D03*
X1487525Y397794D03*
X1493375Y394414D03*
X1489475D03*
X1487525Y384274D03*
X1489475Y387654D03*
X1514265Y355542D03*
X1499225Y377514D03*
X1495325Y391034D03*
X1493375Y387654D03*
X1505075Y394414D03*
X1501175Y387654D03*
X1495325Y377514D03*
X1524575Y394414D03*
X1530425Y384274D03*
X1487525Y377514D03*
X1517367Y349964D03*
X1472940Y384030D03*
X1473255Y372654D03*
X1525561Y350253D03*
X1511000Y350627D03*
X1505075Y387654D03*
Y401174D03*
X1501175D03*
X1507025Y404554D03*
X1522625Y391034D03*
X1495325Y397794D03*
X1499225D03*
Y404554D03*
X1493375Y401174D03*
X1489475D03*
X1507025Y384274D03*
X1501175Y380894D03*
X1522625Y404554D03*
X1481000Y350000D03*
X1502970Y350610D03*
X1496000Y350000D03*
X1528475Y380894D03*
X1522625Y397794D03*
X1528475Y401174D03*
Y387654D03*
X1529829Y362655D03*
X1516775Y380894D03*
X1526659Y397500D03*
X1528475Y394414D03*
X1524575Y380894D03*
X1522476Y361907D03*
X1507025Y377514D03*
X1520675Y394414D03*
X1522625Y377514D03*
X1530425D03*
X1518725Y397794D03*
Y391034D03*
Y384274D03*
X1510925Y397794D03*
X1512875Y401174D03*
Y394414D03*
X1530425Y391034D03*
X1514925Y358844D03*
X1484600Y394100D03*
X1495325Y384274D03*
X1483868Y390233D03*
X1483664Y362914D03*
X1520675Y401174D03*
X1516775D03*
Y394414D03*
X1510925Y377514D03*
X1512875Y380894D03*
X1515328Y363389D03*
X1518725Y377514D03*
X1522625Y384274D03*
X1510925Y391034D03*
X1516775Y387654D03*
X1512875D03*
X1510925Y384274D03*
X1478163Y354940D03*
X1530425Y397794D03*
X1489475Y380894D03*
X1524575Y387654D03*
X1503878Y364717D03*
X1485300Y443484D03*
X1489475Y450306D03*
X1491425Y453686D03*
X1493375Y457066D03*
X1499225Y460446D03*
X1493375Y450306D03*
X1489475Y457066D03*
X1495325Y460446D03*
X1497275Y463826D03*
X1483375Y458375D03*
X1530425Y467206D03*
X1516700Y409900D03*
X1528475Y407934D03*
X1512875Y463826D03*
X1510925Y467206D03*
X1507025D03*
X1508975Y463826D03*
X1501175Y428214D03*
X1495325Y418074D03*
X1499225Y424834D03*
X1516775Y463826D03*
X1505075D03*
X1524575D03*
X1493375Y414694D03*
X1489475D03*
X1491425Y411314D03*
X1487525D03*
X1493375Y443546D03*
X1489475D03*
X1491425Y440166D03*
X1487525D03*
X1516775Y457066D03*
X1528475Y463826D03*
X1524575Y407624D03*
X1514825Y467206D03*
X1499225Y411314D03*
X1501175Y407934D03*
X1499225Y440166D03*
X1524575Y457066D03*
X1505075D03*
X1501175Y443546D03*
X1485250Y408017D03*
X1501200Y450600D03*
X1521800Y419900D03*
X1508975Y457066D03*
X1505715Y441368D03*
X1497200Y421200D03*
X1491425Y446926D03*
X1493375Y428214D03*
X1489475D03*
X1493375Y436786D03*
X1489475D03*
X1499225Y446926D03*
Y453686D03*
X1491425Y460446D03*
X1499225Y467206D03*
X1489475Y463826D03*
X1491425Y467206D03*
X1487525Y460446D03*
X1495325Y467206D03*
X1485030Y463690D03*
X1491400Y424600D03*
X1487500D03*
X1489475Y421454D03*
X1493375D03*
X1520675Y463826D03*
X1505075Y407934D03*
X1497273Y407610D03*
X1489475Y407934D03*
X1493375D03*
X1520675Y470586D03*
X1503400Y524663D03*
X1524575Y470586D03*
X1520675Y477346D03*
X1512875Y470586D03*
X1472500Y509810D03*
X1474400Y517200D03*
X1482200Y477800D03*
X1497275Y470586D03*
Y477346D03*
X1489475D03*
X1499225Y473966D03*
X1493375Y470586D03*
X1495325Y473966D03*
X1493375Y477346D03*
X1491425Y480726D03*
X1501175Y477346D03*
X1530425Y487486D03*
X1528475Y484106D03*
X1520675D03*
X1524575Y477346D03*
X1512875D03*
X1497275Y484106D03*
X1499225Y487486D03*
X1503125Y473966D03*
X1507025D03*
X1501175Y484106D03*
X1505075D03*
X1503125Y480726D03*
X1505075Y477346D03*
X1508975Y484106D03*
X1507025Y480726D03*
X1510925Y487486D03*
X1512875Y484106D03*
X1493375D03*
X1491425Y487486D03*
X1495325Y480726D03*
Y487486D03*
X1526525Y480726D03*
X1530425D03*
X1524575Y484106D03*
X1522625Y480726D03*
X1516775Y477346D03*
X1472250Y485100D03*
X1470643Y495299D03*
X1482958Y486118D03*
X1485100Y469900D03*
X1487525Y480726D03*
X1478700Y533700D03*
X1500445Y619956D03*
X1549600Y-10800D03*
X1538520Y11911D03*
X1590431Y-6702D03*
X1544882Y-6900D03*
X1592829Y24460D03*
X1589623Y24528D03*
X1543500Y3400D03*
X1540000D03*
X1581947Y-6702D03*
X1545111Y24172D03*
X1580398Y-600D03*
Y5400D03*
X1571500Y-1406D03*
X1556200Y94800D03*
X1545572Y38188D03*
X1579100Y69000D03*
X1577269Y95344D03*
X1535300Y78490D03*
X1590949Y97850D03*
X1583374Y81319D03*
X1574780Y90992D03*
X1587359Y84348D03*
X1545250Y88360D03*
X1546370Y84180D03*
X1592715Y70817D03*
X1575018Y71213D03*
X1556810Y71760D03*
X1541413Y155259D03*
X1588176Y157600D03*
X1541765Y114000D03*
X1541421Y106742D03*
X1580275Y101041D03*
X1553500Y157000D03*
X1552171Y133000D03*
X1563108Y126423D03*
X1582500Y109900D03*
X1577700Y140149D03*
X1567520Y133354D03*
X1549000Y115571D03*
X1549187Y104713D03*
X1589200Y121800D03*
X1589622Y112876D03*
X1557981Y141470D03*
X1541390Y136498D03*
X1591950Y158250D03*
X1573153Y103721D03*
X1576606Y104392D03*
X1588500Y106788D03*
X1588000Y100500D03*
X1542685Y133321D03*
X1574197Y127915D03*
X1531726Y123800D03*
X1576506Y143416D03*
X1572395Y110754D03*
X1558100Y128926D03*
X1554627Y100877D03*
X1558136D03*
X1558100Y138025D03*
Y133526D03*
X1590569Y152464D03*
X1541434Y139871D03*
X1542000Y126246D03*
X1591800Y164900D03*
X1566486Y181270D03*
X1535065Y164300D03*
X1552051Y172053D03*
X1571501Y180031D03*
X1568488Y164058D03*
X1562150Y160700D03*
X1583874Y217746D03*
X1582249Y191716D03*
X1572817Y169910D03*
X1570294Y167384D03*
X1535425Y188016D03*
X1535000Y207200D03*
X1557979Y188844D03*
X1543100Y184128D03*
X1553500Y165400D03*
X1548178Y190880D03*
X1558000Y205100D03*
X1545023Y161675D03*
X1561925Y192675D03*
X1566858Y175192D03*
X1549693Y196707D03*
X1552063Y202031D03*
X1558042Y172448D03*
X1593218Y191776D03*
X1557787Y192236D03*
X1561538Y174649D03*
X1587549Y192000D03*
X1582699Y252646D03*
X1561104Y234255D03*
X1537972Y236000D03*
X1532237Y247801D03*
X1567000Y259560D03*
X1552900Y281700D03*
X1579867Y265445D03*
X1563157Y258164D03*
X1533596Y273504D03*
X1542751Y240477D03*
X1542690Y236050D03*
X1531935Y224160D03*
X1541325Y245090D03*
X1568120Y251710D03*
X1545802Y233529D03*
X1584568Y281339D03*
X1571876Y255800D03*
X1558700Y252000D03*
X1568365Y247761D03*
X1551404Y309376D03*
X1533228Y325000D03*
X1550619Y303087D03*
X1534400Y296029D03*
X1587800Y308200D03*
X1538450Y314300D03*
X1578790Y290920D03*
X1550800Y296200D03*
X1577486Y307621D03*
X1532850Y303950D03*
X1548024Y322145D03*
X1585479Y316610D03*
X1570574Y341776D03*
X1554932Y332171D03*
X1538406Y330157D03*
X1573950Y338050D03*
X1537500Y292800D03*
X1581834Y318591D03*
X1559800Y285300D03*
X1559500Y290300D03*
X1575645Y320664D03*
X1588551Y341410D03*
X1548334Y325497D03*
X1581940Y295820D03*
X1582800Y312100D03*
X1548273Y313227D03*
X1565000Y290500D03*
X1543864Y311399D03*
X1590212Y315425D03*
X1551250Y320303D03*
X1590176Y331844D03*
X1554775Y295328D03*
X1548100Y342200D03*
X1534833Y309798D03*
X1560500Y350000D03*
X1553825Y377514D03*
X1557534Y353400D03*
X1533589Y366361D03*
X1553825Y391034D03*
X1546025D03*
X1532367Y356530D03*
X1581822Y365770D03*
X1569584Y378002D03*
X1563575Y394414D03*
X1557725Y397794D03*
X1571375Y387654D03*
X1569425Y397794D03*
X1550639Y350200D03*
X1563575Y401174D03*
X1569425Y391034D03*
X1553825Y397794D03*
X1542300Y376717D03*
X1546025Y397794D03*
X1551875Y394414D03*
Y387654D03*
X1549950Y404490D03*
X1565525Y384274D03*
X1587684Y362653D03*
X1557725Y377514D03*
X1586500Y354900D03*
X1559675Y401174D03*
X1542125Y397794D03*
X1583208Y404941D03*
X1565525Y391034D03*
X1547975Y394414D03*
X1540175Y387654D03*
Y380894D03*
Y401174D03*
X1542932Y355740D03*
X1547975Y387654D03*
X1571450Y359650D03*
X1536275Y401174D03*
Y387654D03*
X1534325Y384274D03*
X1536275Y380894D03*
X1534325Y397794D03*
X1540175Y394414D03*
X1534325Y391034D03*
X1582600Y389300D03*
X1559675Y387654D03*
Y394414D03*
X1551875Y380894D03*
X1557725Y391034D03*
X1536275Y394414D03*
X1557725Y404554D03*
X1563575Y387654D03*
X1567475Y401174D03*
X1566922Y359681D03*
X1567121Y363217D03*
X1551875Y401174D03*
X1565525Y397794D03*
Y377514D03*
X1559675Y380894D03*
X1571375Y394414D03*
X1532375Y401174D03*
X1563575Y380894D03*
X1546182Y355446D03*
X1534325Y377514D03*
X1542125Y460446D03*
X1538225D03*
X1549925Y467206D03*
X1557725D03*
X1569425Y453686D03*
X1559675Y407934D03*
X1561625Y446926D03*
X1551875Y450306D03*
X1536275Y463826D03*
X1532375D03*
X1534325Y467206D03*
X1538225D03*
X1585560Y421324D03*
X1583773Y436137D03*
X1544075Y463826D03*
X1543850Y451400D03*
X1553825Y411314D03*
X1544150Y409900D03*
X1553825Y440166D03*
Y446926D03*
X1549926Y411312D03*
X1540175Y407934D03*
X1536275D03*
X1532375D03*
X1555775D03*
Y414694D03*
X1565525Y418074D03*
X1561625D03*
Y411314D03*
X1565525D03*
X1561625Y440166D03*
X1557725D03*
X1565525Y424834D03*
X1569425D03*
X1536300Y455200D03*
X1553825Y453686D03*
X1547000Y435650D03*
X1551875Y436786D03*
X1549925Y440166D03*
X1540653Y454588D03*
X1532349Y455200D03*
X1549925Y460446D03*
X1583208Y416752D03*
X1591350Y445300D03*
X1542125Y467206D03*
X1559595Y450631D03*
X1569425Y446926D03*
X1591430Y409440D03*
X1565525Y453686D03*
X1551875Y443546D03*
X1571375Y436786D03*
X1587573Y445300D03*
X1587550Y456550D03*
X1565525Y467206D03*
X1561625D03*
X1567475Y463826D03*
X1569425Y467206D03*
X1553825Y460446D03*
X1567475Y443546D03*
X1571375D03*
X1563575Y450306D03*
X1567475Y436786D03*
X1569425Y440166D03*
X1565525Y460446D03*
X1563575Y463826D03*
X1582300Y446100D03*
X1565525Y446926D03*
X1559675Y457066D03*
X1546025Y460446D03*
X1557725D03*
X1551875Y470586D03*
X1549925Y480726D03*
X1551875Y477346D03*
X1546025Y473966D03*
X1547975Y477346D03*
X1559675Y470586D03*
X1533595Y505530D03*
X1559675Y484106D03*
X1561625Y480726D03*
X1557725Y487486D03*
X1561625D03*
X1567475Y484106D03*
X1563575D03*
X1559675Y477346D03*
X1565525Y487486D03*
X1563575Y477346D03*
X1571375D03*
X1590580Y472370D03*
X1536275Y477346D03*
X1534325Y480726D03*
Y473966D03*
X1538225Y480726D03*
X1532375Y484106D03*
Y477346D03*
X1540175Y470586D03*
X1563575D03*
X1561625Y473966D03*
X1565525D03*
X1567475Y477346D03*
X1584970Y472370D03*
X1542125Y487486D03*
X1540175Y484106D03*
X1546025Y487486D03*
X1551875Y484106D03*
X1538225Y487486D03*
X1542125Y480726D03*
X1544075Y484106D03*
X1547975D03*
X1550990Y586588D03*
X1554358Y587258D03*
X1592934Y592396D03*
X1587610Y579550D03*
X1585155Y538574D03*
X1581730Y537170D03*
X1565389Y585721D03*
X1535565Y591658D03*
X1579900Y606050D03*
X1586700Y620100D03*
X1540477Y620308D03*
X1540700Y613700D03*
X1545407Y598393D03*
X1541384Y601262D03*
X1546075Y618145D03*
X1544050Y615296D03*
X1579680Y610279D03*
X1534968Y597268D03*
X1573500Y619500D03*
X1577000D03*
X1572950Y593950D03*
X1601650Y24160D03*
X1617500Y-14500D03*
X1597800Y24300D03*
X1637482Y21623D03*
X1653100Y11500D03*
X1638550Y7200D03*
X1623900Y4600D03*
X1598602Y3437D03*
X1599000Y61500D03*
X1596050Y75400D03*
X1632006Y94500D03*
X1640900Y66900D03*
X1630826Y88087D03*
X1614997Y84403D03*
X1625075Y80182D03*
X1597867Y93900D03*
X1597987Y79500D03*
X1619000Y38500D03*
X1606579Y86726D03*
X1614169Y95004D03*
X1617347Y94581D03*
X1599500Y75000D03*
X1649900Y78600D03*
X1653000Y77600D03*
X1643500Y80400D03*
X1635337Y73500D03*
X1604000Y93925D03*
X1627489Y74960D03*
X1632020Y97871D03*
X1632000Y73500D03*
X1628788Y97800D03*
X1621100Y69600D03*
X1620900Y81300D03*
X1593241Y134295D03*
X1598300Y116477D03*
X1598449Y120760D03*
X1600148Y142262D03*
X1604292Y150137D03*
X1596427Y157975D03*
X1600490Y158010D03*
X1604169Y156407D03*
X1600000Y104243D03*
X1616900Y143880D03*
X1653111Y102240D03*
X1648000Y100597D03*
X1594452Y111377D03*
X1600900Y131900D03*
X1608000Y99400D03*
X1607441Y106042D03*
X1635750Y128240D03*
X1642087Y143837D03*
X1637363Y149484D03*
X1593756Y129048D03*
X1642087Y153286D03*
X1632639Y124940D03*
X1647852Y197374D03*
X1651000Y178628D03*
X1603300Y185100D03*
X1600490Y167459D03*
X1627326Y182759D03*
X1654015Y217239D03*
X1615362Y213507D03*
X1622217Y177809D03*
X1650600Y186300D03*
X1648349Y182276D03*
X1645700Y214050D03*
X1602185Y180709D03*
X1635351Y185444D03*
X1608731Y180819D03*
X1598006Y192421D03*
X1595291Y166423D03*
X1644290Y196383D03*
X1648320Y172690D03*
X1635621Y208259D03*
X1643662Y172609D03*
X1601870Y270470D03*
X1643106Y233913D03*
X1600810Y266006D03*
X1636914Y270900D03*
X1596300Y250320D03*
X1627024Y253387D03*
X1631300Y280400D03*
X1637281Y260922D03*
X1597201Y238188D03*
X1643775Y246137D03*
X1637281Y254322D03*
X1617498Y273433D03*
X1632128Y225472D03*
X1637269Y264421D03*
X1622000Y279495D03*
X1627043Y256900D03*
X1636684Y283141D03*
X1610290Y265352D03*
X1638216Y246021D03*
X1604222Y268107D03*
X1608764Y322440D03*
X1608850Y343835D03*
X1638086Y319664D03*
X1625400Y327667D03*
X1602776Y331304D03*
X1652991Y321341D03*
X1620159Y332004D03*
X1638063Y326504D03*
X1631015Y328350D03*
X1635355Y324228D03*
X1639040Y316343D03*
X1625846Y286154D03*
X1609172Y339630D03*
X1636800Y287956D03*
X1602215Y363981D03*
X1610140Y358350D03*
X1609271Y348166D03*
X1621727Y395374D03*
X1612825Y405438D03*
X1622100Y400600D03*
X1630400Y391800D03*
X1629300Y385400D03*
X1630750Y404800D03*
X1613452Y387098D03*
X1638991Y352037D03*
X1621800Y381500D03*
Y386300D03*
X1595800Y405900D03*
X1639750Y445477D03*
X1630219Y446000D03*
X1621000Y440500D03*
X1621044Y433364D03*
X1621182Y427091D03*
X1603719Y412000D03*
X1611638Y454809D03*
X1612100Y446000D03*
X1646480Y443880D03*
X1611642Y461877D03*
X1630150Y427663D03*
X1593400Y432200D03*
X1639774Y439486D03*
X1623705Y467855D03*
X1639822Y453140D03*
X1647200Y430450D03*
X1640625Y429460D03*
X1621226Y445026D03*
X1615061Y463157D03*
X1596500Y455500D03*
X1617900Y409900D03*
X1595200Y412700D03*
X1651754Y488025D03*
X1626518Y528029D03*
X1627622Y524928D03*
X1631975Y527700D03*
X1597380Y495416D03*
X1600780D03*
X1617300Y519000D03*
X1625485Y494188D03*
X1623551Y525015D03*
X1621783Y498617D03*
X1620030Y525066D03*
X1645969Y514870D03*
X1617700Y475957D03*
X1614000Y475970D03*
X1639271Y491135D03*
X1639391Y513065D03*
X1629778Y507294D03*
X1642670Y514939D03*
X1629500Y491500D03*
X1649336Y511502D03*
X1641470Y506403D03*
X1644651Y505500D03*
X1649545Y515215D03*
X1601540Y588793D03*
X1622330Y592325D03*
X1594110Y611510D03*
X1619700Y617300D03*
X1617600Y619800D03*
X1680033Y-16711D03*
X1666500Y10500D03*
X1680034Y2863D03*
X1697300Y73296D03*
X1689250Y86000D03*
X1692300Y56900D03*
X1658600Y44700D03*
X1667000Y88000D03*
X1693900Y73300D03*
X1708610Y85121D03*
X1713900Y87900D03*
X1696870Y86093D03*
X1711000Y55525D03*
X1712600Y46100D03*
X1707268Y77668D03*
X1669000Y92000D03*
X1709184Y88811D03*
X1678627Y54616D03*
X1684248Y56746D03*
X1690500Y73950D03*
X1715100Y70500D03*
X1659000Y88000D03*
X1661900Y92400D03*
X1704824Y90049D03*
X1664500Y99000D03*
X1672200Y112200D03*
X1696907Y99077D03*
X1678400Y103000D03*
X1667348Y156500D03*
X1674800Y103100D03*
X1659643Y213505D03*
X1687550Y213751D03*
X1674912Y183000D03*
X1673530Y209974D03*
X1708350Y175050D03*
X1660800Y181900D03*
X1663400Y179475D03*
X1667140Y182300D03*
X1669849Y193067D03*
X1665063Y172608D03*
X1702400Y193450D03*
X1664321Y195244D03*
X1658082Y195298D03*
X1655978Y207827D03*
X1705666Y198055D03*
X1671688Y182925D03*
X1688046Y174447D03*
X1664390Y201163D03*
X1660440Y200789D03*
X1667356Y213096D03*
X1691439Y174354D03*
X1713000Y185000D03*
X1674019Y175990D03*
X1713596Y175795D03*
X1676750Y206050D03*
X1681116Y238614D03*
X1657500Y259700D03*
X1657567Y264600D03*
X1657498Y269700D03*
Y274700D03*
Y279900D03*
X1715837Y246178D03*
X1715078Y250231D03*
X1657494Y292816D03*
X1657498Y284900D03*
X1664453Y308557D03*
X1660972Y401447D03*
X1660834Y404934D03*
X1660890Y397300D03*
X1673074Y453185D03*
X1675120Y439731D03*
X1679145Y461950D03*
X1667588Y434149D03*
X1668100Y418700D03*
X1678303Y442765D03*
X1667946Y412987D03*
X1673550Y442696D03*
X1714530Y519900D03*
X1710594D03*
X1676800Y483800D03*
X1681650Y510673D03*
X1687606Y500938D03*
X1672265Y473600D03*
X1681115Y525218D03*
X1716490Y506970D03*
X1681500Y482000D03*
X1671050Y487000D03*
Y490850D03*
X1672159Y494042D03*
X1655790Y476593D03*
X1705767Y482434D03*
X1698354Y486873D03*
X1701617Y482706D03*
X1680133Y535489D03*
X1710389Y577787D03*
X1699600Y578100D03*
X1710000Y604500D03*
Y600000D03*
X1701291Y602268D03*
X1741544Y9151D03*
X1749085Y9177D03*
X1744900Y9100D03*
X1725474Y69250D03*
X1746328Y59011D03*
X1760016Y65774D03*
X1771707Y86500D03*
X1767250Y94500D03*
Y89500D03*
X1766333Y59116D03*
X1775000Y53500D03*
X1750400Y47400D03*
X1720100Y46100D03*
X1720500Y52440D03*
X1717014Y97550D03*
X1757998Y73637D03*
X1731350Y92140D03*
X1757772Y90174D03*
X1765015Y119100D03*
X1776828Y155211D03*
X1735989Y133250D03*
X1728789Y136250D03*
X1735989Y149050D03*
X1726539Y139450D03*
X1734989Y142750D03*
X1726464Y111150D03*
X1731789Y139450D03*
X1717014Y142650D03*
X1746189Y153250D03*
X1748425Y119190D03*
X1745768Y111743D03*
X1745363Y108004D03*
X1742214Y114300D03*
X1720164Y117451D03*
X1745364Y117450D03*
X1717014Y133200D03*
Y111150D03*
X1745500Y104500D03*
X1768886Y156173D03*
X1719000Y190500D03*
X1719080Y236152D03*
X1718820Y249032D03*
X1727896Y246175D03*
X1719080Y232852D03*
X1720651Y246141D03*
X1749462Y232955D03*
X1746900Y249804D03*
X1751900Y249700D03*
X1722251Y250532D03*
X1724181Y246159D03*
X1730996Y442804D03*
X1737150Y450850D03*
X1719089Y472104D03*
X1728700Y470200D03*
X1719560Y501770D03*
X1766100Y521124D03*
X1722347Y471811D03*
X1750800Y516100D03*
X1762715Y521085D03*
X1753807Y548183D03*
X1757478Y548192D03*
X1767529Y566200D03*
X1764300Y570900D03*
X1742200Y552863D03*
X1724899Y584748D03*
X1733000Y557000D03*
X1767141Y555500D03*
X1756578Y586743D03*
X1724250Y588250D03*
X1743000Y574500D03*
X1730759Y548162D03*
X1722500Y562000D03*
X1754897Y578750D03*
X1742381Y588530D03*
X1767500Y559800D03*
X1738498Y554255D03*
X1750399Y603201D03*
X1739714Y604967D03*
X1716950Y603450D03*
X1735000Y621002D03*
X1764823Y613600D03*
X1725133Y614896D03*
X1766400Y599400D03*
X1770600Y600800D03*
X1764912Y618718D03*
X1728341Y614851D03*
X1819800Y2100D03*
X1813913Y2287D03*
X1799462Y8830D03*
X1804462D03*
X1790078Y11860D03*
X1795078Y11900D03*
X1792700Y36871D03*
X1797700Y36804D03*
X1831000Y-16300D03*
X1828874Y-13520D03*
X1815150Y26650D03*
X1779750Y36530D03*
X1791500Y26918D03*
X1808100Y21800D03*
X1813795Y12165D03*
X1819837Y21700D03*
X1786865Y22375D03*
X1823600Y8800D03*
X1797700Y21018D03*
X1837500Y35700D03*
X1838850Y13160D03*
X1836700Y-18900D03*
X1804800Y-1500D03*
X1816723Y9781D03*
X1826414Y35486D03*
X1835600Y3900D03*
X1824240Y83680D03*
X1802119Y56581D03*
X1799438Y44328D03*
X1827000Y94550D03*
X1827150Y97800D03*
X1827100Y81600D03*
X1798454Y82256D03*
X1788216Y59197D03*
X1821350Y98270D03*
X1803300Y39900D03*
X1808363Y40033D03*
X1812352Y36949D03*
X1838500Y40400D03*
X1820457Y39128D03*
X1829580Y38620D03*
X1810100Y114700D03*
X1808226Y136171D03*
X1803509Y128500D03*
X1807818Y124179D03*
X1813118Y127976D03*
X1815026Y121478D03*
X1788000Y129000D03*
X1815883Y133277D03*
X1808313Y111705D03*
X1807509Y128500D03*
X1814900Y116900D03*
X1783252Y109044D03*
X1796500Y120000D03*
X1815348Y143437D03*
X1803058Y143733D03*
X1830316Y102163D03*
X1827500Y144900D03*
X1837090Y149830D03*
X1839667Y151994D03*
X1809810Y155858D03*
X1800792Y122691D03*
X1824990Y103620D03*
X1787373Y120188D03*
X1816418Y127976D03*
X1807166Y147401D03*
X1800420Y148240D03*
X1821261Y170012D03*
X1824200Y176900D03*
X1830415Y196567D03*
X1785500Y164000D03*
X1836100Y179700D03*
X1836900Y165800D03*
X1787000Y175500D03*
X1778900Y165800D03*
X1834103Y176021D03*
X1833629Y170807D03*
X1836932Y170486D03*
X1816125Y169492D03*
X1834400Y216900D03*
X1785500Y168000D03*
X1822877Y235852D03*
X1826085Y236034D03*
X1822638Y232106D03*
X1826662Y232191D03*
X1784440Y232938D03*
X1804388Y249904D03*
X1831700Y252272D03*
X1837857Y468630D03*
X1834100Y523900D03*
X1814852Y519901D03*
X1810350Y525650D03*
X1809700Y506875D03*
X1820400Y501100D03*
X1837200Y525700D03*
X1813500Y526500D03*
X1816584Y530542D03*
X1810200Y513300D03*
X1837300Y472276D03*
X1825900Y523500D03*
X1815200Y501500D03*
X1794100Y521900D03*
X1798250Y529200D03*
X1803900Y491500D03*
X1795200Y525700D03*
X1836600Y521600D03*
X1831600Y529000D03*
X1833700Y497300D03*
X1781300Y537800D03*
X1837475Y573835D03*
X1829051Y591299D03*
X1809600Y582800D03*
X1793660Y560570D03*
X1811100Y586800D03*
X1816458Y587480D03*
X1829300Y572900D03*
X1793100Y578500D03*
X1816020Y571448D03*
X1812802Y578693D03*
X1780394Y561076D03*
X1837534Y579322D03*
X1792805Y574675D03*
X1832500Y539500D03*
X1829000Y536315D03*
X1832200Y567760D03*
X1791349Y589122D03*
X1788300Y585100D03*
X1810863Y560637D03*
X1816175Y567669D03*
X1838224Y586650D03*
X1783700Y576400D03*
X1785050Y584550D03*
X1792100Y566900D03*
X1816330Y545260D03*
X1816100Y576200D03*
X1829176Y584287D03*
X1809309Y555713D03*
X1839126Y583354D03*
X1831500Y544500D03*
Y548000D03*
X1831800Y552300D03*
X1837000Y534900D03*
X1782300Y555900D03*
X1778675Y592224D03*
X1794500Y612500D03*
X1791500Y606500D03*
X1782700Y610900D03*
X1795000Y599600D03*
X1791323Y594030D03*
X1805000Y606500D03*
X1787500Y600500D03*
X1784200Y593924D03*
X1900256Y-14760D03*
X1841060Y35540D03*
X1882999Y7383D03*
X1883041Y15814D03*
X1893094Y-12642D03*
X1876792Y18461D03*
X1876881Y22181D03*
X1878000Y73950D03*
X1843107Y97988D03*
X1848208Y49427D03*
X1889218Y51030D03*
Y46030D03*
Y61030D03*
Y56030D03*
X1842250Y84000D03*
X1858600Y74300D03*
X1849426Y90700D03*
Y95500D03*
X1883200Y76600D03*
X1850600Y41348D03*
X1875600Y156300D03*
X1857110Y113600D03*
X1881324Y153250D03*
X1890974Y105600D03*
X1898102Y107325D03*
X1885700Y141200D03*
X1897536Y114600D03*
Y120510D03*
X1887497Y105444D03*
X1878753Y139893D03*
X1867280Y135406D03*
X1881165Y105561D03*
X1885102Y101134D03*
X1866606Y109967D03*
X1857849Y148079D03*
X1872254Y138618D03*
X1872400Y144619D03*
X1871521Y153593D03*
X1888639Y147042D03*
X1893640D03*
X1894855Y142122D03*
X1899855D03*
X1861932Y146431D03*
X1857919Y156123D03*
X1869668Y146750D03*
X1864904Y114735D03*
X1895060Y136099D03*
X1897507Y124450D03*
X1895673Y151800D03*
X1868843Y207920D03*
X1874236Y213800D03*
X1893238Y208042D03*
X1863650Y189750D03*
X1877880Y203780D03*
X1847200Y202050D03*
X1884340Y217866D03*
X1840900Y179700D03*
X1845700D03*
X1896710Y194380D03*
X1882452Y195888D03*
X1901100Y194200D03*
X1889400Y191200D03*
X1886200Y161000D03*
X1875700Y184800D03*
X1864637Y201861D03*
X1876700Y207600D03*
X1872100Y207900D03*
X1861243Y183100D03*
X1862000Y177500D03*
X1884000Y188100D03*
X1884400Y183700D03*
X1858686Y180377D03*
X1858500Y200100D03*
X1864000Y184900D03*
X1878789Y213663D03*
X1891880Y204370D03*
X1856874Y219443D03*
X1864464Y198466D03*
X1885465Y166285D03*
X1855000Y167100D03*
X1850723Y219250D03*
X1865100Y174600D03*
X1877517Y217988D03*
X1840149Y244425D03*
X1843449D03*
X1899816Y235035D03*
X1844444Y224035D03*
X1854374Y248790D03*
X1854720Y253700D03*
X1846517Y253500D03*
X1850220D03*
X1896529Y235080D03*
X1892274D03*
X1842857Y468630D03*
X1878100Y450200D03*
X1868167Y467855D03*
X1863137Y452710D03*
X1859059Y448076D03*
X1858633Y452803D03*
X1901574Y454422D03*
X1875900Y453600D03*
X1867500Y447900D03*
X1859530Y516430D03*
X1842400Y516800D03*
X1841900Y498800D03*
X1900890Y477200D03*
X1864339Y509560D03*
X1863000Y480000D03*
X1859600Y476200D03*
X1852719Y487575D03*
Y492575D03*
X1876945Y471316D03*
X1877407Y479046D03*
X1857450Y473654D03*
X1855206Y471112D03*
X1847000Y487500D03*
X1860000Y495500D03*
X1842764Y528136D03*
X1869914Y517225D03*
X1866688Y517128D03*
X1870100Y561150D03*
X1844018Y586482D03*
X1868200Y590939D03*
X1858528Y544528D03*
X1875850Y567200D03*
X1840690Y557190D03*
X1878500Y553500D03*
X1858500Y540000D03*
X1852250Y547900D03*
X1858681Y568087D03*
X1879862Y581862D03*
X1896899Y557790D03*
X1900729Y569557D03*
X1864580Y537060D03*
X1878736Y533040D03*
X1868110Y536000D03*
X1845407Y533178D03*
X1900250Y533700D03*
X1856573Y576534D03*
X1895523Y586365D03*
X1857812Y557245D03*
X1866800Y588000D03*
X1869800Y557100D03*
X1878875Y565475D03*
X1847070Y537610D03*
X1882300Y565550D03*
X1885100Y584300D03*
X1848900Y590750D03*
X1845000Y590800D03*
X1873510Y541710D03*
X1875600Y588500D03*
X1840700Y563800D03*
X1854530Y533132D03*
X1896358Y595255D03*
X1916078Y-16368D03*
X1918352Y89300D03*
X1923300Y94300D03*
X1920300Y68300D03*
X1917600Y66000D03*
X1948472Y80362D03*
X1933914Y96040D03*
X1946500Y104974D03*
X1940700Y136300D03*
X1908327Y149353D03*
X1904215Y142812D03*
X1909216D03*
X1943752Y137548D03*
X1947078Y139300D03*
X1963400Y141100D03*
X1921264Y153000D03*
X1937900Y153600D03*
X1923800Y151000D03*
X1927000Y152200D03*
X1934544Y127957D03*
X1929000Y158600D03*
X1926952Y156049D03*
X1952726Y102950D03*
X1914500Y113300D03*
X1940500Y157600D03*
X1932998Y119438D03*
X1923329Y99475D03*
X1947000Y142600D03*
X1923837Y118800D03*
X1937728Y99441D03*
X1925358Y140685D03*
X1903150Y217250D03*
X1910123Y217349D03*
X1957334Y201269D03*
X1939300Y204300D03*
X1917568Y201215D03*
X1917024Y193600D03*
X1929700Y163400D03*
X1921500Y193600D03*
X1940240Y169970D03*
X1939550Y165600D03*
X1931483Y199350D03*
X1940647Y161600D03*
X1909438Y204307D03*
X1904042Y204895D03*
X1903917Y201472D03*
X1925400Y196300D03*
X1929090Y193190D03*
X1939400Y198400D03*
X1934100Y193400D03*
X1935600Y176300D03*
X1932837Y186700D03*
X1925000Y192000D03*
X1918489Y212513D03*
X1943500Y209500D03*
X1930500Y209464D03*
X1918143Y219848D03*
X1927064Y207564D03*
X1938400Y178200D03*
X1939200Y194300D03*
X1935600Y198700D03*
X1950981Y191218D03*
X1963300Y191000D03*
X1952717Y198614D03*
X1943217Y221154D03*
Y217645D03*
X1942000Y440500D03*
X1937430Y464785D03*
X1904724Y447930D03*
X1939845Y445055D03*
X1947550Y485350D03*
X1956500Y507470D03*
X1938300Y486250D03*
X1957250Y512050D03*
X1937300Y508900D03*
X1919230Y483430D03*
X1919000Y487210D03*
X1919510Y475100D03*
Y479200D03*
X1939000Y476600D03*
X1956606Y526671D03*
X1957212Y479521D03*
X1957063Y474769D03*
X1945000Y474000D03*
X1948200Y474300D03*
X1928620Y482710D03*
X1956300Y515900D03*
X1959300Y518000D03*
X1908300Y514500D03*
X1942328Y508712D03*
X1963000Y573000D03*
X1921244Y533750D03*
X1951900Y534900D03*
X1963097Y551000D03*
X1934200Y573700D03*
X1935400Y583000D03*
X1940800Y537300D03*
X1945900Y549900D03*
X1923500Y579500D03*
X1948100Y538700D03*
X1923400Y583000D03*
X1923600Y575500D03*
X1926600Y559500D03*
X1923600Y565100D03*
X1923000Y568700D03*
X1959120Y547050D03*
X1958940Y538890D03*
X1961715Y555639D03*
X1918880Y586460D03*
X1961771Y591744D03*
X1962950Y566600D03*
X1956191Y548700D03*
X1962500Y578500D03*
X1958500Y535000D03*
X1907500Y545600D03*
X1907200Y551600D03*
X1932390Y590100D03*
X1959400Y601100D03*
X1934350Y609250D03*
X1923504Y592500D03*
X1911750Y592800D03*
X1927000Y614500D03*
X1914700Y594600D03*
X1963300Y612800D03*
X1938130Y601480D03*
X1967580Y104721D03*
X1972598Y165236D03*
X1967200Y521600D03*
X1964270Y511410D03*
X1968375Y509375D03*
X1972700Y576400D03*
Y549950D03*
X1964890Y534940D03*
X1965400Y619500D03*
X1456000Y360700D03*
X1460400Y353000D03*
X1459111Y356353D03*
X1467597Y363000D03*
X1463870Y367869D03*
X1453900Y353350D03*
X1453251Y356676D03*
X1552500Y358500D03*
X1550417Y362607D03*
G54D77*
X1854501Y195587D03*
X1859854Y501441D03*
X1952756Y589960D03*
X1944882Y582086D03*
X1952756D03*
X1944882Y574212D03*
X1952756D03*
X1944882Y566338D03*
X1952756D03*
X1944882Y558464D03*
Y589960D03*
X1952756Y558464D03*
X1944882Y605708D03*
X1952756D03*
X1944882Y597834D03*
X1952756D03*
G54D71*
X1638131Y475946D03*
G54D60*
X-4488Y425472D03*
X99980Y136909D03*
X1472000Y-5000D03*
Y-15000D03*
X1462000Y-5000D03*
Y-15000D03*
X1452000Y-5000D03*
Y-15000D03*
X1442000Y-5000D03*
Y-15000D03*
X1525000D03*
X1515000D03*
X1505000D03*
X1482000D03*
X1492000Y-5000D03*
Y-15000D03*
X1482000Y-5000D03*
X1575000Y-15000D03*
X1565000D03*
X1555000D03*
X1545000D03*
X1535000D03*
X1713503Y-5000D03*
Y-15000D03*
X1703503Y-5000D03*
Y-15000D03*
X1743503D03*
X1733503Y-5000D03*
Y-15000D03*
X1743503Y-5000D03*
X1779504D03*
X1769504D03*
Y-15000D03*
X1809504D03*
X1799504Y-5000D03*
Y-15000D03*
X1789504Y-5000D03*
Y-15000D03*
X1819504Y-5000D03*
Y-15000D03*
X1809504Y-5000D03*
G54D38*
X40500Y-42250D03*
Y-52250D03*
X60500Y-42250D03*
X80500D03*
X100500D03*
X60500Y-52250D03*
X80500D03*
X100500D03*
X120500Y-42250D03*
X140500D03*
X120500Y-52250D03*
X140500D03*
X467246Y-52301D03*
Y-42301D03*
X487246Y-52301D03*
Y-42301D03*
X507246Y-52301D03*
Y-42301D03*
X527246Y-52301D03*
Y-42301D03*
X547246Y-52301D03*
Y-42301D03*
X567246Y-52301D03*
Y-42301D03*
X798984Y-52057D03*
Y-42057D03*
X818984Y-52057D03*
Y-42057D03*
X838984Y-52057D03*
Y-42057D03*
X858984Y-52057D03*
Y-42057D03*
X878984Y-52057D03*
Y-42057D03*
X898984Y-52057D03*
Y-42057D03*
X1135583Y-52285D03*
Y-42285D03*
X1155583Y-52285D03*
Y-42285D03*
X1392258Y-52257D03*
Y-42257D03*
X1412258Y-52257D03*
Y-42257D03*
X1432258Y-52257D03*
Y-42257D03*
X1452258Y-52257D03*
Y-42257D03*
G54D80*
X1922248Y518328D03*
G54D75*
X1724807Y451179D03*
X1851250Y584622D03*
Y576748D03*
Y568874D03*
G54D73*
X1674921Y528523D03*
X1773347D03*
Y545059D03*
G54D65*
X638541Y171945D03*
Y454425D03*
X752641Y159945D03*
X1288068Y171945D03*
Y454425D03*
X1402168Y159945D03*
Y442425D03*
G54D57*
X40512Y458744D03*
G54D51*
X-15748Y116969D03*
Y132717D03*
X787D03*
X28740Y124843D03*
Y140591D03*
G54D43*
X60512Y467244D03*
G54D59*
X30512D03*
X40512D03*
G54D76*
X1809665Y618663D03*
X1819665D03*
X1829665D03*
G54D62*
X63093Y202300D03*
X72936D03*
X82779D03*
X1914911Y495775D03*
X1934597D03*
X1924754D03*
G54D53*
X-14488Y434094D03*
X-4488D03*
X5512D03*
X15512D03*
X89980Y145531D03*
X99980D03*
X109980D03*
X119980D03*
G54D67*
X1401516Y23976D03*
G54D49*
X1753503Y-15000D03*
Y-5000D03*
X1723503Y-15000D03*
Y-5000D03*
G54D46*
X1466694Y375787D03*
G54D48*
X1705772Y567874D03*
G54D61*
X94683Y31978D03*
Y13078D03*
Y69778D03*
Y50878D03*
Y532955D03*
Y514079D03*
Y570755D03*
Y589679D03*
Y551879D03*
Y608555D03*
X637793Y-5822D03*
Y13078D03*
Y69778D03*
Y50878D03*
Y88678D03*
Y532955D03*
Y514079D03*
Y570755D03*
Y589679D03*
Y551879D03*
Y608555D03*
X744293Y-5822D03*
Y31978D03*
Y13078D03*
Y69778D03*
Y88678D03*
Y50878D03*
Y532955D03*
Y514079D03*
Y570755D03*
Y589679D03*
Y551879D03*
Y608555D03*
X1287403Y-5822D03*
Y31978D03*
Y13078D03*
Y69778D03*
Y88678D03*
Y50878D03*
Y532955D03*
Y514079D03*
Y551879D03*
Y608555D03*
G54D52*
X-7874Y216181D03*
Y325315D03*
G54D50*
X0Y0D03*
G54D56*
X18228Y178386D03*
X-1969D03*
X44291D03*
G54D41*
X1866923Y235400D03*
G54D37*
X-3937Y-43307D03*
X1956693D03*
X-13780Y598560D03*
X-3937Y646063D03*
X1956693D03*
G54D47*
X1611283Y615236D03*
G54D40*
X1955506Y454297D03*
X1699600D03*
Y235400D03*
G54D44*
X133563Y183126D03*
Y419626D03*
X783171Y183126D03*
Y419626D03*
G54D45*
X1454685Y338189D03*
X1600355Y527165D03*
G54D70*
X1613069Y302692D03*
G54D64*
X224410Y301378D03*
X326772Y163582D03*
Y439173D03*
X500000Y163582D03*
Y439173D03*
X602362Y214764D03*
Y387992D03*
X874016Y301378D03*
X976378Y163582D03*
Y439173D03*
X1149606Y163582D03*
Y439173D03*
X1251969Y214764D03*
Y387992D03*
%LPD*%
G75*
G36*
G01X13800Y269464D02*
Y336848D01*
X16232Y339280D01*
X38761D01*
X39734Y338307D01*
Y275251D01*
X39717Y275212D01*
G03Y274082I1283J-565D01*
G01X39734Y274043D01*
Y265954D01*
X39717Y265915D01*
G03Y264785I1283J-565D01*
G01X39734Y264746D01*
Y199495D01*
X37239Y197000D01*
X13236D01*
X12100Y198136D01*
Y232636D01*
X12098Y232638D01*
Y232723D01*
X9032Y235790D01*
Y264669D01*
X13796Y269435D01*
Y269460D01*
X13800Y269464D01*
G37*
G36*
G01X53036Y223300D02*
X51800Y224536D01*
Y258964D01*
X59936Y267100D01*
X72864D01*
X75000Y264964D01*
Y224636D01*
X73664Y223300D01*
X53036D01*
G37*
G36*
G01X317491Y64490D02*
X315990Y65991D01*
Y72535D01*
G02X316684Y72806I400J0D01*
G03Y74708I1030J951D01*
G02X315990Y74979I-294J271D01*
G01Y83492D01*
G02X316684Y83763I400J0D01*
G03Y85665I1030J951D01*
G02X315990Y85936I-294J271D01*
G01Y90509D01*
X319981Y94500D01*
X320830D01*
Y94148D01*
X320684Y94107D01*
G03X321996Y93802I378J-1350D01*
G02X322262Y94500I267J298D01*
G01X333246D01*
G02X333512Y93802I-1J-400D01*
G03X335382I935J-1045D01*
G02X335648Y94500I267J298D01*
G01X339939D01*
G02X340205Y93802I-1J-400D01*
G03X342075I935J-1045D01*
G02X342341Y94500I267J298D01*
G01X353214D01*
G02X353480Y93802I-1J-400D01*
G03X355350I935J-1045D01*
G02X355616Y94500I267J298D01*
G01X357999D01*
X359950Y92549D01*
Y65441D01*
X358999Y64490D01*
X356067D01*
G02X355725Y65097I0J400D01*
G03X353325I-1200J725D01*
G02X352983Y64490I-342J-207D01*
G01X352721D01*
G02X352379Y65097I0J400D01*
G03X349979I-1200J725D01*
G02X349637Y64490I-342J-207D01*
G01X346028D01*
G02X345686Y65097I0J400D01*
G03X343286I-1200J725D01*
G02X342944Y64490I-342J-207D01*
G01X342682D01*
G02X342340Y65097I0J400D01*
G03X339940I-1200J725D01*
G02X339598Y64490I-342J-207D01*
G01X335993D01*
G02X335650Y65095I0J400D01*
G03X333242I-1204J719D01*
G02X332899Y64490I-343J-205D01*
G01X332647D01*
G02X332304Y65095I0J400D01*
G03X329896I-1204J719D01*
G02X329553Y64490I-343J-205D01*
G01X325954D01*
G02X325611Y65095I0J400D01*
G03X323203I-1204J719D01*
G02X322860Y64490I-343J-205D01*
G01X322608D01*
G02X322265Y65095I0J400D01*
G03X319857I-1204J719D01*
G02X319514Y64490I-343J-205D01*
G01X317491D01*
G37*
G36*
G01X322440Y508436D02*
X316826Y514050D01*
Y533590D01*
X322536Y539300D01*
X357229D01*
X359934Y536595D01*
Y509800D01*
X358570Y508436D01*
X345756D01*
G02X345474Y509120I0J400D01*
G03X343498I-988J994D01*
G02X343216Y508436I-282J-284D01*
G01X339169D01*
G02X338864Y509094I0J400D01*
G03X336722I-1071J905D01*
G02X336417Y508436I-305J-258D01*
G01X325783D01*
G02X325478Y509094I0J400D01*
G03X323336I-1071J905D01*
G02X323031Y508436I-305J-258D01*
G01X322440D01*
G37*
G36*
G01X396481Y63500D02*
X391788Y68192D01*
Y72228D01*
G03X391490Y73664I-3601J2D01*
G01Y84792D01*
G03X391788Y86228I-3303J1434D01*
G01Y91128D01*
G03X391490Y92564I-3601J2D01*
G01Y98519D01*
X400481Y107510D01*
X429499D01*
X444971Y92038D01*
G02X444730Y91358I-283J-282D01*
G03X446274Y89814I150J-1394D01*
G02X446954Y90055I398J-42D01*
G01X447302Y89707D01*
X447313Y89646D01*
G03X448000Y88681I1379J254D01*
G01Y86558D01*
G03Y84034I610J-1262D01*
G01Y74857D01*
G03X447688Y72523I599J-1268D01*
G02X447699Y71926I-260J-303D01*
G03X448000Y69654I952J-1030D01*
G01Y69344D01*
G03Y66836I627J-1254D01*
G01Y66001D01*
X445499Y63500D01*
X396481D01*
G37*
G36*
G01X432016Y496760D02*
X420982Y507781D01*
G03X420452Y508000I-530J-532D01*
G01X393576D01*
X392683Y508892D01*
Y537872D01*
X393721Y538910D01*
X445974D01*
X446320Y538564D01*
Y538430D01*
G02X445690Y538103I-400J0D01*
G03Y535811I-808J-1146D01*
G02X446320Y535484I230J-327D01*
G01Y516836D01*
G02X445689Y516509I-400J0D01*
G03Y514219I-809J-1145D01*
G02X446320Y513892I231J-327D01*
G01Y511586D01*
G02X445689Y511259I-400J0D01*
G03X445965Y509226I-809J-1145D01*
G01X446025Y509300D01*
X446320D01*
Y508926D01*
X445176Y507781D01*
X437160Y499756D01*
G02X436503Y499897I-283J282D01*
G03X434697Y498088I-1311J-497D01*
G02X434839Y497431I-141J-374D01*
G01X434168Y496760D01*
X432016D01*
G37*
G36*
G01X1006100Y93011D02*
Y92793D01*
X1006096Y92774D01*
G03X1008206Y91138I1477J-274D01*
G01X1008332Y91197D01*
X1009520Y90009D01*
Y65511D01*
X1008999Y64990D01*
X1005882D01*
G02X1005494Y65486I0J400D01*
G03X1002772I-1361J336D01*
G02X1002384Y64990I-388J-96D01*
G01X1002059D01*
Y65231D01*
X1002075Y65269D01*
G03X999426Y65486I-1288J553D01*
G02X999038Y64990I-388J-96D01*
G01X995843D01*
G02X995455Y65486I0J400D01*
G03X992733I-1361J336D01*
G02X992345Y64990I-388J-96D01*
G01X992020D01*
Y65231D01*
X992036Y65269D01*
G03X989387Y65486I-1288J553D01*
G02X988999Y64990I-388J-96D01*
G01X985805D01*
G02X985417Y65484I1J400D01*
G03X982691I-1363J330D01*
G02X982303Y64990I-389J-94D01*
G01X981983D01*
Y65231D01*
X981999Y65268D01*
G03X979345Y65484I-1291J546D01*
G02X978957Y64990I-389J-94D01*
G01X975766D01*
G02X975378Y65484I1J400D01*
G03X972652I-1363J330D01*
G02X972264Y64990I-389J-94D01*
G01X971944D01*
Y65231D01*
X971960Y65268D01*
G03X969529Y66630I-1291J546D01*
G02X968921Y66580I-325J233D01*
G01X966990Y68511D01*
Y71956D01*
G02X967375Y72356I400J0D01*
G03Y75158I-53J1401D01*
G02X966990Y75558I15J400D01*
G01Y82913D01*
G02X967375Y83313I400J0D01*
G03Y86115I-53J1401D01*
G02X966990Y86515I15J400D01*
G01Y88063D01*
G02X967376Y88463I400J0D01*
G03X968733Y90478I-54J1501D01*
G01X968690Y90597D01*
X969765Y91673D01*
X969901Y91584D01*
G03X972066Y92643I768J1173D01*
G02X972465Y93011I399J-32D01*
G01X982259D01*
G02X982658Y92643I0J-400D01*
G03X985452I1397J114D01*
G02X985851Y93011I399J-32D01*
G01X988952D01*
G02X989351Y92643I0J-400D01*
G03X992145I1397J114D01*
G02X992544Y93011I399J-32D01*
G01X1002227D01*
G02X1002626Y92643I0J-400D01*
G03X1005420I1397J114D01*
G02X1005819Y93011I399J-32D01*
G01X1006100D01*
G37*
G36*
G01X972050Y508436D02*
X966436Y514050D01*
Y533590D01*
X971176Y538330D01*
X972498D01*
G02X972835Y537714I0J-400D01*
G03X975195I1180J-757D01*
G02X975532Y538330I337J216D01*
G01X975845D01*
G02X976182Y537714I0J-400D01*
G03X978542I1180J-757D01*
G02X978879Y538330I337J216D01*
G01X982538D01*
G02X982875Y537714I0J-400D01*
G03X985235I1180J-757D01*
G02X985572Y538330I337J216D01*
G01X985884D01*
G02X986221Y537714I0J-400D01*
G03X988581I1180J-757D01*
G02X988918Y538330I337J216D01*
G01X992577D01*
G02X992914Y537714I0J-400D01*
G03X995274I1180J-757D01*
G02X995611Y538330I337J216D01*
G01X995924D01*
G02X996261Y537714I0J-400D01*
G03X998621I1180J-757D01*
G02X998958Y538330I337J216D01*
G01X1002617D01*
G02X1002954Y537714I0J-400D01*
G03X1005314I1180J-757D01*
G02X1005651Y538330I337J216D01*
G01X1007809D01*
X1009544Y536595D01*
Y514655D01*
X1008029Y513140D01*
X1006389D01*
X1005985Y512736D01*
G02X1005306Y512969I-282J283D01*
G03X1003738Y511401I-1391J-177D01*
G02X1003971Y510722I-50J-397D01*
G01X1001685Y508436D01*
X995364D01*
G02X995082Y509120I0J400D01*
G03X993106I-988J994D01*
G02X992824Y508436I-282J-284D01*
G01X988777D01*
G02X988472Y509094I0J400D01*
G03X986330I-1071J905D01*
G02X986025Y508436I-305J-258D01*
G01X975391D01*
G02X975086Y509094I0J400D01*
G03X972944I-1071J905D01*
G02X972639Y508436I-305J-258D01*
G01X972050D01*
G37*
G36*
G01X1093522Y90996D02*
X1093406Y90856D01*
G03X1095380Y88883I1082J-891D01*
G01X1095521Y88998D01*
X1097010Y87510D01*
Y86009D01*
X1096986Y85965D01*
G03Y84627I1232J-669D01*
G01X1097010Y84583D01*
Y74319D01*
G03Y72859I1197J-730D01*
G01Y71534D01*
X1096991Y71494D01*
G03Y70298I1268J-598D01*
G01X1097010Y70258D01*
Y68774D01*
X1096988Y68731D01*
G03Y67449I1247J-641D01*
G01X1097010Y67406D01*
Y66995D01*
X1096375Y66360D01*
G02X1095736Y66460I-283J283D01*
G03X1093087Y65875I-1248J-638D01*
G02X1092687Y65490I-400J15D01*
G01X1089598D01*
G02X1089198Y65875I0J400D01*
G03X1086396I-1401J-53D01*
G02X1085996Y65490I-400J15D01*
G01X1082902D01*
G02X1082503Y65872I0J400D01*
G03X1079701I-1401J-65D01*
G02X1079302Y65490I-399J18D01*
G01X1076209D01*
G02X1075810Y65872I0J400D01*
G03X1073011Y65705I-1401J-65D01*
G01Y65490D01*
X1072461D01*
Y65706D01*
G03X1069663Y65875I-1397J117D01*
G02X1069263Y65490I-400J15D01*
G01X1066172D01*
G02X1065772Y65875I0J400D01*
G03X1062970I-1401J-53D01*
G02X1062570Y65490I-400J15D01*
G01X1059477D01*
G02X1059078Y65872I0J400D01*
G03X1056279Y65705I-1401J-65D01*
G01Y65490D01*
X1055728D01*
Y65706D01*
G03X1052930Y65875I-1397J117D01*
G02X1052530Y65490I-400J15D01*
G01X1049285D01*
X1049040Y65735D01*
X1049039Y65817D01*
G03X1047867Y67190I-1402J-10D01*
G01X1047700Y67218D01*
Y71951D01*
X1046960Y72691D01*
Y75011D01*
X1045470Y76501D01*
Y86635D01*
G03Y88149I-1180J757D01*
G01Y90999D01*
X1047260Y92790D01*
G03X1047480Y93320I-530J531D01*
G01Y103005D01*
X1050983Y106510D01*
X1077995D01*
X1093522Y90996D01*
G37*
G36*
G01X1081626Y496760D02*
X1070592Y507781D01*
G03X1070062Y508000I-530J-532D01*
G01X1043186D01*
X1042293Y508892D01*
Y537222D01*
X1042614Y537543D01*
X1042825Y537332D01*
X1042812Y537235D01*
G03X1045388Y537806I1391J-177D01*
G02X1045727Y538420I338J214D01*
G01X1049530D01*
G02X1049853Y537784I0J-400D01*
G03X1052117I1132J-827D01*
G02X1052440Y538420I323J236D01*
G01X1052876D01*
G02X1053199Y537784I0J-400D01*
G03X1055463I1132J-827D01*
G02X1055786Y538420I323J236D01*
G01X1059569D01*
G02X1059892Y537784I0J-400D01*
G03X1062156I1132J-827D01*
G02X1062479Y538420I323J236D01*
G01X1062916D01*
G02X1063239Y537784I0J-400D01*
G03X1065503I1132J-827D01*
G02X1065826Y538420I323J236D01*
G01X1076302D01*
G02X1076625Y537784I0J-400D01*
G03X1078889I1132J-827D01*
G02X1079212Y538420I323J236D01*
G01X1082995D01*
G02X1083318Y537784I0J-400D01*
G03X1085582I1132J-827D01*
G02X1085905Y538420I323J236D01*
G01X1086342D01*
G02X1086665Y537784I0J-400D01*
G03X1088929I1132J-827D01*
G02X1089252Y538420I323J236D01*
G01X1093035D01*
G02X1093358Y537784I0J-400D01*
G03X1095299Y535812I1132J-827D01*
G02X1095930Y535485I231J-327D01*
G01Y516834D01*
G02X1095299Y516508I-400J0D01*
G03Y514220I-811J-1144D01*
G02X1095930Y513894I231J-326D01*
G01Y511584D01*
G02X1095299Y511258I-400J0D01*
G03X1095575Y509229I-811J-1144D01*
G01X1095635Y509302D01*
X1095930D01*
Y508926D01*
X1094786Y507781D01*
X1086769Y499754D01*
G02X1086112Y499895I-283J283D01*
G03X1084306Y498088I-1312J-495D01*
G02X1084448Y497431I-141J-374D01*
G01X1083778Y496760D01*
X1081626D01*
G37*
G36*
G01X1443529Y267984D02*
G03X1442983Y268529I-1225J-682D01*
G02Y269228I195J349D01*
G03X1442985Y271679I-680J1226D01*
G02Y272378I195J350D01*
G03X1443529Y272922I-681J1225D01*
G02X1444229I350J-194D01*
G03X1446135Y274828I1225J681D01*
G02Y275528I194J350D01*
G03X1446679Y276071I-680J1226D01*
G02X1447378I349J-194D01*
G03X1449285Y277978I1225J682D01*
G02Y278677I194J350D01*
G03X1449828Y279221I-683J1224D01*
G02X1450528I350J-194D01*
G03X1452434Y281128I1225J681D01*
G02Y281827I194J349D01*
G03X1452978Y282370I-680J1226D01*
G02X1453677I349J-195D01*
G03X1455583Y284277I1225J682D01*
G02Y284977I194J350D01*
G03X1456127Y285521I-681J1225D01*
G02X1456827I350J-194D01*
G03X1459277I1225J681D01*
G02X1459977I350J-194D01*
G03X1460521Y284977I1225J681D01*
G02Y284277I-194J-350D01*
G03Y281827I681J-1225D01*
G02Y281127I-194J-350D01*
G03X1459977Y280583I681J-1225D01*
G02X1459277I-350J194D01*
G03X1457370Y278677I-1225J-681D01*
G02Y277978I-194J-350D01*
G03X1456827Y277434I683J-1224D01*
G02X1456127I-350J194D01*
G03X1454221Y275528I-1225J-681D01*
G02Y274828I-194J-350D01*
G03X1453677Y274285I680J-1226D01*
G02X1452978I-350J194D01*
G03X1451071Y272378I-1225J-682D01*
G02Y271679I-194J-350D01*
G03X1450528Y271135I683J-1224D01*
G02X1449828I-350J194D01*
G03X1447922Y269229I-1225J-681D01*
G02Y268529I-194J-350D01*
G03X1447378Y267986I680J-1226D01*
G02X1446679I-350J194D01*
G03X1444228Y267984I-1225J-682D01*
G02X1443529I-350J194D01*
G37*
G36*
G01X1611816Y113022D02*
G03X1611272Y113566I-1225J-681D01*
G02Y114266I194J350D01*
G03X1611273Y116716I-681J1225D01*
G02Y117415I194J349D01*
G03X1611816Y117959I-683J1224D01*
G02X1612516I350J-194D01*
G03X1614966I1225J681D01*
G02X1615665I350J-195D01*
G03X1616223Y117408I1225J682D01*
G02X1616214Y116699I-190J-352D01*
G03X1616155Y114230I634J-1250D01*
G02X1616164Y113540I-198J-348D01*
G03X1615665Y113023I726J-1200D01*
G02X1614966I-349J194D01*
G03X1612516Y113022I-1225J-682D01*
G02X1611816I-350J194D01*
G37*
G36*
G01X1655910Y122471D02*
G03X1655367Y123015I-1226J-680D01*
G02Y123714I194J350D01*
G03X1653460Y125621I-681J1226D01*
G02X1652761I-349J194D01*
G03X1652217Y126164I-1224J-683D01*
G02Y126864I194J350D01*
G03Y129314I-681J1225D01*
G02Y130014I194J350D01*
G03X1652761Y130557I-680J1226D01*
G02X1653460I350J-194D01*
G03X1655910Y130558I1225J682D01*
G02X1656610I350J-194D01*
G03X1659060I1225J681D01*
G02X1659760I350J-194D01*
G03X1660304Y130014I1225J681D01*
G02Y129314I-194J-350D01*
G03Y126864I681J-1225D01*
G02Y126164I-194J-350D01*
G03X1660303Y123714I681J-1225D01*
G02Y123015I-194J-350D01*
G03X1659760Y122471I683J-1224D01*
G02X1659060I-350J194D01*
G03X1656610I-1225J-681D01*
G02X1655910I-350J194D01*
G37*
%LPC*%
G75*
G36*
G01X58175Y255329D02*
G02X56785Y255306I-675J-1229D01*
G03X56753Y256011I-204J344D01*
G02X58183Y256034I692J1445D01*
G03X58175Y255329I184J-355D01*
G37*
G36*
G01X358743Y69924D02*
G03Y69346I277J-289D01*
G02X356801I-971J-1011D01*
G03Y69924I-277J289D01*
G02X358743I971J1011D01*
G37*
G36*
G01X358688Y533045D02*
G03Y532501I293J-272D01*
G02X356634I-1027J-955D01*
G03Y533045I-293J272D01*
G02X358688I1027J955D01*
G37*
G36*
G01X1008351Y69924D02*
G03Y69346I277J-289D01*
G02X1006409I-971J-1011D01*
G03Y69924I-277J289D01*
G02X1008351I971J1011D01*
G37*
G36*
G01X1008178Y533126D02*
G03Y532548I277J-289D01*
G02X1006236I-971J-1011D01*
G03Y533126I-277J289D01*
G02X1008178I971J1011D01*
G37*
G54D63*
X19800Y257900D03*
G54D39*
X19904Y254162D03*
X37000Y265350D03*
X33490Y267900D03*
X37000Y275000D03*
X321334Y69900D03*
X334292D03*
X327754Y73757D03*
Y87392D03*
X324407Y89964D03*
Y73757D03*
Y84599D03*
X334447Y73757D03*
Y87392D03*
X331100Y89964D03*
X354526Y73757D03*
X354415Y87392D03*
X351179Y89964D03*
X347833Y73757D03*
Y87392D03*
X344486Y84714D03*
Y73757D03*
Y89964D03*
X337793Y84599D03*
Y73757D03*
X321061Y518157D03*
Y529014D03*
X327754Y512792D03*
X324407Y529014D03*
Y515364D03*
X334447Y512792D03*
X331100Y529014D03*
Y515364D03*
X354525Y529022D03*
X354526Y518157D03*
X354307Y512792D03*
X351179Y515364D03*
Y529022D03*
X347833Y512792D03*
X344486Y529022D03*
Y515364D03*
X341140Y529022D03*
Y518157D03*
X334446Y529014D03*
X334447Y518157D03*
X321334Y533100D03*
X334292D03*
X327754Y536957D03*
X324407D03*
X334447D03*
X354526D03*
X347833D03*
X344486D03*
X337793D03*
X408184Y69900D03*
X404723Y65822D03*
X404722Y89964D03*
X401377Y73757D03*
X401375Y87392D03*
X414763Y65822D03*
X414761Y92757D03*
X398029Y65807D03*
Y89964D03*
X404723Y73757D03*
X404722Y84599D03*
X414763Y73757D03*
X414761Y87392D03*
X408069Y65807D03*
X408068Y92757D03*
X394682Y87392D03*
X411415Y84714D03*
X411416Y73757D03*
X394682Y68492D03*
X401375Y103116D03*
X414819D03*
X408126D03*
X433508Y69900D03*
X421368D03*
X421456Y73757D03*
X438187Y84714D03*
X438189Y73757D03*
X431494Y65807D03*
X444880Y65822D03*
X431494Y89964D03*
X444880Y84714D03*
X428147Y87392D03*
X428149Y73757D03*
X421456Y65822D03*
X421454Y92757D03*
X434842Y73757D03*
X434840Y87392D03*
X424801Y65807D03*
X438189Y65822D03*
X424801Y89964D03*
X438187D03*
X427696Y103100D03*
X421512Y103116D03*
X404723Y529022D03*
X404722Y515364D03*
X401375Y512792D03*
X414761Y518157D03*
X398029Y529007D03*
Y515364D03*
X404722Y509999D03*
X414761Y512792D03*
X408068Y518157D03*
X408069Y529007D03*
X394682Y512792D03*
X411415Y510114D03*
X394587Y529026D03*
X408184Y533100D03*
X401377Y536957D03*
X404723D03*
X414763D03*
X394595Y537058D03*
X411416Y536957D03*
X438187Y510114D03*
X431494Y515364D03*
X428147Y512792D03*
X421456Y529022D03*
X421454Y518157D03*
X434840Y512792D03*
X424801Y515364D03*
X438187D03*
X421368Y533100D03*
X434395Y532904D03*
X438189Y536957D03*
X428149D03*
X434842D03*
X970942Y69900D03*
X974015Y89964D03*
Y84599D03*
Y73757D03*
X983900Y69900D03*
X977362Y73757D03*
Y87392D03*
X984055D03*
Y73757D03*
X980708Y89964D03*
X1004134Y73757D03*
X1004023Y87392D03*
X1000787Y89964D03*
X997441Y73757D03*
Y87392D03*
X994094Y84714D03*
Y73757D03*
Y89964D03*
X987401Y84599D03*
Y73757D03*
X970669Y529014D03*
Y518157D03*
X974015Y515364D03*
Y529014D03*
X970942Y533100D03*
X977362Y512792D03*
X984055D03*
X980708Y529014D03*
Y515364D03*
X1004133Y529022D03*
X1004134Y518157D03*
X1000787Y515364D03*
Y529022D03*
X997441Y512792D03*
X994094Y529022D03*
Y515364D03*
X990748Y529022D03*
Y518157D03*
X984055D03*
X984054Y529014D03*
X983900Y533100D03*
X1057792Y69900D03*
X1083116D03*
X1070976D03*
X1071064Y73757D03*
X1054330Y89964D03*
X1050985Y73757D03*
X1050983Y87392D03*
X1087797Y73757D03*
X1087795Y84714D03*
X1064369Y92757D03*
X1081102Y89964D03*
X1094488Y84714D03*
X1047637Y89964D03*
X1054331Y73757D03*
X1054330Y84599D03*
X1077755Y87392D03*
X1077757Y73757D03*
X1064371D03*
X1064369Y87392D03*
X1071062Y92757D03*
X1057676D03*
X1084448Y87392D03*
X1084450Y73757D03*
X1074409Y89964D03*
X1087795D03*
X1061024Y73757D03*
X1061023Y84714D03*
X1050983Y103116D03*
X1064427D03*
X1077304Y103100D03*
X1057734Y103116D03*
X1071120D03*
X1054331Y529022D03*
X1054330Y515364D03*
X1050983Y512792D03*
X1087795Y510114D03*
X1064369Y518157D03*
X1081102Y515364D03*
X1047637Y529007D03*
Y515364D03*
X1054330Y509999D03*
X1077755Y512792D03*
X1064369D03*
X1071062Y518157D03*
X1071064Y529022D03*
X1057677Y529007D03*
X1057676Y518157D03*
X1084448Y512792D03*
X1074409Y515364D03*
X1087795D03*
X1044290Y512792D03*
X1061023Y510114D03*
X1044195Y529026D03*
X1057792Y533100D03*
X1070976D03*
X1084003Y532904D03*
%LPD*%
G75*
G54D10*
X-17936Y-49379D03*
Y-53779D03*
Y-44979D03*
Y-40579D03*
X-18079Y-35764D03*
Y-58764D03*
X-14186Y196989D03*
Y199989D03*
X-14839Y445588D03*
X-14753Y448601D03*
X-17179Y643156D03*
X-17194Y638753D03*
X-17179Y647556D03*
Y660756D03*
Y651956D03*
Y656356D03*
X-13636Y-40479D03*
Y-44879D03*
Y-53679D03*
X-9079Y-50164D03*
X-4679D03*
X-279D03*
X-9079Y-54264D03*
X-4679D03*
X-279D03*
X22964Y-40379D03*
Y-44779D03*
Y-53579D03*
Y-49179D03*
X18964Y-53579D03*
Y-49179D03*
X13964Y-53579D03*
Y-49179D03*
X8964Y-40379D03*
Y-44779D03*
Y-53579D03*
Y-49179D03*
X3964Y-40379D03*
Y-44779D03*
Y-53579D03*
Y-49179D03*
X25921Y-35764D03*
X30321D03*
X43521D03*
X39121D03*
X34721D03*
X8321D03*
X12721D03*
X21521D03*
X17121D03*
X-13679D03*
X-9279D03*
X3921D03*
X-4879D03*
X-479D03*
X17121Y-58764D03*
X21521D03*
X12721D03*
X8321D03*
X34721D03*
X39121D03*
X43521D03*
X30321D03*
X25921D03*
X-479D03*
X-13679D03*
X-4879D03*
X3921D03*
X-13636Y-49279D03*
X-9279Y-58764D03*
X875Y211336D03*
X6074Y211293D03*
X3474Y211263D03*
X875Y208352D03*
X36200Y208600D03*
X33200D03*
X20700D03*
X17700Y211600D03*
X20700D03*
X17700Y208600D03*
X23700Y211600D03*
Y208600D03*
X33200Y211600D03*
X30200D03*
Y208600D03*
X36200Y211600D03*
X6074Y208321D03*
X3474Y208263D03*
X5500Y218500D03*
X-5300Y200191D03*
X-7900D03*
X-2700Y200202D03*
X-11586Y196989D03*
Y199989D03*
X-2600Y232300D03*
X-5246Y232351D03*
X-7846D03*
X20500Y221000D03*
Y224000D03*
X17500Y221000D03*
Y224000D03*
X23500D03*
Y221000D03*
X33300Y224000D03*
Y221000D03*
X30300D03*
Y224000D03*
X36300D03*
Y221000D03*
X-14129Y235221D03*
X-11484Y235215D03*
Y232215D03*
X-14084D03*
X2678Y221018D03*
X5277Y221110D03*
X5173Y224042D03*
X2574Y223963D03*
X-26Y223982D03*
X-11652Y445530D03*
Y448530D03*
X22421Y647556D03*
X26821D03*
X31221D03*
X18021D03*
Y643156D03*
X31221D03*
X26821D03*
X22421D03*
X18006Y638753D03*
X9221Y647556D03*
X13621D03*
Y643156D03*
X9221D03*
X4821D03*
Y647556D03*
X22406Y638753D03*
X26806D03*
X31206D03*
X-12794D03*
X-12779Y647556D03*
Y643156D03*
X40006Y638753D03*
X44406D03*
X35606D03*
X35621Y647556D03*
Y643156D03*
X-9599Y610630D03*
X-3301Y619643D03*
Y601615D03*
X4549Y620682D03*
X4548Y600577D03*
X13801Y624130D03*
Y597130D03*
X23360Y620172D03*
X23352Y601079D03*
X27301Y610630D03*
X18021Y660756D03*
X35621Y656356D03*
X26821Y660756D03*
X18021Y651956D03*
X31221D03*
X22421Y660756D03*
X26821Y651956D03*
X22421D03*
X4821D03*
X13621D03*
X9221D03*
X-8379Y660756D03*
X4821Y656356D03*
X9221D03*
X13621D03*
X-3979D03*
X421D03*
X13621Y660756D03*
X-3979D03*
X421D03*
X4821D03*
X-12779Y651956D03*
X22421Y656356D03*
X26821D03*
X31221D03*
X18021D03*
X-8379D03*
X-12779D03*
X31221Y660756D03*
X35621Y651956D03*
Y660756D03*
X44421D03*
X40021D03*
X-12779D03*
X9221D03*
X107921Y-58764D03*
X102921D03*
X97921D03*
X92921D03*
X87921D03*
X82921D03*
X77921D03*
X72921D03*
X67921D03*
X62921D03*
X57921D03*
X52921D03*
X47921Y-35764D03*
Y-58764D03*
X107921Y-35764D03*
X102921D03*
X97921D03*
X92921D03*
X87921D03*
X82921D03*
X77921D03*
X72921D03*
X67921D03*
X62921D03*
X57921D03*
X52921D03*
X96249Y204722D03*
X64700Y210100D03*
Y212800D03*
X64778Y218062D03*
X58000Y206500D03*
X56900Y197800D03*
X93870Y199131D03*
X97730Y188584D03*
X58200Y230400D03*
Y233400D03*
X55600Y230400D03*
X53000Y230300D03*
Y233300D03*
X55600Y233400D03*
X58200Y227400D03*
X53000Y227300D03*
X55600Y227400D03*
X58200Y239400D03*
X53000Y239300D03*
X55600Y239400D03*
X58200Y236400D03*
X55600D03*
X53000Y236300D03*
X71500Y263300D03*
X68800D03*
X53004Y244632D03*
X55275Y245900D03*
X57875D03*
X57457Y248537D03*
Y251237D03*
X57600Y262800D03*
X57500Y260200D03*
X62800Y265500D03*
X71500Y266000D03*
X65500Y265500D03*
X68800Y266000D03*
X60000Y265500D03*
X76540Y397355D03*
X81900Y398300D03*
X79140Y397355D03*
X98149Y399769D03*
X102456Y393756D03*
X76052Y420935D03*
X78000Y423100D03*
X80100Y425000D03*
X81500Y427400D03*
X79700Y409700D03*
X77400Y407800D03*
X81500Y412100D03*
X84913Y434471D03*
X87013Y436371D03*
X107571Y406291D03*
X48806Y638753D03*
X75206D03*
X106006D03*
X70806D03*
X53206D03*
X66406D03*
X92806D03*
X97206D03*
X101606D03*
X57606D03*
X62006D03*
X79606D03*
X84006D03*
X88406D03*
X53221Y660756D03*
X101621D03*
X97221D03*
X92821D03*
X106021D03*
X48821D03*
X70821D03*
X66421D03*
X62021D03*
X57621D03*
X75221D03*
X88421D03*
X84021D03*
X79621D03*
X167921Y-58764D03*
X162921D03*
X157921D03*
X152921D03*
X147921D03*
X142921D03*
X137921D03*
X132921D03*
X127921D03*
X122921D03*
X117921D03*
X112921D03*
X162921Y-35764D03*
X157921D03*
X152921D03*
X147921D03*
X142921D03*
X137921D03*
X132921D03*
X127921D03*
X122921D03*
X117921D03*
X112921D03*
X167921D03*
X166000Y212900D03*
X168600D03*
X164300Y207870D03*
X160800Y212900D03*
X163400D03*
X157800Y207300D03*
X161216Y209533D03*
Y206933D03*
X154500Y205500D03*
X150600Y212900D03*
X151000Y205500D03*
X140889Y211972D03*
X137615Y212039D03*
X143900Y204600D03*
X147500Y205500D03*
X137300Y204500D03*
X140200Y204400D03*
X153200Y212900D03*
X122044Y162340D03*
X139815Y268974D03*
X137900Y272800D03*
X139800Y237000D03*
X165825Y239543D03*
X168425Y236943D03*
Y239543D03*
X165825Y236943D03*
X163225D03*
X152825D03*
X145025D03*
X147625D03*
X150225D03*
X142425D03*
X163225Y239543D03*
X158025Y236943D03*
X155425D03*
X160625D03*
X142371Y244384D03*
X142466Y268982D03*
X142700Y276200D03*
X136729Y276386D03*
X139683Y276174D03*
X163225Y242143D03*
X168425Y244743D03*
X165825D03*
X163225D03*
X168425Y242143D03*
X165825D03*
X150700Y276800D03*
X169150Y259470D03*
Y255470D03*
X157633Y268727D03*
X162833D03*
X160233D03*
X165433D03*
X168033Y271327D03*
X162833Y276527D03*
Y273927D03*
Y271327D03*
X165433Y276527D03*
Y273927D03*
Y271327D03*
X159983Y276507D03*
X168033Y276527D03*
Y273927D03*
Y268727D03*
X153300Y276800D03*
X139866Y333016D03*
X160233Y306257D03*
Y308857D03*
Y303657D03*
X157518Y335391D03*
X157745Y332800D03*
X139900Y302400D03*
X142433Y301057D03*
X147633D03*
X150233D03*
X145033D03*
X145200Y341300D03*
X148200D03*
X142465Y332940D03*
X152833Y301057D03*
X163233Y306257D03*
Y308857D03*
X168433Y306257D03*
Y308857D03*
Y301057D03*
X165833D03*
X163233D03*
X160633D03*
X158033D03*
X155433D03*
X169150Y287600D03*
Y291600D03*
X165833Y306257D03*
X163233Y303657D03*
X168433D03*
X165833D03*
Y308857D03*
X151000Y341300D03*
X169150Y323600D03*
Y319600D03*
X160501Y332965D03*
X160274Y335556D03*
X165701Y338165D03*
Y335565D03*
X163101Y332965D03*
X168301D03*
X165701D03*
X163101Y335565D03*
X168301Y340765D03*
Y338165D03*
Y335565D03*
X163101Y338165D03*
Y340765D03*
X165701D03*
X154200Y341100D03*
X139767Y364883D03*
X147833Y364457D03*
X142421Y364908D03*
X145033Y364457D03*
X142863Y402829D03*
X140219Y402894D03*
X137619Y402900D03*
X134992D03*
X142818Y400163D03*
X143073Y397194D03*
X140475Y397310D03*
X140218Y400163D03*
X137529Y400296D03*
X134929D03*
X114084Y399937D03*
X122840Y400827D03*
X150633Y364457D03*
X167433Y369657D03*
X169150Y355600D03*
Y351600D03*
X167700Y363900D03*
X161833Y364457D03*
X164633D03*
X159033D03*
X156233D03*
X153433D03*
X164633Y369657D03*
X161833D03*
X161933Y372357D03*
X164733D03*
X167533D03*
X166340Y374785D03*
X167670Y383993D03*
Y387993D03*
X130613Y429647D03*
X123648Y425041D03*
X125328Y427269D03*
X127932Y428571D03*
X110519Y410307D03*
X110199Y413852D03*
X110406Y638753D03*
X145606D03*
X141206D03*
X136806D03*
X132406D03*
X158806D03*
X119206D03*
X123606D03*
X114806D03*
X128006D03*
X163206D03*
X154406D03*
X167606D03*
X150006D03*
X132421Y660756D03*
X145621D03*
X141221D03*
X136821D03*
X123621D03*
X114821D03*
X128021D03*
X110421D03*
X119221D03*
X150021D03*
X167621D03*
X163221D03*
X158821D03*
X154421D03*
X182921Y-58764D03*
X177921D03*
X172921D03*
X227921Y-35764D03*
X222921D03*
X217921D03*
X212921D03*
X207921D03*
X202921D03*
X197921D03*
X192921D03*
X187921D03*
X182921D03*
X177921D03*
X227921Y-58764D03*
X222921D03*
X217921D03*
X212921D03*
X207921D03*
X202921D03*
X197921D03*
X192921D03*
X187921D03*
X172921Y-35764D03*
X211606Y638753D03*
X224806D03*
X220406D03*
X216006D03*
X189606D03*
X198406D03*
X202806D03*
X207206D03*
X176406D03*
X172006D03*
X185206D03*
X180806D03*
X194006D03*
X226500Y649900D03*
X229206Y638753D03*
X224821Y660756D03*
X220421D03*
X198421D03*
X211621D03*
X189621D03*
X202821D03*
X207221D03*
X194021D03*
X185221D03*
X172021D03*
X176421D03*
X180821D03*
X229221D03*
X216021D03*
X292921Y-35764D03*
X287921D03*
X282921D03*
X277921D03*
X272921D03*
X267921D03*
X262921D03*
X257921D03*
X252921D03*
X247921D03*
X242921D03*
X237921D03*
X232921D03*
X292921Y-58764D03*
X287921D03*
X282921D03*
X277921D03*
X272921D03*
X267921D03*
X262921D03*
X257921D03*
X252921D03*
X247921D03*
X242921D03*
X237921D03*
X232921D03*
X290806Y638753D03*
X268806D03*
X273206D03*
X277606D03*
X282006D03*
X260006D03*
X264406D03*
X255606D03*
X251206D03*
X286406D03*
X242406D03*
X246806D03*
X233606D03*
X238006D03*
X286421Y660756D03*
X268821D03*
X282021D03*
X273221D03*
X277621D03*
X264421D03*
X251221D03*
X255621D03*
X260021D03*
X246821D03*
X242421D03*
X238021D03*
X233621D03*
X290821D03*
X352921Y-58764D03*
Y-35764D03*
X347921Y-58764D03*
Y-35764D03*
X342921Y-58764D03*
Y-35764D03*
X337921Y-58764D03*
Y-35764D03*
X332921Y-58764D03*
Y-35764D03*
X327921Y-58764D03*
Y-35764D03*
X322921Y-58764D03*
Y-35764D03*
X317921Y-58764D03*
Y-35764D03*
X312921Y-58764D03*
X307921D03*
Y-35764D03*
X302921Y-58764D03*
Y-35764D03*
X297921D03*
Y-58764D03*
X312921Y-35764D03*
X330406Y638753D03*
X348006D03*
X326006D03*
X312806D03*
X317206D03*
X321606D03*
X352406D03*
X295206D03*
X299606D03*
X308406D03*
X304006D03*
X334806D03*
X339206D03*
X343606D03*
X312821Y660756D03*
X317221D03*
X308421D03*
X304021D03*
X352421D03*
X295221D03*
X326021D03*
X321621D03*
X339221D03*
X299621D03*
X334821D03*
X330421D03*
X343621D03*
X348021D03*
X392921Y-35764D03*
X387921Y-58764D03*
Y-35764D03*
X382921Y-58764D03*
Y-35764D03*
X377921Y-58764D03*
Y-35764D03*
X372921Y-58764D03*
Y-35764D03*
X367921Y-58764D03*
Y-35764D03*
X362921Y-58764D03*
Y-35764D03*
X357921Y-58764D03*
Y-35764D03*
X392921Y-58764D03*
X402921Y-35764D03*
X397921Y-58764D03*
Y-35764D03*
X412921Y-58764D03*
Y-35764D03*
X407921Y-58764D03*
Y-35764D03*
X402921Y-58764D03*
X380885Y273876D03*
Y270876D03*
X382494Y278904D03*
X371094D03*
X378294D03*
X375294D03*
X368094D03*
X389694D03*
X392694D03*
X385945Y278480D03*
X407094Y278910D03*
X414207D03*
X411288D03*
X404094D03*
X400842Y278914D03*
X368094Y295904D03*
X371094D03*
X385494D03*
X375294D03*
X378294D03*
X382494D03*
X389694D03*
X392694D03*
X365693Y311893D03*
X391144Y324173D03*
X388394D03*
X385494D03*
X411294Y295904D03*
X414294D03*
X407094D03*
X404094D03*
X399894D03*
X396894D03*
Y324173D03*
X408894D03*
X411894D03*
X405894D03*
X414894D03*
X393894D03*
X402894D03*
X399894D03*
X383206Y638753D03*
X387606D03*
X392006D03*
X396406D03*
X400806D03*
X405206D03*
X409606D03*
X414006D03*
X370006D03*
X365606D03*
X374406D03*
X378806D03*
X356806D03*
X361206D03*
X374421Y660756D03*
X387621D03*
X383221D03*
X400821D03*
X396421D03*
X392021D03*
X405221D03*
X409621D03*
X414021D03*
X361221D03*
X365621D03*
X356821D03*
X370021D03*
X378821D03*
X477921Y-58764D03*
Y-35764D03*
X472921Y-58764D03*
Y-35764D03*
X467921Y-58764D03*
Y-35764D03*
X462921Y-58764D03*
Y-35764D03*
X457921Y-58764D03*
Y-35764D03*
X452921Y-58764D03*
Y-35764D03*
X447921Y-58764D03*
Y-35764D03*
X442921Y-58764D03*
Y-35764D03*
X437921Y-58764D03*
Y-35764D03*
X432921Y-58764D03*
X422921Y-35764D03*
X417921Y-58764D03*
Y-35764D03*
X432921D03*
X427921Y-58764D03*
Y-35764D03*
X422921Y-58764D03*
X432643Y264508D03*
X418523Y278910D03*
X428694D03*
X432894D03*
X425694D03*
X435894Y278938D03*
X443094Y278904D03*
X440094D03*
X421523Y278944D03*
X451675Y291739D03*
X449148Y292841D03*
X446209Y292842D03*
X451816Y295904D03*
X435894D03*
X418494D03*
X443094D03*
X440094D03*
X446383Y295841D03*
X428694Y295904D03*
X432894D03*
X425694D03*
X421494D03*
X418494Y324173D03*
X451267Y324476D03*
X448694Y323949D03*
X421494Y324173D03*
X446094Y323904D03*
X425694Y324173D03*
X428694D03*
X432894D03*
X435894D03*
X455226Y291686D03*
X454922Y295841D03*
X466806Y638753D03*
X462406D03*
X475606D03*
X471206D03*
X418406D03*
X422806D03*
X427206D03*
X440406D03*
X436006D03*
X431606D03*
X449206D03*
X458006D03*
X453606D03*
X444806D03*
X458021Y660756D03*
X449221D03*
X462421D03*
X466821D03*
X471221D03*
X418421D03*
X475621D03*
X453621D03*
X422821D03*
X427221D03*
X440421D03*
X431621D03*
X436021D03*
X444821D03*
X537921Y-58764D03*
Y-35764D03*
X532921Y-58764D03*
Y-35764D03*
X527921Y-58764D03*
Y-35764D03*
X522921Y-58764D03*
Y-35764D03*
X517921Y-58764D03*
Y-35764D03*
X512921Y-58764D03*
Y-35764D03*
X507921Y-58764D03*
Y-35764D03*
X502921Y-58764D03*
Y-35764D03*
X497921Y-58764D03*
Y-35764D03*
X492921Y-58764D03*
Y-35764D03*
X487921Y-58764D03*
Y-35764D03*
X482921Y-58764D03*
Y-35764D03*
X480006Y638753D03*
X484406D03*
X488806D03*
X493206D03*
X497606D03*
X510806D03*
X537206D03*
X519606D03*
X524006D03*
X532806D03*
X528406D03*
X515206D03*
X502006D03*
X506406D03*
X524021Y660756D03*
X480021D03*
X484421D03*
X497621D03*
X493221D03*
X488821D03*
X519621D03*
X532821D03*
X537221D03*
X528421D03*
X515221D03*
X510821D03*
X506421D03*
X502021D03*
X597921Y-35764D03*
Y-58764D03*
X592921Y-35764D03*
Y-58764D03*
X587921Y-35764D03*
Y-58764D03*
X582921Y-35764D03*
Y-58764D03*
X577921Y-35764D03*
Y-58764D03*
X572921Y-35764D03*
Y-58764D03*
X567921Y-35764D03*
Y-58764D03*
X562921Y-35764D03*
Y-58764D03*
X557921Y-35764D03*
Y-58764D03*
X552921Y-35764D03*
Y-58764D03*
X547921D03*
Y-35764D03*
X542921Y-58764D03*
Y-35764D03*
X590006Y638753D03*
X572406D03*
X559206D03*
X568006D03*
X563606D03*
X550406D03*
X581206D03*
X585606D03*
X576806D03*
X598806D03*
X594406D03*
X601500Y649500D03*
X554806Y638753D03*
X541606D03*
X546006D03*
X559221Y660756D03*
X546021D03*
X554821D03*
X598821D03*
X572421D03*
X568021D03*
X563621D03*
X585621D03*
X541621D03*
X594421D03*
X576821D03*
X590021D03*
X581221D03*
X550421D03*
X637921Y-58764D03*
X632921Y-35764D03*
Y-58764D03*
X627921Y-35764D03*
Y-58764D03*
X622921Y-35764D03*
Y-58764D03*
X617921Y-35764D03*
Y-58764D03*
X612921Y-35764D03*
Y-58764D03*
X607921Y-35764D03*
Y-58764D03*
X602921Y-35764D03*
Y-58764D03*
X652921Y-35764D03*
Y-58764D03*
X647921Y-35764D03*
Y-58764D03*
X642921Y-35764D03*
Y-58764D03*
X637921Y-35764D03*
X662921D03*
Y-58764D03*
X657921Y-35764D03*
Y-58764D03*
X638406Y638753D03*
X634006D03*
X642806D03*
X629606D03*
X616406D03*
X612006D03*
X603206D03*
X625206D03*
X651606D03*
X647206D03*
X660406D03*
X620806D03*
X656006D03*
X607606D03*
X607621Y660756D03*
X638421D03*
X647221D03*
X616421D03*
X634021D03*
X612021D03*
X620821D03*
X625221D03*
X629621D03*
X642821D03*
X603221D03*
X656021D03*
X660421D03*
X651621D03*
X692921Y-58764D03*
X687921Y-35764D03*
Y-58764D03*
X682921Y-35764D03*
Y-58764D03*
X677921Y-35764D03*
Y-58764D03*
X672921Y-35764D03*
Y-58764D03*
X667921Y-35764D03*
Y-58764D03*
X697921Y-35764D03*
Y-58764D03*
X692921Y-35764D03*
X722921D03*
Y-58764D03*
X717921Y-35764D03*
Y-58764D03*
X712921Y-35764D03*
Y-58764D03*
X707921Y-35764D03*
Y-58764D03*
X702921Y-35764D03*
Y-58764D03*
X704466Y-7874D03*
X690966Y-21374D03*
X700525Y1668D03*
X700517Y-17425D03*
X681713Y-17927D03*
X690966Y5626D03*
X681714Y2178D03*
X673864Y-16889D03*
X667566Y-7874D03*
X673864Y1139D03*
X695606Y638753D03*
X673606D03*
X708806D03*
X704406D03*
X700006D03*
X722006D03*
X717606D03*
X713206D03*
X664806D03*
X669206D03*
X686806D03*
X682406D03*
X678006D03*
X691206D03*
X690966Y624130D03*
Y597130D03*
X700525Y620172D03*
X700517Y601079D03*
X704466Y610630D03*
X667566D03*
X673864Y619643D03*
Y601615D03*
X681714Y620682D03*
X681713Y600577D03*
X664821Y660756D03*
X695621D03*
X708821D03*
X700021D03*
X704421D03*
X669221D03*
X686821D03*
X691221D03*
X678021D03*
X673621D03*
X682421D03*
X722021D03*
X717621D03*
X713221D03*
X777921Y-58764D03*
X772921Y-35764D03*
Y-58764D03*
X767921Y-35764D03*
Y-58764D03*
X762921Y-35764D03*
Y-58764D03*
X757921Y-35764D03*
Y-58764D03*
X752921Y-35764D03*
Y-58764D03*
X787921Y-35764D03*
Y-58764D03*
X782921Y-35764D03*
Y-58764D03*
X777921Y-35764D03*
X747921D03*
Y-58764D03*
X742921Y-35764D03*
Y-58764D03*
X737921Y-35764D03*
Y-58764D03*
X732921Y-35764D03*
Y-58764D03*
X727921Y-35764D03*
Y-58764D03*
X786674Y211463D03*
X785920Y204763D03*
X786300Y207400D03*
X787200Y244200D03*
Y271900D03*
X787100Y241100D03*
X773419Y270414D03*
X787200Y276400D03*
X787100Y303900D03*
X753098Y338316D03*
X744698Y332816D03*
X787000Y308300D03*
X787400Y340400D03*
X741774Y376463D03*
X785400Y372400D03*
X757500Y374000D03*
X770406Y638753D03*
X779206D03*
X774806D03*
X730806D03*
X726406D03*
X739606D03*
X735206D03*
X748406D03*
X744006D03*
X766006D03*
X761606D03*
X757206D03*
X752806D03*
X783606D03*
X744021Y660756D03*
X735221D03*
X779221D03*
X770421D03*
X774821D03*
X726421D03*
X730821D03*
X739621D03*
X748421D03*
X783621D03*
X757221D03*
X761621D03*
X752821D03*
X766021D03*
X842921Y-35764D03*
X837921Y-58764D03*
Y-35764D03*
X832921Y-58764D03*
X847921D03*
Y-35764D03*
X842921Y-58764D03*
X832921Y-35764D03*
X827921Y-58764D03*
Y-35764D03*
X822921Y-58764D03*
Y-35764D03*
X817921Y-58764D03*
Y-35764D03*
X812921Y-58764D03*
Y-35764D03*
X807921Y-58764D03*
Y-35764D03*
X802921Y-58764D03*
Y-35764D03*
X797921D03*
Y-58764D03*
X792921Y-35764D03*
Y-58764D03*
X816900Y216300D03*
X816874Y212863D03*
X814274D03*
X811674D03*
X808818Y211179D03*
X808618Y208579D03*
X803200Y213100D03*
X800600D03*
X794474Y211463D03*
X791874D03*
X789274D03*
X788522Y204343D03*
X791122Y204339D03*
X789432Y236947D03*
X789400Y273700D03*
X811983Y244843D03*
Y242243D03*
X814583Y239643D03*
X815432Y237000D03*
X814583Y244843D03*
Y242243D03*
X812832Y237000D03*
X811983Y239643D03*
X802432Y237000D03*
X799832D03*
X792032D03*
X794632D03*
X810232D03*
X797232D03*
X805032D03*
X807632D03*
X791000Y244400D03*
X793600D03*
X816800Y234300D03*
X816900Y230900D03*
X817000Y252500D03*
X789800Y276400D03*
X792400D03*
X801991Y276557D03*
X804591D03*
X792191Y269101D03*
X789591D03*
X814891Y271657D03*
Y274257D03*
Y276857D03*
Y269057D03*
X812291D03*
Y274257D03*
Y276857D03*
Y271657D03*
X817000Y255100D03*
Y257700D03*
X817491Y276857D03*
Y274257D03*
Y271657D03*
Y269057D03*
X817183Y242243D03*
Y239643D03*
Y244843D03*
X818032Y237000D03*
X788600Y306100D03*
X789500Y301200D03*
X797300D03*
X799900D03*
X810300D03*
X802500D03*
X812900D03*
X807700D03*
X805100D03*
X815500D03*
X811991Y308957D03*
Y306357D03*
Y303757D03*
X814591Y306357D03*
Y308957D03*
Y303757D03*
X792900Y308400D03*
X789900D03*
X794700Y301200D03*
X792100D03*
X793000Y340400D03*
X790300Y340300D03*
X816991Y337357D03*
Y334757D03*
Y339957D03*
X814391D03*
Y337357D03*
Y334757D03*
X811791Y337357D03*
Y339957D03*
Y334757D03*
X791879Y332798D03*
X794600Y332600D03*
X816938Y319888D03*
Y323888D03*
X817100Y317000D03*
X818100Y301200D03*
X817191Y303757D03*
Y306357D03*
Y308957D03*
X789860Y364947D03*
X816591Y369857D03*
Y372457D03*
X811391Y369857D03*
X813991D03*
Y372457D03*
X811391D03*
X790900Y372300D03*
X788300Y372400D03*
X802759Y364575D03*
X816672Y358809D03*
X795310Y364721D03*
X816593Y356210D03*
X807959Y364575D03*
X805359D03*
X810559D03*
X815759D03*
X813159D03*
X816900Y361400D03*
X792610Y364821D03*
X816591Y375057D03*
X792238Y396753D03*
X789600Y396809D03*
X811515Y397289D03*
X808915D03*
X813648Y395557D03*
X815472Y390442D03*
X814877Y393138D03*
X792000Y399409D03*
X789400D03*
X849606Y638753D03*
X836406D03*
X832006D03*
X796806D03*
X801206D03*
X792406D03*
X827606D03*
X818806D03*
X823206D03*
X810006D03*
X788006D03*
X845206D03*
X814406D03*
X805606D03*
X840806D03*
X849621Y660756D03*
X832021D03*
X810021D03*
X818821D03*
X836421D03*
X788021D03*
X814421D03*
X801221D03*
X805621D03*
X823221D03*
X827621D03*
X840821D03*
X796821D03*
X792421D03*
X845221D03*
X907921Y-58764D03*
Y-35764D03*
X902921Y-58764D03*
Y-35764D03*
X897921Y-58764D03*
Y-35764D03*
X892921Y-58764D03*
Y-35764D03*
X887921Y-58764D03*
Y-35764D03*
X882921Y-58764D03*
Y-35764D03*
X877921Y-58764D03*
Y-35764D03*
X872921Y-58764D03*
Y-35764D03*
X867921Y-58764D03*
Y-35764D03*
X862921Y-58764D03*
Y-35764D03*
X857921Y-58764D03*
Y-35764D03*
X852921Y-58764D03*
Y-35764D03*
X858406Y638753D03*
X854006D03*
X884806D03*
X880406D03*
X876006D03*
X871606D03*
X867206D03*
X911206D03*
X906806D03*
X889206D03*
X898006D03*
X902406D03*
X893606D03*
X862806D03*
X854021Y660756D03*
X858421D03*
X862821D03*
X898021D03*
X902421D03*
X871621D03*
X884821D03*
X893621D03*
X867221D03*
X889221D03*
X911221D03*
X906821D03*
X880421D03*
X876021D03*
X937921Y-35764D03*
X932921Y-58764D03*
Y-35764D03*
X927921Y-58764D03*
Y-35764D03*
X922921Y-58764D03*
Y-35764D03*
X917921Y-58764D03*
Y-35764D03*
X912921Y-58764D03*
Y-35764D03*
X942921D03*
X967921D03*
X962921Y-58764D03*
Y-35764D03*
X957921Y-58764D03*
Y-35764D03*
X952921Y-58764D03*
Y-35764D03*
X947921Y-58764D03*
Y-35764D03*
X942921Y-58764D03*
X972921D03*
Y-35764D03*
X967921Y-58764D03*
X937921D03*
X924406Y638753D03*
X920006D03*
X915606D03*
X972806D03*
X968406D03*
X964006D03*
X917100Y649300D03*
X942006Y638753D03*
X937606D03*
X933206D03*
X928806D03*
X959606D03*
X955206D03*
X950806D03*
X946406D03*
X959621Y660756D03*
X964021D03*
X968421D03*
X972821D03*
X920021D03*
X915621D03*
X924421D03*
X946421D03*
X942021D03*
X937621D03*
X933221D03*
X928821D03*
X955221D03*
X950821D03*
X1002921Y-58764D03*
Y-35764D03*
X997921Y-58764D03*
Y-35764D03*
X992921Y-58764D03*
Y-35764D03*
X987921Y-58764D03*
Y-35764D03*
X982921Y-58764D03*
Y-35764D03*
X977921Y-58764D03*
Y-35764D03*
X1032921Y-58764D03*
Y-35764D03*
X1027921Y-58764D03*
Y-35764D03*
X1022921Y-58764D03*
Y-35764D03*
X1017921Y-58764D03*
Y-35764D03*
X1012921Y-58764D03*
Y-35764D03*
X1007921Y-58764D03*
Y-35764D03*
X1030489Y270889D03*
Y273889D03*
X1027902Y278904D03*
X1020702D03*
X1017702D03*
X1024902D03*
X1032102D03*
X1017567Y295859D03*
X1024767D03*
X1020567D03*
X1031967D03*
X1027767D03*
X1015293Y311955D03*
X1003606Y638753D03*
X1012406D03*
X977206D03*
X990406D03*
X986006D03*
X994806D03*
X1016806D03*
X1021206D03*
X981606D03*
X999206D03*
X1025606D03*
X1008006D03*
X1030006D03*
X1034406D03*
X999221Y660756D03*
X1034421D03*
X1030021D03*
X1008021D03*
X1012421D03*
X1003621D03*
X1016821D03*
X977221D03*
X981621D03*
X1021221D03*
X1025621D03*
X994821D03*
X986021D03*
X990421D03*
X1067921Y-58764D03*
Y-35764D03*
X1062921Y-58764D03*
Y-35764D03*
X1057921Y-58764D03*
Y-35764D03*
X1052921Y-58764D03*
Y-35764D03*
X1047921Y-58764D03*
Y-35764D03*
X1042921Y-58764D03*
Y-35764D03*
X1037921Y-58764D03*
Y-35764D03*
X1092921Y-58764D03*
Y-35764D03*
X1087921Y-58764D03*
Y-35764D03*
X1082921Y-58764D03*
Y-35764D03*
X1077921Y-58764D03*
Y-35764D03*
X1072921Y-58764D03*
Y-35764D03*
X1042302Y278904D03*
X1039302D03*
X1056602Y278910D03*
X1035814Y278775D03*
X1049867Y278999D03*
X1053459Y278910D03*
X1060958D03*
X1075302D03*
X1078302D03*
X1082330D03*
X1070926D03*
X1063652D03*
X1067783D03*
X1082432Y264620D03*
X1085518Y278910D03*
X1089702Y278904D03*
X1039167Y295859D03*
X1042167D03*
X1034967D03*
X1046367D03*
X1056567D03*
X1049367D03*
X1053567D03*
X1038720Y324174D03*
X1044220D03*
X1035820D03*
X1050220D03*
X1047220D03*
X1053220D03*
X1056220D03*
X1041470D03*
X1059220D03*
X1060767Y295859D03*
X1095756Y292841D03*
X1082367Y295859D03*
X1085367D03*
X1075167D03*
X1078167D03*
X1089567D03*
X1092567D03*
X1095567Y295841D03*
X1070967Y295859D03*
X1063767D03*
X1067967D03*
X1062220Y324174D03*
X1095402Y323904D03*
X1083220Y324174D03*
X1076020D03*
X1079020D03*
X1071820D03*
X1065220D03*
X1068820D03*
X1096006Y638753D03*
X1078406D03*
X1082806D03*
X1074006D03*
X1069606D03*
X1091606D03*
X1052006D03*
X1038806D03*
X1087206D03*
X1060806D03*
X1056406D03*
X1065206D03*
X1043206D03*
X1047606D03*
X1078421Y660756D03*
X1060821D03*
X1087221D03*
X1038821D03*
X1091621D03*
X1052021D03*
X1074021D03*
X1065221D03*
X1096021D03*
X1056421D03*
X1043221D03*
X1047621D03*
X1082821D03*
X1069621D03*
X1157921Y-58764D03*
Y-35764D03*
X1152921Y-58764D03*
Y-35764D03*
X1147921Y-58764D03*
Y-35764D03*
X1142921Y-58764D03*
Y-35764D03*
X1137921Y-58764D03*
Y-35764D03*
X1132921Y-58764D03*
Y-35764D03*
X1127921Y-58764D03*
Y-35764D03*
X1122921Y-58764D03*
Y-35764D03*
X1117921Y-58764D03*
Y-35764D03*
X1112921Y-58764D03*
Y-35764D03*
X1107921Y-58764D03*
Y-35764D03*
X1102921Y-58764D03*
Y-35764D03*
X1097921Y-58764D03*
Y-35764D03*
X1104256Y291841D03*
X1101615Y292447D03*
X1098756Y292841D03*
X1101567Y295859D03*
X1104221Y295696D03*
X1098567Y295841D03*
X1112490Y312723D03*
X1112515Y315369D03*
X1101200Y324013D03*
X1098402Y324017D03*
X1135606Y638753D03*
X1126806D03*
X1144406D03*
X1140006D03*
X1118006D03*
X1122406D03*
X1153206D03*
X1157606D03*
X1104806D03*
X1100406D03*
X1131206D03*
X1148806D03*
X1109206D03*
X1113606D03*
X1157621Y660756D03*
X1148821D03*
X1122421D03*
X1126821D03*
X1100421D03*
X1118021D03*
X1140021D03*
X1113621D03*
X1109221D03*
X1153221D03*
X1144421D03*
X1104821D03*
X1131221D03*
X1135621D03*
X1217921Y-58764D03*
Y-35764D03*
X1212921Y-58764D03*
Y-35764D03*
X1207921Y-58764D03*
Y-35764D03*
X1202921Y-58764D03*
Y-35764D03*
X1197921Y-58764D03*
Y-35764D03*
X1192921Y-58764D03*
Y-35764D03*
X1187921Y-58764D03*
Y-35764D03*
X1182921Y-58764D03*
Y-35764D03*
X1177921Y-58764D03*
Y-35764D03*
X1172921Y-58764D03*
Y-35764D03*
X1167921Y-58764D03*
Y-35764D03*
X1162921Y-58764D03*
Y-35764D03*
X1188406Y638753D03*
X1214806D03*
X1197206D03*
X1201606D03*
X1192806D03*
X1170806D03*
X1162006D03*
X1166406D03*
X1206006D03*
X1219206D03*
X1179606D03*
X1175206D03*
X1210406D03*
X1184006D03*
X1184021Y660756D03*
X1219221D03*
X1192821D03*
X1188421D03*
X1201621D03*
X1179621D03*
X1214821D03*
X1206021D03*
X1166421D03*
X1210421D03*
X1170821D03*
X1162021D03*
X1175221D03*
X1197221D03*
X1232921Y-58764D03*
Y-35764D03*
X1227921Y-58764D03*
Y-35764D03*
X1222921Y-58764D03*
Y-35764D03*
X1252921Y-58764D03*
Y-35764D03*
X1247921Y-58764D03*
Y-35764D03*
X1242921Y-58764D03*
Y-35764D03*
X1237921Y-58764D03*
Y-35764D03*
X1257921D03*
X1272921Y-58764D03*
Y-35764D03*
X1267921Y-58764D03*
Y-35764D03*
X1262921Y-58764D03*
Y-35764D03*
X1257921Y-58764D03*
X1277921D03*
Y-35764D03*
X1263206Y638753D03*
X1223606D03*
X1228006D03*
X1258806D03*
X1241206D03*
X1236806D03*
X1250006D03*
X1245606D03*
X1276406D03*
X1254406D03*
X1280806D03*
X1272006D03*
X1267606D03*
X1232406D03*
X1228021Y660756D03*
X1232421D03*
X1280821D03*
X1245621D03*
X1236821D03*
X1223621D03*
X1276421D03*
X1241221D03*
X1272021D03*
X1258821D03*
X1250021D03*
X1254421D03*
X1263221D03*
X1267621D03*
X1342921Y-35764D03*
Y-58764D03*
X1317921D03*
X1312921Y-35764D03*
Y-58764D03*
X1307921Y-35764D03*
Y-58764D03*
X1302921Y-35764D03*
Y-58764D03*
X1297921D03*
Y-35764D03*
X1292921Y-58764D03*
Y-35764D03*
X1287921Y-58764D03*
Y-35764D03*
X1282921Y-58764D03*
Y-35764D03*
X1322921D03*
Y-58764D03*
X1317921Y-35764D03*
X1337921D03*
Y-58764D03*
X1332921Y-35764D03*
Y-58764D03*
X1327921Y-35764D03*
Y-58764D03*
X1324806Y638753D03*
X1298406D03*
X1285206D03*
X1294006D03*
X1302806D03*
X1333606D03*
X1338006D03*
X1320406D03*
X1311606D03*
X1329206D03*
X1307206D03*
X1342406D03*
X1289606D03*
X1316006D03*
X1329221Y660756D03*
X1311621D03*
X1316021D03*
X1333621D03*
X1342421D03*
X1285221D03*
X1324821D03*
X1338021D03*
X1298421D03*
X1289621D03*
X1294021D03*
X1320421D03*
X1302821D03*
X1307221D03*
X1402921Y-58764D03*
X1397921D03*
X1402921Y-35764D03*
X1392921Y-58764D03*
X1397921Y-35764D03*
X1387921Y-58764D03*
X1392921Y-35764D03*
X1382921Y-58764D03*
X1387921Y-35764D03*
X1377921Y-58764D03*
X1382921Y-35764D03*
X1372921Y-58764D03*
X1377921Y-35764D03*
X1367921Y-58764D03*
X1362921Y-35764D03*
Y-58764D03*
X1357921Y-35764D03*
Y-58764D03*
X1352921Y-35764D03*
Y-58764D03*
X1347921Y-35764D03*
Y-58764D03*
X1395913Y-7874D03*
X1402211Y1139D03*
Y-16889D03*
X1351206Y638753D03*
X1360006D03*
X1404506Y638853D03*
X1355606Y638753D03*
X1386906Y638853D03*
X1364406Y638753D03*
X1391306Y638853D03*
X1346806Y638753D03*
X1400106Y638853D03*
X1382006Y638753D03*
X1377606D03*
X1373206D03*
X1395706Y638853D03*
X1368806Y638753D03*
X1402211Y601615D03*
Y619643D03*
X1395913Y610630D03*
X1368821Y660756D03*
X1346821D03*
X1355621D03*
X1360021D03*
X1364421D03*
X1351221D03*
X1404521Y660856D03*
X1400121D03*
X1395721D03*
X1386921D03*
X1377621Y660756D03*
X1382021D03*
X1373221D03*
X1391321Y660856D03*
X1407921Y-58764D03*
X1412921Y-35764D03*
X1407921D03*
X1442921Y-58764D03*
X1447921Y-35764D03*
X1437921Y-58764D03*
X1442921Y-35764D03*
X1432921Y-58764D03*
X1437921Y-35764D03*
X1427921Y-58764D03*
X1432921Y-35764D03*
X1422921Y-58764D03*
X1427921Y-35764D03*
X1417921Y-58764D03*
X1422921Y-35764D03*
X1412921Y-58764D03*
X1417921Y-35764D03*
X1462921Y-58764D03*
X1457921D03*
X1462921Y-35764D03*
X1452921Y-58764D03*
X1457921Y-35764D03*
X1447921Y-58764D03*
X1452921Y-35764D03*
X1410061Y2178D03*
X1410060Y-17927D03*
X1419313Y5626D03*
Y-21374D03*
X1428872Y1668D03*
X1428864Y-17425D03*
X1432813Y-7874D03*
X1422106Y638853D03*
X1466106D03*
X1448506D03*
X1457306D03*
X1417706D03*
X1413306D03*
X1461706D03*
X1452906D03*
X1408906D03*
X1444106D03*
X1435306D03*
X1426506D03*
X1430906D03*
X1439706D03*
X1432813Y610630D03*
X1428864Y601079D03*
X1428872Y620172D03*
X1419313Y597130D03*
Y624130D03*
X1410060Y600577D03*
X1410061Y620682D03*
X1457321Y660856D03*
X1417721D03*
X1413321D03*
X1408921D03*
X1422121D03*
X1426521D03*
X1435321D03*
X1444121D03*
X1439721D03*
X1430921D03*
X1448521D03*
X1452921D03*
X1466121D03*
X1461721D03*
X1502921Y-58764D03*
X1507921Y-35764D03*
X1497921Y-58764D03*
X1502921Y-35764D03*
X1492921Y-58764D03*
X1497921Y-35764D03*
X1487921Y-58764D03*
X1492921Y-35764D03*
X1482921Y-58764D03*
X1487921Y-35764D03*
X1477921Y-58764D03*
X1482921Y-35764D03*
X1472921Y-58764D03*
X1477921Y-35764D03*
X1467921Y-58764D03*
X1472921Y-35764D03*
X1467921D03*
X1527921Y-58764D03*
X1522921D03*
X1527921Y-35764D03*
X1517921Y-58764D03*
X1522921Y-35764D03*
X1512921Y-58764D03*
X1517921Y-35764D03*
X1507921Y-58764D03*
X1512921Y-35764D03*
X1496906Y638853D03*
X1492506D03*
X1501706Y638753D03*
X1506106D03*
X1514906D03*
X1483706Y638853D03*
X1523706Y638753D03*
X1510506D03*
X1488106Y638853D03*
X1474906D03*
X1519306Y638753D03*
X1479306Y638853D03*
X1528106Y638753D03*
X1470506Y638853D03*
X1496921Y660856D03*
X1483721D03*
X1488121D03*
X1492521D03*
X1479321D03*
X1510521Y660756D03*
X1528121D03*
X1523721D03*
X1501721D03*
X1506121D03*
X1514921D03*
X1519321D03*
X1474921Y660856D03*
X1470521D03*
X1587921Y-58764D03*
X1582921D03*
X1587921Y-35764D03*
X1532921D03*
X1542921D03*
X1532921Y-58764D03*
X1537921Y-35764D03*
X1577921Y-58764D03*
X1582921Y-35764D03*
X1572921Y-58764D03*
X1577921Y-35764D03*
X1567921Y-58764D03*
X1572921Y-35764D03*
X1562921Y-58764D03*
X1567921Y-35764D03*
X1557921Y-58764D03*
X1562921Y-35764D03*
X1552921Y-58764D03*
X1557921Y-35764D03*
X1547921Y-58764D03*
X1552921Y-35764D03*
X1542921Y-58764D03*
X1547921Y-35764D03*
X1537921Y-58764D03*
X1580121Y647556D03*
X1555106Y638753D03*
X1555121Y647556D03*
X1590121D03*
X1590106Y638753D03*
X1590121Y643156D03*
X1585121Y647556D03*
X1585106Y638753D03*
X1585121Y643156D03*
X1565121Y647556D03*
X1570121Y643156D03*
X1570106Y638753D03*
X1565106D03*
X1565121Y643156D03*
X1570121Y647556D03*
X1560121D03*
X1560106Y638753D03*
X1560121Y643156D03*
X1575121D03*
X1575106Y638753D03*
X1575121Y647556D03*
X1555121Y643156D03*
X1580106Y638753D03*
X1580121Y643156D03*
X1550121Y647556D03*
X1541306Y638753D03*
X1545706D03*
X1550106D03*
X1550121Y643156D03*
X1536906Y638753D03*
X1532506D03*
X1565121Y651956D03*
X1570121Y660756D03*
Y656356D03*
X1565121Y660756D03*
X1555121Y651956D03*
X1590121Y660756D03*
Y656356D03*
Y651956D03*
X1585121Y660756D03*
Y656356D03*
Y651956D03*
X1580121Y660756D03*
Y656356D03*
Y651956D03*
X1560121Y660756D03*
Y656356D03*
Y651956D03*
X1555121Y660756D03*
Y656356D03*
X1570121Y651956D03*
X1575121D03*
Y656356D03*
Y660756D03*
X1565121Y656356D03*
X1550121Y651956D03*
Y656356D03*
X1541321Y660756D03*
X1550121D03*
X1545721D03*
X1532521D03*
X1536921D03*
X1642921Y-35764D03*
Y-58764D03*
X1637921Y-35764D03*
Y-58764D03*
X1632921Y-35764D03*
Y-58764D03*
X1627921D03*
X1622921D03*
X1627921Y-35764D03*
X1617921Y-58764D03*
X1622921Y-35764D03*
X1612921Y-58764D03*
X1617921Y-35764D03*
X1607921Y-58764D03*
X1612921Y-35764D03*
X1602921Y-58764D03*
X1607921Y-35764D03*
X1597921Y-58764D03*
X1602921Y-35764D03*
X1592921Y-58764D03*
X1597921Y-35764D03*
X1592921D03*
X1647921D03*
Y-58764D03*
X1625106Y638753D03*
X1625121Y647556D03*
X1630121Y643156D03*
X1630106Y638753D03*
X1630121Y647556D03*
X1635121Y643156D03*
X1635106Y638753D03*
X1635121Y647556D03*
X1640121Y643156D03*
Y647556D03*
X1640106Y638753D03*
X1650121Y647556D03*
X1650106Y638753D03*
X1650121Y643156D03*
X1645121Y647556D03*
X1645106Y638753D03*
X1645121Y643156D03*
X1625121D03*
X1620121Y647556D03*
X1620106Y638753D03*
X1620121Y643156D03*
X1615121Y647556D03*
X1615106Y638753D03*
X1615121Y643156D03*
X1610121Y647556D03*
X1610106Y638753D03*
X1610121Y643156D03*
X1605121Y647556D03*
X1605106Y638753D03*
X1605121Y643156D03*
X1600121Y647556D03*
X1600106Y638753D03*
X1600121Y643156D03*
X1595121Y647556D03*
X1595106Y638753D03*
X1595121Y643156D03*
X1625121Y651956D03*
Y660756D03*
X1630121Y651956D03*
Y656356D03*
Y660756D03*
X1635121Y651956D03*
Y656356D03*
Y660756D03*
X1625121Y656356D03*
X1640121D03*
Y651956D03*
X1650121Y660756D03*
Y656356D03*
Y651956D03*
X1645121Y660756D03*
Y656356D03*
Y651956D03*
X1640121Y660756D03*
X1620121D03*
Y656356D03*
Y651956D03*
X1615121Y660756D03*
Y656356D03*
Y651956D03*
X1610121Y660756D03*
Y656356D03*
Y651956D03*
X1605121Y660756D03*
Y656356D03*
Y651956D03*
X1600121Y660756D03*
Y656356D03*
Y651956D03*
X1595121Y660756D03*
Y656356D03*
Y651956D03*
X1692921Y-40764D03*
X1702921Y-54764D03*
X1687921D03*
X1682921D03*
X1677921D03*
X1672921D03*
X1692921D03*
X1697921D03*
X1707921D03*
X1712921D03*
X1697921Y-40764D03*
X1692921Y-50764D03*
X1687921D03*
X1682921D03*
X1677921D03*
X1672921D03*
X1712921D03*
X1707921D03*
X1702921D03*
X1697921Y-45764D03*
X1707921D03*
X1702921D03*
X1712921D03*
X1697921Y-50764D03*
X1667921Y-35764D03*
X1712921D03*
Y-58764D03*
X1707921Y-35764D03*
Y-58764D03*
X1702921Y-35764D03*
Y-58764D03*
X1697921Y-35764D03*
Y-58764D03*
X1687921Y-40764D03*
X1672921Y-45764D03*
X1677921D03*
X1682921D03*
Y-40764D03*
X1687921Y-45764D03*
X1692921D03*
X1667921Y-58764D03*
X1662921Y-35764D03*
Y-58764D03*
X1657921Y-35764D03*
Y-58764D03*
X1652921Y-35764D03*
Y-58764D03*
X1712921Y-40764D03*
X1707921D03*
X1702921D03*
X1677921D03*
X1672921D03*
X1677921Y-35764D03*
Y-58764D03*
X1672921Y-35764D03*
Y-58764D03*
X1682921Y-35764D03*
Y-58764D03*
X1692921Y-35764D03*
Y-58764D03*
X1687921Y-35764D03*
Y-58764D03*
X1690121Y647556D03*
X1710121D03*
X1710106Y638753D03*
X1710121Y643156D03*
X1705121Y647556D03*
X1705106Y638753D03*
X1695121Y643156D03*
X1695106Y638753D03*
X1695121Y647556D03*
X1700121Y643156D03*
X1700106Y638753D03*
X1685121Y647556D03*
X1685106Y638753D03*
X1685121Y643156D03*
X1680121Y647556D03*
X1680106Y638753D03*
X1680121Y643156D03*
X1675121Y647556D03*
X1675106Y638753D03*
X1675121Y643156D03*
X1670121Y647556D03*
X1670106Y638753D03*
X1670121Y643156D03*
X1665121Y647556D03*
X1665106Y638753D03*
X1665121Y643156D03*
X1660121Y647556D03*
X1660106Y638753D03*
X1660121Y643156D03*
X1655121Y647556D03*
X1655106Y638753D03*
X1655121Y643156D03*
X1690121D03*
X1690106Y638753D03*
X1700121Y647556D03*
X1705121Y643156D03*
X1690121Y656356D03*
Y651956D03*
X1710121Y660756D03*
Y656356D03*
Y651956D03*
X1705121Y660756D03*
Y656356D03*
Y651956D03*
X1690121Y660756D03*
X1695121Y651956D03*
Y656356D03*
Y660756D03*
X1685121Y651956D03*
X1680121Y660756D03*
Y656356D03*
Y651956D03*
X1675121Y660756D03*
Y656356D03*
Y651956D03*
X1670121Y660756D03*
Y656356D03*
Y651956D03*
X1665121Y660756D03*
Y656356D03*
Y651956D03*
X1660121Y660756D03*
Y656356D03*
Y651956D03*
X1655121Y660756D03*
Y656356D03*
Y651956D03*
X1685121Y660756D03*
Y656356D03*
X1700121Y651956D03*
Y656356D03*
Y660756D03*
X1737921Y-50764D03*
X1722921Y-45764D03*
X1727921D03*
X1732921D03*
X1747921D03*
X1752921D03*
X1727921Y-54764D03*
X1757921D03*
X1717921D03*
X1722921D03*
X1767921Y-40764D03*
Y-50764D03*
X1762921D03*
X1757921D03*
X1762921Y-54764D03*
X1752921D03*
X1747921D03*
X1742921D03*
X1737921D03*
X1732921D03*
X1772921D03*
X1767921D03*
X1762921Y-40764D03*
X1772921D03*
X1722921Y-50764D03*
X1717921D03*
X1732921D03*
X1757921Y-40764D03*
X1717921Y-45764D03*
Y-58764D03*
X1742921Y-50764D03*
X1747921D03*
X1752921D03*
X1742921Y-58764D03*
X1737921Y-35764D03*
Y-58764D03*
X1732921Y-35764D03*
Y-58764D03*
X1727921Y-35764D03*
Y-58764D03*
X1722921Y-35764D03*
Y-58764D03*
X1717921Y-35764D03*
X1757921Y-45764D03*
X1762921D03*
X1742921D03*
X1752921Y-40764D03*
X1747921D03*
X1742921D03*
X1737921D03*
X1732921D03*
X1727921D03*
X1722921D03*
X1717921D03*
X1727921Y-50764D03*
X1767921Y-45764D03*
X1772921D03*
X1737921D03*
X1772921Y-35764D03*
Y-58764D03*
X1767921Y-35764D03*
Y-58764D03*
X1762921Y-35764D03*
Y-58764D03*
X1757921Y-35764D03*
Y-58764D03*
X1752921Y-35764D03*
Y-58764D03*
X1747921Y-35764D03*
Y-58764D03*
X1742921Y-35764D03*
X1772921Y-50764D03*
X1775121Y643156D03*
Y647556D03*
X1775106Y638753D03*
X1730121Y647556D03*
X1730106Y638753D03*
X1730121Y643156D03*
X1725121Y647556D03*
X1725106Y638753D03*
X1725121Y643156D03*
X1720121Y647556D03*
X1720106Y638753D03*
X1720121Y643156D03*
X1715121Y647556D03*
X1715106Y638753D03*
X1715121Y643156D03*
X1770121Y647556D03*
X1770106Y638753D03*
X1770121Y643156D03*
X1765121Y647556D03*
X1765106Y638753D03*
X1765121Y643156D03*
X1760121Y647556D03*
X1760106Y638753D03*
X1760121Y643156D03*
X1755121Y647556D03*
X1755106Y638753D03*
X1755121Y643156D03*
X1750121Y647556D03*
X1750106Y638753D03*
X1750121Y643156D03*
X1745121Y647556D03*
X1745106Y638753D03*
X1745121Y643156D03*
X1740121Y647556D03*
X1740106Y638753D03*
X1740121Y643156D03*
X1735121Y647556D03*
X1735106Y638753D03*
X1735121Y643156D03*
X1770121Y660756D03*
X1775121D03*
Y656356D03*
Y651956D03*
X1725121Y660756D03*
Y656356D03*
Y651956D03*
X1720121Y660756D03*
Y656356D03*
Y651956D03*
X1715121Y660756D03*
Y656356D03*
Y651956D03*
X1770121D03*
X1765121Y660756D03*
Y656356D03*
Y651956D03*
X1760121Y660756D03*
Y656356D03*
Y651956D03*
X1755121Y660756D03*
Y656356D03*
Y651956D03*
X1750121Y660756D03*
Y656356D03*
Y651956D03*
X1745121Y660756D03*
Y656356D03*
Y651956D03*
X1740121Y660756D03*
Y656356D03*
Y651956D03*
X1735121Y660756D03*
Y656356D03*
Y651956D03*
X1730121Y660756D03*
Y656356D03*
X1770121D03*
X1730121Y651956D03*
X1817921Y-40764D03*
X1832921Y-45764D03*
Y-54764D03*
X1827921D03*
X1822921D03*
X1817921D03*
X1812921D03*
X1807921D03*
X1802921D03*
X1797921D03*
X1792921D03*
X1787921D03*
X1782921D03*
X1777921D03*
X1832921Y-50764D03*
X1827921D03*
X1822921D03*
X1817921D03*
X1812921D03*
X1807921D03*
X1802921D03*
X1797921D03*
X1792921D03*
X1787921D03*
X1782921Y-40764D03*
X1792921D03*
X1802921D03*
X1807921D03*
X1822921D03*
X1827921D03*
X1832921D03*
X1812921D03*
X1797921D03*
X1777921Y-45764D03*
X1782921D03*
X1787921D03*
X1792921D03*
X1797921D03*
X1802921D03*
X1807921D03*
X1812921D03*
X1817921D03*
X1822921D03*
X1787921Y-40764D03*
X1832921Y-35764D03*
Y-58764D03*
X1827921Y-35764D03*
Y-58764D03*
X1822921Y-35764D03*
Y-58764D03*
X1817921Y-35764D03*
Y-58764D03*
X1812921Y-35764D03*
Y-58764D03*
X1807921Y-35764D03*
Y-58764D03*
X1802921Y-35764D03*
Y-58764D03*
X1797921Y-35764D03*
Y-58764D03*
X1792921Y-35764D03*
Y-58764D03*
X1787921Y-35764D03*
Y-58764D03*
X1782921Y-35764D03*
Y-58764D03*
X1777921Y-35764D03*
Y-58764D03*
X1782921Y-50764D03*
X1777921D03*
Y-40764D03*
X1827921Y-45764D03*
X1794992Y61342D03*
X1797664Y61334D03*
X1797645Y64153D03*
X1792382Y61363D03*
X1792363Y64182D03*
X1794973Y64161D03*
X1807891Y62180D03*
X1810563Y62172D03*
X1810693Y59493D03*
X1808021Y59501D03*
X1805411Y59522D03*
X1813393Y59493D03*
X1813363Y62172D03*
X1810578Y56866D03*
X1805282Y56880D03*
X1807916Y56895D03*
X1813278Y56866D03*
X1805281Y62201D03*
X1831148Y144592D03*
X1836200Y153424D03*
X1833000D03*
X1833600Y145900D03*
X1793205Y165531D03*
X1793268Y162774D03*
X1780121Y643156D03*
X1780106Y638753D03*
X1780121Y647556D03*
X1785121Y643156D03*
X1790121D03*
X1835121Y647556D03*
X1835106Y638753D03*
X1835121Y643156D03*
X1830121Y647556D03*
X1830106Y638753D03*
X1830121Y643156D03*
X1825121Y647556D03*
X1825106Y638753D03*
X1825121Y643156D03*
X1820121Y647556D03*
X1820106Y638753D03*
X1820121Y643156D03*
X1815121Y647556D03*
X1815106Y638753D03*
X1815121Y643156D03*
X1810121Y647556D03*
X1810106Y638753D03*
X1810121Y643156D03*
X1805121Y647556D03*
X1805106Y638753D03*
X1805121Y643156D03*
X1800121Y647556D03*
X1800106Y638753D03*
X1800121Y643156D03*
X1795121Y647556D03*
X1795106Y638753D03*
X1795121Y643156D03*
X1790121Y647556D03*
X1790106Y638753D03*
X1785121Y647556D03*
X1785106Y638753D03*
X1800121Y656356D03*
X1780121Y651956D03*
Y656356D03*
Y660756D03*
X1835121D03*
Y656356D03*
Y651956D03*
X1830121Y660756D03*
Y656356D03*
Y651956D03*
X1825121Y660756D03*
Y656356D03*
Y651956D03*
X1820121Y660756D03*
Y656356D03*
Y651956D03*
X1815121Y660756D03*
Y656356D03*
Y651956D03*
X1810121Y660756D03*
Y656356D03*
Y651956D03*
X1805121Y660756D03*
Y656356D03*
Y651956D03*
X1800121Y660756D03*
Y651956D03*
X1795121Y660756D03*
Y656356D03*
Y651956D03*
X1790121Y660756D03*
Y656356D03*
Y651956D03*
X1785121Y660756D03*
Y656356D03*
Y651956D03*
X1857921Y-45764D03*
X1837921D03*
X1897921D03*
X1892921D03*
X1887921D03*
X1882921D03*
X1877921D03*
X1872921D03*
X1867921D03*
X1862921D03*
X1842921Y-54764D03*
X1852921Y-45764D03*
X1847921D03*
X1842921D03*
X1897921Y-54764D03*
X1892921D03*
X1887921D03*
X1882921D03*
X1877921D03*
X1872921D03*
X1867921D03*
X1862921D03*
X1857921D03*
X1852921D03*
X1847921D03*
X1837921D03*
X1897921Y-50764D03*
X1892921D03*
X1887921D03*
X1882921D03*
X1877921D03*
X1872921D03*
X1867921D03*
X1862921D03*
X1857921D03*
X1852921D03*
X1847921D03*
X1842921D03*
X1837921D03*
X1892921Y-40764D03*
X1897921D03*
X1877921D03*
X1882921D03*
X1887921D03*
X1857921D03*
X1862921D03*
X1867921D03*
X1872921D03*
X1837921D03*
X1842921D03*
X1847921D03*
X1852921D03*
Y-35764D03*
Y-58764D03*
X1847921Y-35764D03*
Y-58764D03*
X1842921Y-35764D03*
Y-58764D03*
X1837921Y-35764D03*
Y-58764D03*
X1862921D03*
X1857921Y-35764D03*
Y-58764D03*
X1882921D03*
X1877921Y-35764D03*
Y-58764D03*
X1872921Y-35764D03*
Y-58764D03*
X1867921Y-35764D03*
Y-58764D03*
X1862921Y-35764D03*
X1897921D03*
Y-58764D03*
X1892921Y-35764D03*
Y-58764D03*
X1887921Y-35764D03*
Y-58764D03*
X1882921Y-35764D03*
X1847797Y26331D03*
X1847564Y21636D03*
X1844732Y-7874D03*
X1851030Y1139D03*
Y-16889D03*
X1858880Y2178D03*
X1858879Y-17927D03*
X1868132Y5626D03*
Y-21374D03*
X1877691Y1668D03*
X1877683Y-17425D03*
X1881632Y-7874D03*
X1895121Y647556D03*
X1895106Y638753D03*
X1895121Y643156D03*
X1890121Y647556D03*
X1890106Y638753D03*
X1890121Y643156D03*
X1885121Y647556D03*
X1885106Y638753D03*
X1885121Y643156D03*
X1880121Y647556D03*
X1880106Y638753D03*
X1880121Y643156D03*
X1875121Y647556D03*
X1875106Y638753D03*
X1875121Y643156D03*
X1870121Y647556D03*
X1870106Y638753D03*
X1870121Y643156D03*
X1865121Y647556D03*
X1865106Y638753D03*
X1865121Y643156D03*
X1860121Y647556D03*
X1860106Y638753D03*
X1860121Y643156D03*
X1855121Y647556D03*
X1855106Y638753D03*
X1855121Y643156D03*
X1850121Y647556D03*
X1850106Y638753D03*
X1850121Y643156D03*
X1845121Y647556D03*
X1845106Y638753D03*
X1845121Y643156D03*
X1840121Y647556D03*
X1840106Y638753D03*
X1840121Y643156D03*
X1844732Y610630D03*
X1851030Y619643D03*
Y601615D03*
X1858880Y620682D03*
X1858879Y600577D03*
X1868132Y624130D03*
Y597130D03*
X1877691Y620172D03*
X1877683Y601079D03*
X1881632Y610630D03*
X1895121Y660756D03*
Y656356D03*
Y651956D03*
X1890121Y660756D03*
Y656356D03*
Y651956D03*
X1885121Y660756D03*
Y656356D03*
Y651956D03*
X1880121Y660756D03*
Y656356D03*
Y651956D03*
X1875121Y660756D03*
Y656356D03*
Y651956D03*
X1870121Y660756D03*
Y656356D03*
Y651956D03*
X1865121Y660756D03*
Y656356D03*
Y651956D03*
X1860121Y660756D03*
Y656356D03*
Y651956D03*
X1855121Y660756D03*
Y656356D03*
Y651956D03*
X1850121Y660756D03*
Y656356D03*
Y651956D03*
X1845121Y660756D03*
Y656356D03*
Y651956D03*
X1840121Y660756D03*
Y656356D03*
Y651956D03*
X1927921Y-40764D03*
X1947921Y-45764D03*
X1942921D03*
X1937921D03*
X1932921D03*
X1927921D03*
X1922921D03*
X1917921D03*
X1912921D03*
X1907921D03*
X1902921D03*
X1927921Y-50764D03*
X1932921D03*
Y-40764D03*
X1937921D03*
X1942921D03*
X1947921D03*
X1907921Y-50764D03*
X1902921D03*
X1922921Y-40764D03*
X1917921D03*
X1912921D03*
X1907921D03*
X1902921D03*
X1922921Y-54764D03*
X1917921D03*
X1912921D03*
X1907921D03*
X1902921D03*
X1927921D03*
X1932921D03*
X1937921D03*
X1942921D03*
X1947921D03*
X1952921D03*
X1957921D03*
Y-50764D03*
X1952921D03*
X1947921D03*
X1942921D03*
X1937921D03*
X1922921D03*
X1917921D03*
X1912921D03*
X1957921Y-35764D03*
Y-58764D03*
X1952921Y-35764D03*
Y-58764D03*
X1947921Y-35764D03*
Y-58764D03*
X1942921Y-35764D03*
Y-58764D03*
X1937921Y-35764D03*
Y-58764D03*
X1932921Y-35764D03*
Y-58764D03*
X1927921Y-35764D03*
Y-58764D03*
X1922921Y-35764D03*
Y-58764D03*
X1917921Y-35764D03*
Y-58764D03*
X1912921Y-35764D03*
Y-58764D03*
X1907921Y-35764D03*
Y-58764D03*
X1902921Y-35764D03*
Y-58764D03*
X1960106Y638753D03*
X1955106D03*
X1950106D03*
X1945121Y647556D03*
Y643156D03*
X1945106Y638753D03*
X1940121Y647556D03*
Y643156D03*
X1940106Y638753D03*
X1935121Y647556D03*
Y643156D03*
X1935106Y638753D03*
X1930106D03*
X1925106D03*
X1920121Y647556D03*
X1910121Y643156D03*
X1910106Y638753D03*
X1905121Y647556D03*
Y643156D03*
X1905106Y638753D03*
X1900121Y647556D03*
X1900106Y638753D03*
X1900121Y643156D03*
X1920106Y638753D03*
X1915121Y647556D03*
X1920121Y643156D03*
X1910121Y647556D03*
X1915106Y638753D03*
X1915121Y643156D03*
X1960121Y656356D03*
Y660756D03*
X1955121Y656356D03*
Y660756D03*
X1950121Y651956D03*
Y656356D03*
Y660756D03*
X1945121Y651956D03*
Y656356D03*
Y660756D03*
X1940121Y651956D03*
Y656356D03*
Y660756D03*
X1935121Y651956D03*
Y656356D03*
Y660756D03*
X1930121Y651956D03*
Y656356D03*
Y660756D03*
X1925121Y651956D03*
Y656356D03*
Y660756D03*
X1920121Y651956D03*
Y656356D03*
X1905121Y651956D03*
Y656356D03*
Y660756D03*
X1900121D03*
Y656356D03*
Y651956D03*
X1915121D03*
Y656356D03*
Y660756D03*
X1920121D03*
X1910121D03*
Y656356D03*
Y651956D03*
X1967921Y-45764D03*
X1962921D03*
Y-40764D03*
X1967921D03*
Y-54764D03*
X1962921D03*
X1967921Y-50764D03*
X1962921D03*
X1967921Y-35764D03*
Y-58764D03*
X1962921Y-35764D03*
Y-58764D03*
X1970121Y647556D03*
Y643156D03*
X1970106Y638753D03*
X1965121Y647556D03*
Y643156D03*
X1965106Y638753D03*
X1970121Y651956D03*
Y656356D03*
Y660756D03*
X1965121Y651956D03*
Y656356D03*
Y660756D03*
G54D11*
X0Y0D03*
G54D20*
X320784Y203219D03*
X330948Y201258D03*
X401377Y65822D03*
X411416D03*
X401377Y529022D03*
X411416D03*
X434842Y65822D03*
X428149D03*
X458640Y200596D03*
X428149Y529022D03*
X434842D03*
X970392Y203219D03*
X980556Y201258D03*
X1050985Y65822D03*
X1061024D03*
X1084450D03*
X1077757D03*
X1050985Y529022D03*
X1061024D03*
X1084450D03*
X1077757D03*
X1108248Y200596D03*
X1111631Y198327D03*
X1451753Y276753D03*
X1454902Y279902D03*
X1445454Y270454D03*
X1448603Y273603D03*
X1454902Y305098D03*
X1448603Y311397D03*
X1458051Y301949D03*
X1464351Y295649D03*
Y289351D03*
X1458051Y283051D03*
X1489546Y270454D03*
X1486397Y273603D03*
X1483247Y276753D03*
X1470649Y295649D03*
Y289351D03*
X1480098Y305098D03*
X1476949Y301949D03*
X1486397Y311397D03*
X1489546Y314546D03*
X1483247Y308247D03*
X1476949Y283051D03*
X1606470Y93759D03*
X1638938Y109192D03*
X1638250Y125750D03*
X1651536Y121790D03*
X1638938Y118641D03*
X1645378Y128378D03*
X1638902Y112305D03*
X1648430Y150163D03*
X1638937Y131239D03*
Y143837D03*
Y137538D03*
X1638938Y153286D03*
X1616900Y153200D03*
X1629489Y150136D03*
X1616891Y146987D03*
X1616893Y140782D03*
X1635788Y137538D03*
Y143837D03*
Y131239D03*
X1616891Y134389D03*
X1629489Y137538D03*
Y143837D03*
Y131239D03*
X1620040Y106042D03*
X1623189Y118640D03*
X1629489D03*
X1610793Y109190D03*
X1607441Y118640D03*
X1616891Y124939D03*
X1596220Y109470D03*
X1613741Y115491D03*
X1602717Y102240D03*
X1620040Y162735D03*
X1627998Y172854D03*
X1601142Y172185D03*
X1674685Y134217D03*
X1693625Y133220D03*
X1680402Y128652D03*
X1678127Y117293D03*
X1673883Y124308D03*
X1654685Y146987D03*
X1654678Y137530D03*
X1657835Y134389D03*
X1671000Y103000D03*
X1709000Y127200D03*
X1691207Y139891D03*
X1667284Y137537D03*
X1657835Y124940D03*
Y150136D03*
X1667284Y121790D03*
Y128089D03*
Y150136D03*
X1664134Y140688D03*
X1668213Y172608D03*
X1729444Y123782D03*
X1726294Y101785D03*
X1742212Y117451D03*
X1717014Y108000D03*
Y139500D03*
X1739064Y108000D03*
X1742214Y101700D03*
X1745364Y114300D03*
X1755089Y150750D03*
X1752189Y136750D03*
X1752389Y132250D03*
X1754189Y124250D03*
X1757689Y123850D03*
X1752889Y146250D03*
X1745364Y145800D03*
X1731903Y133712D03*
X1720164Y97550D03*
Y111150D03*
X1723314D03*
Y117450D03*
X1720164Y120600D03*
Y133200D03*
Y126800D03*
X1751800Y141700D03*
X1742214Y98550D03*
Y126900D03*
X1745364Y120600D03*
X1742214Y111150D03*
X1739064Y114300D03*
G54D30*
X1949650Y220787D03*
Y228661D03*
G54D21*
X1392264Y23976D03*
X1513918D03*
G54D12*
G01X38645Y172740D02*
X44291Y178386D01*
G01D02*
X49937Y184032D01*
G01X38645D02*
X44291Y178386D01*
G01D02*
X49937Y172740D01*
G01X-7615D02*
X-1969Y178386D01*
G01D02*
X3677Y184032D01*
G01X-7615D02*
X-1969Y178386D01*
G01D02*
X3677Y172740D01*
G01X12582D02*
X18228Y178386D01*
G01D02*
X23874Y184032D01*
G01X12582D02*
X18228Y178386D01*
G01D02*
X23874Y172740D01*
G01X12129Y430711D02*
X15512Y434094D01*
G01D02*
X18895Y437477D01*
G01X12129D02*
X15512Y434094D01*
G01D02*
X18895Y430711D01*
G01X430749Y-124922D02*
G02I-12000J0D01*
G01X425599D02*
G02I-6850J0D01*
G01X434749D02*
X402749D01*
G01X434749Y-140922D02*
Y-220922D01*
G01D02*
X1729349D01*
G01X434749Y-176422D02*
X1729349D01*
G01X418749Y-140922D02*
Y-108922D01*
G01X434749Y-140922D02*
X1729349D01*
G01X941849D02*
Y-220922D01*
G01X1079349Y-140922D02*
Y-220922D01*
G01X1194349Y-140922D02*
Y-220922D01*
G01X1361849Y-140922D02*
Y-220922D01*
G01X1389729Y21441D02*
X1392264Y23976D01*
G01D02*
X1394799Y26511D01*
G01X1389729D02*
X1392264Y23976D01*
G01D02*
X1394799Y21441D01*
G01X1511383D02*
X1513918Y23976D01*
G01D02*
X1516453Y26511D01*
G01X1511383D02*
X1513918Y23976D01*
G01D02*
X1516453Y21441D01*
G01X1531849Y-140922D02*
Y-220922D01*
G01X1644721Y-2921D02*
X1647327Y-315D01*
G01D02*
X1649933Y2291D01*
G01X1644721D02*
X1647327Y-315D01*
G01D02*
X1649933Y-2921D01*
G01X1729349Y-140922D02*
Y-220922D01*
G01X1757349Y-124922D02*
G02I-12000J0D01*
G01X1752199D02*
G02I-6850J0D01*
G01X1745349Y-140922D02*
Y-108922D01*
G01X1761349Y-124922D02*
X1729349D01*
G01X1947447Y214597D02*
X1950000Y207893D01*
G01X1947447Y203241D02*
X1950000Y207893D01*
G01X1959921Y209074D02*
X1961890Y211043D01*
G01X1950000Y220787D02*
X1953630Y217612D01*
G01X1946370D02*
X1950000Y220787D01*
G01X1947447Y234851D02*
X1950000Y241555D01*
G01Y234851D02*
Y241555D01*
G01X1959921Y240374D02*
X1961890Y238405D01*
G01X1946370Y231836D02*
X1950000Y228661D01*
G01D02*
X1953630Y225486D01*
G01X1950000Y228661D02*
X1953630Y231836D01*
G01X1946370Y223962D02*
X1950000Y220787D01*
G01D02*
X1953630Y223962D01*
G01X1967468Y212037D02*
X1970670Y207007D01*
G01X1967468Y201977D02*
X1970670Y207007D01*
G01X1961890Y211043D02*
X1963859Y213012D01*
G01X1961890Y211043D02*
X1963859Y209074D01*
G01X1967468Y237411D02*
X1970670Y242441D01*
G01Y237411D02*
Y242441D01*
G01X1961890Y238405D02*
X1963859Y240374D01*
G01X1961890Y238405D02*
X1963859Y236436D01*
X-20700Y31400D03*
Y25200D03*
Y22300D03*
Y28100D03*
X-20600Y41200D03*
X-20526Y44263D03*
X-20500Y60300D03*
Y57300D03*
X-20700Y48800D03*
X-20726Y37463D03*
X-20800Y34400D03*
X-20500Y54300D03*
Y51300D03*
X-18000Y247400D03*
X-15000D03*
X-18000Y262700D03*
X-15000D03*
X-14690Y471140D03*
X-16726Y503651D03*
X-17084Y467626D03*
X-17300Y530800D03*
X-17397Y564242D03*
X30600Y-12000D03*
X25838Y-20458D03*
X10600Y25100D03*
X1068Y24831D03*
X27102Y25383D03*
X39530Y5205D03*
X45670Y5185D03*
X33370D03*
X45429Y-4669D03*
X33628Y131D03*
X40994Y-7148D03*
X45700Y40D03*
X11539Y31427D03*
X27200Y30600D03*
X27239Y28027D03*
X25600Y32500D03*
X11600Y33944D03*
X26760Y49595D03*
X27800Y86900D03*
X22100Y56400D03*
X27800Y89900D03*
Y83900D03*
X30400Y89800D03*
Y86800D03*
Y83800D03*
X10925Y56167D03*
X27904Y56294D03*
X30686Y79943D03*
X23530Y94840D03*
X11030D03*
X13530D03*
X16030D03*
X18530D03*
X22380Y92670D03*
X21030Y94840D03*
X2380Y92670D03*
X4880D03*
X7380D03*
X9880D03*
X12380D03*
X14880D03*
X17380D03*
X19880D03*
X3530Y94840D03*
X6030D03*
X8530D03*
X-1000Y81500D03*
X24880Y92670D03*
X25870Y80880D03*
X28294Y80889D03*
X32500Y81791D03*
X25100Y56300D03*
X-1190Y53240D03*
X25886Y71467D03*
X25925Y75867D03*
X26185Y67017D03*
X27488Y64671D03*
X11925Y65311D03*
X27625Y73967D03*
X27525Y69367D03*
X11925Y67811D03*
X11864Y62794D03*
X24064Y61894D03*
X15111Y62553D03*
X27564Y61894D03*
X11600Y36444D03*
X25900Y40300D03*
X27564Y59394D03*
X24064D03*
X25700Y36200D03*
X27300Y34300D03*
Y38300D03*
X27208Y42313D03*
X27239Y47027D03*
X25700Y44400D03*
X27525Y77867D03*
X44200Y139400D03*
X44300Y144800D03*
X44200Y130700D03*
Y116800D03*
X44100Y97800D03*
X44200Y111500D03*
X44300Y102700D03*
Y125600D03*
X44600Y154100D03*
X7995Y285385D03*
X32450Y454050D03*
X35100Y453900D03*
X35900Y423500D03*
X43550Y431300D03*
X20075Y424850D03*
X12025Y427900D03*
X7025D03*
X2025D03*
X21397Y439354D03*
Y444354D03*
X18836Y441785D03*
X7736D03*
X-6104Y461190D03*
X5000Y469000D03*
X10443Y490649D03*
X40132Y499800D03*
X24400Y519500D03*
X280Y524350D03*
X40185Y482918D03*
X37568Y482836D03*
X26780Y488910D03*
X21000Y495800D03*
X13300Y509600D03*
X13600Y504300D03*
X4000Y509500D03*
X2485Y498185D03*
X13700Y498500D03*
X24591Y479139D03*
X35896Y557668D03*
X33396D03*
X38696D03*
X-10200Y558200D03*
X21700Y532300D03*
X19100D03*
X27000D03*
X1040Y531218D03*
X21948Y566700D03*
X19448D03*
X27114Y557563D03*
X24748Y566700D03*
X0Y566800D03*
X29400Y532300D03*
X46400Y536290D03*
Y539790D03*
X43505Y538714D03*
X43241Y535965D03*
X41500Y533800D03*
X29914Y557563D03*
X45880Y554710D03*
Y557820D03*
X46560Y581000D03*
Y577500D03*
X1500Y540600D03*
X15787Y551700D03*
X17100Y545400D03*
X13639Y534683D03*
Y537183D03*
X15800Y543300D03*
X15600Y539100D03*
X17139Y534683D03*
Y537183D03*
X17100Y541200D03*
X17035Y549558D03*
X15800Y547500D03*
X17139Y553683D03*
X1500Y543100D03*
X1439Y538083D03*
X15800Y579500D03*
Y575300D03*
X17108Y585513D03*
X17156Y581481D03*
X17100Y577400D03*
X17139Y573183D03*
X1500Y576600D03*
X17139Y570683D03*
X1500Y579100D03*
X1439Y574083D03*
X15770Y587700D03*
X15800Y583500D03*
X27495Y591409D03*
X-12450Y590965D03*
X30212Y591417D03*
X35085Y591621D03*
X32609Y591538D03*
X46500Y595190D03*
X43190Y598410D03*
X43210Y595180D03*
X43190Y601910D03*
X17139Y589683D03*
X65800Y14200D03*
X59061Y476D03*
X61152Y-12752D03*
X59281Y-20641D03*
X99102Y-12010D03*
X105892Y8700D03*
X62076Y5575D03*
X76247Y1189D03*
X84202Y-11395D03*
X81702D03*
X79202D03*
X73611Y1158D03*
X71111D03*
X68611D03*
X73574Y-1437D03*
X71074D03*
X68574D03*
X79500Y-16600D03*
X55713Y-5095D03*
X76165Y-1415D03*
X106200Y26500D03*
X102100Y73800D03*
X105892Y45290D03*
X52500Y67200D03*
Y63700D03*
Y60700D03*
Y37700D03*
Y34700D03*
Y43700D03*
Y40700D03*
Y57700D03*
X71050Y89600D03*
X48700Y90700D03*
Y95500D03*
X61300Y89800D03*
X81861Y93392D03*
X108385Y84291D03*
X63737Y130602D03*
X48900Y132600D03*
X68592D03*
X85250Y127680D03*
X77730Y126860D03*
X63858Y97620D03*
X66600Y102360D03*
X62422Y109413D03*
X68000Y111000D03*
X48900Y123500D03*
X62524Y123395D03*
X68584Y123900D03*
X68654Y118680D03*
X48800Y118900D03*
X48700Y109600D03*
X48600Y104900D03*
X63582Y116409D03*
X62502Y105100D03*
X52500Y152000D03*
X60300Y151500D03*
X70800Y151400D03*
X48800Y137600D03*
X63878Y144800D03*
X68632Y137800D03*
X63888Y140064D03*
X107254Y128041D03*
X106698Y215610D03*
X100500Y188600D03*
X97500Y185700D03*
X104800D03*
X102400D03*
X99900D03*
X77650Y178150D03*
X73500Y191500D03*
X107750Y238730D03*
X83300Y267400D03*
X108000Y249330D03*
X53400Y277582D03*
Y274500D03*
X48800Y282600D03*
Y285100D03*
X53500Y307300D03*
X85300Y335750D03*
X69500Y322000D03*
X103500Y302100D03*
X99770Y325249D03*
X67400Y391690D03*
X67230Y397380D03*
X67710Y402040D03*
X55616Y368998D03*
X52000Y354500D03*
X61000Y383000D03*
X57500Y388100D03*
X77300Y390600D03*
X107224Y393848D03*
X76500Y368300D03*
X76300Y358400D03*
X82037Y358542D03*
X70600Y368400D03*
X82100Y368300D03*
X70900Y358300D03*
X51500Y406000D03*
X57471Y410749D03*
X64007Y408276D03*
X63630Y424280D03*
X63600Y429000D03*
X51890Y424470D03*
Y418970D03*
X103100Y411800D03*
X72603Y474072D03*
X60300Y508650D03*
X51607Y511747D03*
X74480Y504480D03*
X79630Y504580D03*
X60000Y526500D03*
X79400Y502150D03*
X74600Y502064D03*
X77000Y502133D03*
X49800Y524300D03*
X76996Y504587D03*
X60700Y521900D03*
X57936Y516012D03*
X60202Y495342D03*
X57302Y495442D03*
X105958Y518550D03*
X106392Y537000D03*
X105392Y574800D03*
X105412Y556580D03*
X105000Y614533D03*
X82459Y618932D03*
X105352Y594770D03*
X101898Y611483D03*
X150391Y14814D03*
X163427Y14714D03*
X157084Y14814D03*
X160431Y-1801D03*
X153738Y9114D03*
X150391Y-7851D03*
X163391D03*
X157084D03*
X153738Y-1751D03*
X160431Y9114D03*
X126616Y14714D03*
X136756Y16900D03*
X120273Y16839D03*
X132959Y14814D03*
X141880Y17114D03*
X147045Y9114D03*
X130163D03*
X141856Y9100D03*
X136780Y9098D03*
X123620Y9114D03*
X126580Y-7851D03*
X132959Y-7700D03*
X120273Y-9901D03*
X141893Y-9864D03*
X136806Y-9650D03*
X136780Y-1801D03*
X123620D03*
X130313Y-1751D03*
X141906Y-2050D03*
X147045Y-1751D03*
X169770Y14814D03*
X167124Y-1751D03*
X169770Y-7700D03*
X166974Y9114D03*
X169770Y30100D03*
X120273Y27899D03*
X141893Y27936D03*
X136806Y28150D03*
X126580Y29949D03*
X132959Y30100D03*
X157084Y29949D03*
X163391D03*
X150391D03*
X169770Y90364D03*
X166974Y84714D03*
Y73849D03*
Y46914D03*
X169770Y52614D03*
X167124Y36049D03*
X169770Y67900D03*
X157084Y67749D03*
X163391D03*
X130313Y73849D03*
X123620Y73799D03*
X141906Y73550D03*
X136780Y73799D03*
X126580Y67749D03*
X132959Y67900D03*
X141880Y54914D03*
X123620Y35983D03*
X141856Y46900D03*
X141906Y35750D03*
X136806Y65950D03*
X141893Y65736D03*
X136756Y54700D03*
X136780Y35999D03*
X130313Y35983D03*
X123620Y46914D03*
X132959Y52614D03*
X126616Y52514D03*
X147045Y46914D03*
Y36049D03*
X120273Y54839D03*
Y92500D03*
X126616Y90314D03*
X132959Y90414D03*
X141880Y92714D03*
X163427Y90314D03*
X157084Y90414D03*
X150391D03*
X160431Y84714D03*
X153738D03*
X136756Y92500D03*
X141856Y84700D03*
X136780Y84698D03*
X123620Y84714D03*
X147045D03*
X130163D03*
Y46914D03*
X136780Y46898D03*
X120273Y66000D03*
X147045Y73849D03*
X153738Y36049D03*
Y73849D03*
X160431Y73799D03*
X157084Y52614D03*
X160431Y35999D03*
X150391Y67749D03*
Y52614D03*
X163427Y52514D03*
X160431Y46914D03*
X153738D03*
X156954Y192872D03*
X154454Y193021D03*
X151810Y192670D03*
X124895Y212033D03*
X153788Y187309D03*
X156928Y190053D03*
X148900Y180400D03*
X148800Y185300D03*
Y182900D03*
X148900Y190100D03*
X148800Y187700D03*
X113800Y180500D03*
X116900D03*
X151359Y187700D03*
X156294Y187625D03*
X151300Y190200D03*
X141263Y215216D03*
X125563Y218616D03*
X137763Y217716D03*
X128500Y218700D03*
X141263Y217716D03*
X137763Y215216D03*
X154130Y190186D03*
X169150Y223600D03*
Y227600D03*
X112904Y237218D03*
X122820Y244133D03*
X123074Y275948D03*
X113100Y269163D03*
X125624Y223633D03*
Y221133D03*
X141263Y234216D03*
X141200Y229600D03*
X141211Y225615D03*
X141300Y221700D03*
X139763Y231700D03*
Y227600D03*
Y223700D03*
X139582Y219800D03*
X128200Y250700D03*
X125563Y250616D03*
X141263Y249716D03*
Y247216D03*
X137763D03*
Y249716D03*
X125624Y255633D03*
X141300Y253700D03*
X139631Y251900D03*
X125624Y253133D03*
X137763Y279216D03*
X141263Y266216D03*
X139763Y255700D03*
Y259600D03*
X139800Y263700D03*
X141313Y257533D03*
X141263Y279216D03*
X141200Y261600D03*
X137300Y337200D03*
X118800Y298400D03*
X123301Y308044D03*
X110180Y280920D03*
X109960Y313190D03*
X119050Y341625D03*
X113000Y304000D03*
X113100Y333106D03*
X125624Y287633D03*
X128200Y282600D03*
X141263Y311216D03*
X137763D03*
X141263Y281716D03*
X139730Y284200D03*
X139763Y288200D03*
Y292000D03*
Y296000D03*
X125624Y285133D03*
X141200Y286100D03*
X141261Y290076D03*
X141300Y294000D03*
X141263Y298216D03*
X137763Y281716D03*
X125563Y282616D03*
X141211Y325515D03*
X128200Y314800D03*
X141263Y330216D03*
X139763Y327800D03*
X141300Y317500D03*
Y321500D03*
X139582Y315800D03*
X139763Y319400D03*
X125563Y314616D03*
X141263Y313716D03*
X137763D03*
X139763Y323600D03*
X125624Y317133D03*
Y319633D03*
X109640Y376070D03*
X113500Y369000D03*
X110670Y344500D03*
X112600Y366300D03*
X122300Y372100D03*
X119300Y400900D03*
X110397Y402603D03*
X109924Y393848D03*
X141289Y349488D03*
X128100Y346700D03*
X141300Y353300D03*
X141200Y357200D03*
X137763Y345716D03*
X141263D03*
Y343216D03*
X125624Y349133D03*
X137763Y343216D03*
X141263Y362216D03*
X139582Y347800D03*
X139763Y351400D03*
Y355200D03*
Y359500D03*
X125624Y351633D03*
X125563Y346616D03*
X141300Y381800D03*
X139763Y384000D03*
X125624Y381133D03*
X141263Y394216D03*
Y390416D03*
X141261Y385876D03*
X139736Y392300D03*
X125563Y378616D03*
X137763Y375216D03*
X141263D03*
Y377716D03*
X137763D03*
X139631Y379900D03*
X128500Y378700D03*
X139900Y388000D03*
X125624Y383633D03*
X117363Y417416D03*
X130163Y510114D03*
X147045D03*
X132959Y515814D03*
X126616Y515714D03*
X120273Y517900D03*
X136780Y510098D03*
X136756Y517900D03*
X141856Y510100D03*
X141880Y518114D03*
X123620Y510114D03*
X150391Y515814D03*
X169770Y515764D03*
X163427Y515714D03*
X166974Y510114D03*
X160431D03*
X157084Y515814D03*
X153738Y510114D03*
X141893Y528936D03*
X136806Y529150D03*
X141906Y536750D03*
X132959Y553614D03*
X126616Y553514D03*
X130163Y547914D03*
X123620D03*
X136780Y547898D03*
X141856Y547900D03*
X147045Y537049D03*
Y547914D03*
X120210Y529200D03*
X130313Y537049D03*
X132959Y531100D03*
X126580Y530949D03*
X123620Y536999D03*
X136780D03*
X123620Y574799D03*
X130313Y574849D03*
X132959Y568900D03*
X126580Y568749D03*
X141856Y585700D03*
X141906Y574550D03*
X136780Y574799D03*
Y585698D03*
X120092Y566900D03*
X136806Y566950D03*
X147045Y585714D03*
Y574849D03*
X141880Y555914D03*
X120273Y555700D03*
X136756D03*
X141893Y566736D03*
X130163Y585714D03*
X123620D03*
X150391Y530949D03*
Y553614D03*
X166974Y537049D03*
X163391Y530949D03*
X160431Y536999D03*
X169770Y553564D03*
X163427Y553514D03*
X166974Y547914D03*
X160431D03*
X157084Y530949D03*
X153738Y537049D03*
X157084Y553614D03*
X153738Y547914D03*
X169770Y531100D03*
X150391Y568749D03*
X163391D03*
X160431Y585714D03*
X166974D03*
Y574849D03*
X160431Y574799D03*
X169770Y568900D03*
X157084Y568749D03*
X153738Y585714D03*
Y574849D03*
X147045Y612649D03*
X123620Y612599D03*
X136780D03*
X130313Y612649D03*
X160431Y612599D03*
X166974Y612649D03*
X153738D03*
X126616Y591314D03*
X116992Y590700D03*
X132959Y591414D03*
X136756Y593500D03*
X141880Y593714D03*
X132959Y606700D03*
X126580Y606549D03*
X120092Y604900D03*
X141906Y612350D03*
X136806Y604750D03*
X141893Y604536D03*
X150391Y591414D03*
Y606549D03*
X163427Y591314D03*
X163391Y606549D03*
X169770Y606700D03*
Y591364D03*
X157084Y591414D03*
Y606549D03*
X173591Y-1801D03*
X178691Y17114D03*
X173567Y16900D03*
X178717Y-2050D03*
X183856Y-1751D03*
X173617Y-9650D03*
X178704Y-9864D03*
X178667Y9100D03*
X173591Y9098D03*
X183856Y9114D03*
X178704Y27936D03*
X173617Y28150D03*
X190549Y9114D03*
X197242D03*
X210402Y9098D03*
X210428Y-9650D03*
X193895Y-7851D03*
X187202D03*
X200202D03*
X210402Y-1801D03*
X190549Y-1751D03*
X197242Y-1801D03*
X203935Y-1751D03*
X206581Y-7700D03*
X203785Y9114D03*
X210378Y16900D03*
X210428Y28150D03*
X200202Y29949D03*
X187202D03*
X193895Y14814D03*
Y29949D03*
X200238Y14714D03*
X187202Y14814D03*
X206581D03*
Y30100D03*
X220667Y-1751D03*
X215528Y-2050D03*
X215515Y-9864D03*
X227360Y-1751D03*
X230706Y-7851D03*
X224013D03*
X215478Y9100D03*
X220667Y9114D03*
X227360D03*
X224013Y29949D03*
X230706D03*
Y14814D03*
X224013D03*
X215502Y17114D03*
X215515Y27936D03*
X178691Y92714D03*
X173591Y84698D03*
X178667Y84700D03*
X183856Y84714D03*
X173567Y92500D03*
X183856Y36049D03*
X173591Y46898D03*
X183856Y73849D03*
X178717Y73550D03*
X173591Y73799D03*
X178691Y54914D03*
X173591Y35999D03*
X183856Y46914D03*
X178717Y35750D03*
X178667Y46900D03*
X173567Y54700D03*
X173617Y65950D03*
X178704Y65736D03*
X206581Y52614D03*
X210378Y54700D03*
X210402Y46898D03*
X193895Y67749D03*
X200202D03*
X187202D03*
X203785Y46914D03*
X190549D03*
X197242D03*
X200238Y52514D03*
X193895Y52614D03*
X187202D03*
X190549Y36049D03*
X203935D03*
X197242Y35999D03*
X206581Y67900D03*
X210428Y65950D03*
X210402Y35999D03*
X197242Y73799D03*
X203935Y73849D03*
X210402Y73799D03*
Y84698D03*
X210378Y92500D03*
X190549Y73849D03*
Y84714D03*
X197242D03*
X203785D03*
X193895Y90414D03*
X206581D03*
X200238Y90314D03*
X187202Y90414D03*
X215478Y46900D03*
X215502Y54914D03*
X215515Y65736D03*
X224013Y52614D03*
X220667Y46914D03*
X230706Y52614D03*
X224013Y67749D03*
X230706D03*
X227360Y46914D03*
Y36049D03*
X220667D03*
X215528Y35750D03*
X215502Y92714D03*
X220667Y73849D03*
Y84714D03*
X227360D03*
X230706Y90414D03*
X215478Y84700D03*
X215528Y73550D03*
X227360Y73849D03*
X224013Y90414D03*
X197617Y243089D03*
X191537Y242989D03*
Y240489D03*
X197617Y240589D03*
X191537Y237989D03*
X197617Y238089D03*
X192037Y270750D03*
X194537D03*
X197037D03*
X194537Y299750D03*
X197037D03*
X192037D03*
X194537Y332480D03*
X197037D03*
X192037D03*
X194500Y360200D03*
X197137Y360350D03*
X191900Y360173D03*
X195200Y377800D03*
Y380300D03*
X172697Y407196D03*
X197242Y510114D03*
X200238Y515714D03*
X203785Y510114D03*
X190549D03*
X187202Y515814D03*
X193895D03*
X183856Y510114D03*
X173591Y510098D03*
X173567Y517900D03*
X178691Y518114D03*
X206581Y515814D03*
X210402Y510098D03*
X210378Y517900D03*
X215502Y518114D03*
X215478Y510100D03*
X224013Y515814D03*
X220667Y510114D03*
X227360D03*
X230706Y515814D03*
X193895Y553614D03*
X200238Y553514D03*
X183856Y547914D03*
X190549D03*
X203785D03*
X197242D03*
X190549Y537049D03*
X183856D03*
X187202Y530949D03*
X193895D03*
X197242Y536999D03*
X203935Y537049D03*
X200202Y530949D03*
X206581Y553614D03*
X210402Y547898D03*
X178717Y536750D03*
X173617Y529150D03*
X173591Y536999D03*
X178704Y528936D03*
X178667Y547900D03*
X173591Y547898D03*
X206581Y531100D03*
X210402Y536999D03*
X210428Y529150D03*
X187202Y553614D03*
X178691Y555914D03*
X173567Y555700D03*
X210378D03*
X203935Y574849D03*
X200202Y568749D03*
X197242Y574799D03*
X190549Y585714D03*
X183856D03*
X187202Y568749D03*
X193895D03*
X190549Y574849D03*
X183856D03*
X210402Y585698D03*
X206581Y568900D03*
X210428Y566950D03*
X210402Y574799D03*
X178667Y585700D03*
X178717Y574550D03*
X173591Y574799D03*
Y585698D03*
X173617Y566950D03*
X178704Y566736D03*
X197242Y585714D03*
X203785D03*
X215515Y528936D03*
X215528Y536750D03*
X215478Y547900D03*
X224013Y530949D03*
X220667Y537049D03*
X230706Y530949D03*
X227360Y537049D03*
X230706Y553614D03*
X220667Y547914D03*
X227360D03*
X224013Y553614D03*
X215502Y555914D03*
X220667Y585714D03*
X215528Y574550D03*
X215478Y585700D03*
X215515Y566736D03*
X224013Y568749D03*
X220667Y574849D03*
X230706Y568749D03*
X227360Y574849D03*
Y585714D03*
Y612649D03*
X220667D03*
X203935D03*
X197242Y612599D03*
X190549Y612649D03*
X183856D03*
X210402Y612599D03*
X173591D03*
X187202Y591414D03*
X193895D03*
X187202Y606549D03*
X193895D03*
X200202D03*
X210428Y604750D03*
X206581Y606700D03*
X210378Y593500D03*
X206581Y591414D03*
X178717Y612350D03*
X173617Y604750D03*
X178704Y604536D03*
X173567Y593500D03*
X178691Y593714D03*
X200238Y591314D03*
X224013Y606549D03*
X230706D03*
Y591414D03*
X215515Y604536D03*
X215528Y612350D03*
X215502Y593714D03*
X224013Y591414D03*
X270864Y-1801D03*
X247213D03*
X240746Y-1751D03*
X264171D03*
X252339Y-2050D03*
X234053Y-1801D03*
X257478Y-1751D03*
X243392Y-7700D03*
X260824Y-7851D03*
X252326Y-9864D03*
X237013Y-7851D03*
X247239Y-9650D03*
X267517Y-7851D03*
X252289Y9100D03*
X264171Y9114D03*
X240596D03*
X247213Y9098D03*
X270864Y9114D03*
X234053D03*
X257478D03*
X267517Y14814D03*
Y29949D03*
X247189Y16900D03*
X252326Y27936D03*
X243392Y30100D03*
X247239Y28150D03*
X260824Y29949D03*
X237013D03*
X252313Y17114D03*
X243392Y14814D03*
X260824D03*
X237049Y14714D03*
X284050Y-9650D03*
X289137Y-9864D03*
X273824Y-7851D03*
X280203Y-7700D03*
X289100Y9100D03*
X284024Y9098D03*
X277407Y9114D03*
X277557Y-1751D03*
X289150Y-2050D03*
X284024Y-1801D03*
X273824Y29949D03*
X273860Y14714D03*
X284000Y16900D03*
X280203Y14814D03*
Y30100D03*
X289124Y17114D03*
X284050Y28150D03*
X289137Y27936D03*
X247213Y46898D03*
X257478Y46914D03*
X240596D03*
X243392Y67900D03*
X267517Y67749D03*
Y52614D03*
X270864Y46914D03*
X252326Y65736D03*
X237013Y67749D03*
X260824D03*
X247239Y65950D03*
X243392Y52614D03*
X264171Y46914D03*
X247213Y35999D03*
X257478Y36049D03*
X252339Y35750D03*
X234053Y35999D03*
X240746Y36049D03*
X264171D03*
X237049Y52514D03*
X252289Y46900D03*
X247189Y54700D03*
X252313Y54914D03*
X260824Y52614D03*
X270864Y35999D03*
X234053Y46914D03*
X247213Y73799D03*
Y84698D03*
X264171Y84714D03*
X252339Y73550D03*
X257478Y84714D03*
X240746Y73849D03*
X257478D03*
X234053Y73799D03*
X264171Y73849D03*
X243392Y90414D03*
X252313Y92714D03*
X237049Y90314D03*
X270864Y84714D03*
X247189Y92500D03*
X240596Y84714D03*
X234053D03*
X252289Y84700D03*
X260824Y90414D03*
X267517D03*
X270864Y73799D03*
X273824Y67749D03*
X280203Y67900D03*
X284024Y35999D03*
X277557Y36049D03*
X277407Y46914D03*
X289137Y65736D03*
X284050Y65950D03*
X284024Y46898D03*
X284000Y54700D03*
X289100Y46900D03*
X289150Y35750D03*
X289124Y54914D03*
X280203Y52614D03*
X273860Y90314D03*
X277407Y84714D03*
X289100Y84700D03*
X284024Y84698D03*
X284000Y92500D03*
X289150Y73550D03*
X284024Y73799D03*
X289124Y92714D03*
X280203Y90414D03*
X277407Y73849D03*
X264171Y104284D03*
X267517Y109984D03*
X270864Y104284D03*
X257478D03*
X260824Y109984D03*
X243392Y109534D03*
X252339Y112865D03*
X247213Y113114D03*
X237049Y109884D03*
X240596Y104284D03*
X247239Y105265D03*
X252326Y105051D03*
X234053Y104284D03*
X273860Y109884D03*
X284050Y105265D03*
X289137Y105051D03*
X289150Y112865D03*
X284024Y113114D03*
X280203Y109534D03*
X277407Y104284D03*
X271239Y211060D03*
X284759Y207159D03*
X291519D03*
X274619Y213009D03*
Y216909D03*
X277999Y211060D03*
Y214960D03*
Y203260D03*
Y207159D03*
X281379Y213009D03*
X288139Y216909D03*
X284759Y214960D03*
X291519D03*
Y218860D03*
X281379Y201309D03*
X284759Y199360D03*
X291519D03*
X267859Y244209D03*
Y240309D03*
X271239Y238360D03*
X264179D03*
Y250060D03*
X264092Y222710D03*
X264179Y226660D03*
X271239Y269560D03*
Y273460D03*
Y265660D03*
X267859Y263709D03*
Y259809D03*
X264179Y265660D03*
X267859Y252009D03*
X264179Y253960D03*
X291519Y238360D03*
X284759Y234460D03*
X288139Y232509D03*
X281379D03*
X277999Y234460D03*
X274619Y232509D03*
Y220809D03*
Y224709D03*
Y228610D03*
X277999Y230559D03*
X274619Y244209D03*
X277999Y250060D03*
X274619Y240309D03*
Y248109D03*
Y236409D03*
X291519Y246160D03*
Y250060D03*
X284759Y246160D03*
X291519Y242260D03*
X281379Y220809D03*
X284759Y226660D03*
X288139Y236409D03*
X291519Y234460D03*
Y222760D03*
Y230559D03*
Y226660D03*
X281379Y240309D03*
Y252009D03*
X274619D03*
X277999Y253960D03*
X284759D03*
X291519D03*
X284759Y265660D03*
X291519D03*
Y277360D03*
X281379Y275409D03*
Y271509D03*
X284759Y277360D03*
Y273460D03*
X288139Y275409D03*
Y271509D03*
X277999Y277360D03*
X274619Y255909D03*
Y259809D03*
X277999Y269560D03*
X274619Y275409D03*
Y267609D03*
Y263709D03*
X288139Y255909D03*
X291519Y269560D03*
Y257860D03*
Y261760D03*
X281379Y259809D03*
X288139Y252009D03*
X271239Y328060D03*
X267859Y333909D03*
Y341709D03*
Y330009D03*
X264179Y328060D03*
Y339760D03*
X291519Y285160D03*
Y292959D03*
X284759Y285160D03*
X277999Y308560D03*
Y300760D03*
Y292959D03*
Y285160D03*
X291519Y308560D03*
X284759D03*
Y300760D03*
X291519D03*
X284759Y292959D03*
X291519Y316360D03*
X281379Y318309D03*
X291519Y328060D03*
X288139Y341709D03*
X274619Y330009D03*
Y326110D03*
Y322209D03*
X277999Y328060D03*
X274619Y341709D03*
X277999Y320260D03*
Y316360D03*
X274619Y333909D03*
Y337809D03*
X284759Y324160D03*
X288139Y318309D03*
X284759Y316360D03*
X281379Y337809D03*
X291519Y339760D03*
Y335860D03*
X284759Y331960D03*
X291519D03*
X281379Y326110D03*
X288139D03*
X267559Y369010D03*
X271239Y355360D03*
X267859Y349509D03*
Y353409D03*
X267559Y361209D03*
X264179Y343660D03*
Y355360D03*
X267492Y380709D03*
X271239Y390460D03*
X267859Y388509D03*
X271239Y382660D03*
X284759Y351460D03*
X281379Y345609D03*
X291519Y359260D03*
Y355360D03*
Y351460D03*
X284759Y343660D03*
X274619Y365109D03*
X277999Y363160D03*
Y367060D03*
X274619Y369010D03*
Y361209D03*
Y345609D03*
X277999Y347560D03*
X274619Y353409D03*
Y357309D03*
Y349509D03*
X277999Y343660D03*
X291519Y347560D03*
Y343660D03*
X288139Y365109D03*
X281379D03*
X284759Y363160D03*
X291519D03*
X284759Y370959D03*
X291519Y367060D03*
Y370959D03*
X288139Y361209D03*
X281379Y357309D03*
X288139Y345609D03*
Y380709D03*
Y400209D03*
X274619Y380709D03*
X277999Y394359D03*
X274619Y392410D03*
X277999Y390460D03*
Y386560D03*
X274619Y376809D03*
Y372909D03*
X291519Y374860D03*
X277999Y382660D03*
X284759Y398260D03*
X281379Y396309D03*
X291519Y398260D03*
X284759Y390460D03*
X291519D03*
X281379Y376809D03*
Y384609D03*
X284759Y382660D03*
X291519D03*
Y378760D03*
X264171Y510114D03*
X257478D03*
X260824Y515814D03*
Y491044D03*
X247177Y490514D03*
X252313D03*
X236892Y493400D03*
X243392Y493094D03*
X267584Y491219D03*
X271092Y495944D03*
X257392Y495800D03*
X264192D03*
X233292Y495900D03*
X239492Y498500D03*
X247177Y498514D03*
X252313D03*
X252289Y510100D03*
X267517Y515814D03*
X270864Y510114D03*
X247189Y517900D03*
X252313Y518114D03*
X247213Y510098D03*
X240596Y510114D03*
X243392Y515814D03*
X234053Y510114D03*
X237049Y515714D03*
X284024Y490644D03*
X289124D03*
X273860Y515714D03*
X277557Y495944D03*
X277407Y510114D03*
X289100Y510100D03*
X289124Y518114D03*
X284024Y510098D03*
X280203Y515814D03*
X273992Y491144D03*
X280203Y490644D03*
X284024Y498644D03*
X289124D03*
X284000Y517900D03*
X257478Y537049D03*
X237013Y530949D03*
X252339Y536750D03*
X243392Y531100D03*
X247213Y536999D03*
X252326Y528936D03*
X240746Y537049D03*
X234053Y536999D03*
X267517Y553614D03*
X270864Y547914D03*
X267517Y530949D03*
X270864Y536999D03*
X260824Y553614D03*
X237049Y553514D03*
X243392Y553614D03*
X264171Y547914D03*
X257478D03*
X252289Y547900D03*
X240596Y547914D03*
X247213Y547898D03*
X234053Y547914D03*
X264171Y537049D03*
X260824Y530949D03*
X247189Y555700D03*
X252313Y555914D03*
X270864Y574799D03*
Y585714D03*
X267517Y568749D03*
X247239Y566950D03*
X252326Y566736D03*
X234053Y574799D03*
X240746Y574849D03*
X247213Y574799D03*
X234053Y585714D03*
X237013Y568749D03*
X264171Y585714D03*
X257478D03*
X264171Y574849D03*
X257478D03*
X260824Y568749D03*
X252339Y574550D03*
X252289Y585700D03*
X240596Y585714D03*
X247213Y585698D03*
X243392Y568900D03*
X277407Y537049D03*
X273824Y530949D03*
X273860Y553514D03*
X284024Y547898D03*
X289100Y547900D03*
X280203Y553614D03*
Y531100D03*
X284024Y536999D03*
X289137Y528936D03*
X284050Y529150D03*
X289150Y536750D03*
X277407Y547914D03*
X273824Y568749D03*
X284000Y555700D03*
X289124Y555914D03*
X280203Y568900D03*
X277407Y574849D03*
Y585714D03*
X289100Y585700D03*
X289150Y574550D03*
X284024Y574799D03*
Y585698D03*
X284050Y566950D03*
X289137Y566736D03*
X284024Y612599D03*
X240746Y612649D03*
X247213Y612599D03*
X234053D03*
X257478Y612649D03*
X247239Y604750D03*
X252326Y604536D03*
X260824Y606549D03*
X237013D03*
X243392Y606700D03*
X264171Y612449D03*
X252339Y612350D03*
X267517Y591414D03*
X260824D03*
X237049Y591314D03*
X247189Y593500D03*
X252313Y593714D03*
X243392Y591414D03*
X267517Y606549D03*
X270864Y612399D03*
X273824Y606549D03*
X273860Y591314D03*
X284050Y604750D03*
X289150Y612350D03*
X280203Y606700D03*
Y591414D03*
X277407Y612449D03*
X289124Y593714D03*
X284000Y593500D03*
X289137Y604536D03*
X297635Y-7851D03*
X304328D03*
X300982Y-1751D03*
X294289D03*
Y9114D03*
X300982D03*
X307675Y-1843D03*
Y9300D03*
X304328Y29949D03*
X307992Y13200D03*
X297635Y14814D03*
X321192Y13200D03*
X321334Y32100D03*
X308092D03*
X297635Y29949D03*
X304328Y14814D03*
X334292Y13200D03*
Y32100D03*
X317714Y65814D03*
X307950Y50729D03*
X300982Y36049D03*
X294289Y46914D03*
X304328Y52614D03*
X321192Y51000D03*
X307675Y35957D03*
X304328Y67749D03*
X297635D03*
X294289Y36049D03*
X300982Y46914D03*
X297635Y52614D03*
X327754Y65814D03*
Y92757D03*
X331100Y84714D03*
Y73757D03*
X317714Y89964D03*
X321061Y87392D03*
Y73757D03*
X307992Y70400D03*
X304278Y90414D03*
X307592Y73800D03*
X300982Y84714D03*
X294289D03*
X300982Y73849D03*
X294289D03*
X308166Y87394D03*
X297635Y90414D03*
X334292Y51000D03*
X337793Y65814D03*
X347833Y65822D03*
Y92757D03*
X351179Y84599D03*
Y73757D03*
X337793Y89964D03*
X341140Y87392D03*
Y73757D03*
X300992Y112300D03*
X297642Y107700D03*
X304192Y105000D03*
X324492Y103500D03*
X294899Y213009D03*
X308418Y201309D03*
X317428Y193507D03*
X301648Y194841D03*
X332078Y218860D03*
X329818Y214958D03*
X298279Y218860D03*
X311798Y211060D03*
Y218860D03*
Y214960D03*
X308418Y213009D03*
X305039Y211060D03*
Y218860D03*
X324200Y201308D03*
X298279Y199360D03*
X294899Y201309D03*
X312918Y205210D03*
X315178Y209109D03*
X298279Y207159D03*
Y203260D03*
Y211060D03*
X318558Y218860D03*
X315178Y216909D03*
Y213009D03*
X301659Y209109D03*
X325318Y211060D03*
X334328Y199108D03*
X348978Y209109D03*
X352357Y211060D03*
X338838Y211058D03*
X335458Y216909D03*
X355737Y209109D03*
X294899Y224709D03*
X332078Y242260D03*
Y250060D03*
X328698Y232509D03*
Y220809D03*
X332078Y234460D03*
X298279Y246160D03*
X325318Y250060D03*
X321938Y248109D03*
X305039Y246160D03*
X308418Y244209D03*
X294899D03*
Y248109D03*
X325318Y242260D03*
Y226660D03*
X298279Y234460D03*
X308418Y228610D03*
Y224709D03*
X305039Y230559D03*
X311798Y222760D03*
X308418Y232509D03*
X294899Y228610D03*
X325318Y234460D03*
Y230559D03*
Y222760D03*
X305039Y250060D03*
X318558Y246160D03*
X301659Y248109D03*
X308418Y240309D03*
X315178D03*
X301659D03*
X318558Y242260D03*
X298279Y226660D03*
X318558D03*
X315178Y220809D03*
X321938D03*
X315178Y232509D03*
X301659Y228610D03*
X308418Y236409D03*
X321938D03*
X311798Y238360D03*
X318558D03*
X305039Y226660D03*
X308418Y252009D03*
X298279Y253960D03*
X325318D03*
X308418Y275409D03*
X301659D03*
X308418Y255909D03*
X321938Y275409D03*
X315178Y279310D03*
X318558Y277360D03*
X311798Y261760D03*
X321938Y259809D03*
X301659D03*
X308418Y263709D03*
X325318Y269560D03*
X305039D03*
X318558D03*
X328698Y267609D03*
Y259809D03*
X332078Y269560D03*
X321938Y255909D03*
X308418Y259809D03*
X325318Y273460D03*
Y265660D03*
X301659Y267609D03*
X321938Y263709D03*
X294899Y275409D03*
Y263709D03*
X298279Y265660D03*
X305039Y273460D03*
Y277360D03*
X311798D03*
Y269560D03*
X305039Y265660D03*
X298279Y277360D03*
X328698Y252009D03*
X348978Y220809D03*
X352357Y238360D03*
X345598D03*
X342218Y220809D03*
X338838Y246160D03*
X335458Y248109D03*
X338838Y242260D03*
Y234460D03*
X335458Y236409D03*
X338838Y238360D03*
X335458Y224709D03*
X355737Y248109D03*
X348978D03*
X355737Y220809D03*
X338838Y253960D03*
X335458Y252009D03*
X338838Y265660D03*
X335458Y259809D03*
Y267609D03*
X345598Y265660D03*
X348978Y263709D03*
X355737Y259809D03*
X352357Y261760D03*
X345598Y273460D03*
Y269560D03*
X342218Y263709D03*
Y271509D03*
Y259809D03*
Y255909D03*
Y267609D03*
Y279310D03*
Y275409D03*
X311798Y292959D03*
X305039D03*
X321938Y283209D03*
X315178D03*
X318558Y281260D03*
Y292959D03*
X311798Y285160D03*
X328698Y310509D03*
X332078Y300760D03*
X328698Y283209D03*
X332078Y292959D03*
Y281260D03*
X298279Y308560D03*
X321938Y310509D03*
X315178D03*
X305039Y308560D03*
X311798D03*
X305039Y300760D03*
X325318D03*
X311798D03*
X298279D03*
X318558D03*
X325318Y292959D03*
Y281260D03*
X305039Y285160D03*
X298279D03*
Y292959D03*
X318558Y312460D03*
X325318D03*
X308418Y333909D03*
Y341709D03*
X325318Y339760D03*
Y335860D03*
X301659Y337809D03*
X315178Y330009D03*
X301659D03*
X308418Y337809D03*
X305039Y331960D03*
X298279Y328060D03*
Y331960D03*
X311798Y324160D03*
X308418Y330009D03*
X315178Y322209D03*
X321938D03*
X294899Y333909D03*
X305039Y328060D03*
X321938Y330009D03*
Y337809D03*
X328698Y330009D03*
Y326110D03*
Y333909D03*
X325318Y324160D03*
X318558Y320260D03*
X301659Y318309D03*
X308418D03*
X305039Y316360D03*
X332078Y331960D03*
Y339760D03*
X298279Y316360D03*
X294899Y322209D03*
Y318309D03*
X311798Y316360D03*
X308418Y326110D03*
X315178Y314409D03*
X332078Y312460D03*
X335458Y310509D03*
X338838Y300760D03*
Y292959D03*
Y281260D03*
X335458Y283209D03*
X342218Y310509D03*
Y283209D03*
X345598Y335860D03*
Y331960D03*
X342218Y314409D03*
X338838Y312460D03*
Y316360D03*
X335458Y330009D03*
X338838Y331960D03*
Y339760D03*
X345598Y328060D03*
Y339760D03*
X352357Y335860D03*
X348978Y333909D03*
X342218Y322209D03*
Y318309D03*
Y330009D03*
Y326110D03*
Y333909D03*
X355737Y337809D03*
X345598Y320260D03*
Y324160D03*
X308418Y357309D03*
X311798Y359260D03*
X298279Y351460D03*
X294899Y349509D03*
Y353409D03*
X321938Y349509D03*
X318558Y359260D03*
X321938Y361209D03*
X298279Y343660D03*
X315178Y357309D03*
X301659D03*
Y349509D03*
X308418Y361209D03*
Y353409D03*
Y345609D03*
X305039Y347560D03*
X325318Y343660D03*
Y347560D03*
X328698Y365109D03*
X332078Y363160D03*
X328698Y345609D03*
X325318Y355360D03*
X332078Y347560D03*
Y355360D03*
X294899Y369010D03*
X325318Y367060D03*
Y370959D03*
X318558D03*
X308418Y365109D03*
X315178D03*
X325318Y363160D03*
X298279D03*
X305039Y370959D03*
X308418Y369010D03*
X305039Y367060D03*
X301659Y369010D03*
X298279Y370959D03*
X318558Y351460D03*
Y355360D03*
X305039Y351460D03*
X301659Y388509D03*
X308418D03*
X318558Y394359D03*
X324458Y399911D03*
X332078Y378760D03*
X318558Y386560D03*
X325318D03*
X311798Y374860D03*
X325318D03*
X294899Y372909D03*
X308418D03*
X321938Y376809D03*
X318558Y382660D03*
Y378760D03*
X298279D03*
X305039D03*
X308418Y384609D03*
X311798Y382660D03*
Y378760D03*
X315178Y376809D03*
X328698D03*
X294899Y384609D03*
X318558Y390460D03*
X320808Y401941D03*
X298279Y386560D03*
Y390460D03*
X315178Y392410D03*
Y388509D03*
X311798Y386560D03*
X298279Y398260D03*
Y394359D03*
X294899Y396309D03*
X325318Y378760D03*
X321938Y380709D03*
X305039Y394359D03*
X302608Y402421D03*
X352357Y359260D03*
X338838Y347560D03*
X335458Y361209D03*
X338838Y359260D03*
Y355360D03*
Y351460D03*
X335458Y349509D03*
X345598Y359260D03*
X348978Y349509D03*
X345598Y343660D03*
X342218Y345609D03*
X355737Y349509D03*
Y376809D03*
Y388509D03*
X348978Y376809D03*
X342218Y388509D03*
Y376809D03*
X335458Y372909D03*
Y384609D03*
Y380709D03*
X345598Y390460D03*
X352357Y386560D03*
X294289Y490444D03*
X301092Y490700D03*
X317714Y515364D03*
X321061Y512792D03*
X331100Y510114D03*
X327754Y518157D03*
X297835Y497644D03*
X308166Y512794D03*
X300982Y510114D03*
X304278Y515814D03*
X297635D03*
X294289Y510114D03*
X304392Y497300D03*
X324187Y499793D03*
X337793Y515364D03*
X350882Y509999D03*
X347833Y518157D03*
X341140Y512792D03*
X321061Y536957D03*
X317714Y529014D03*
X331100Y536957D03*
X327754Y529014D03*
X307675Y548200D03*
X304278Y553614D03*
X297635D03*
X300982Y547914D03*
X294289D03*
X307675Y536957D03*
X304328Y530949D03*
X300982Y537049D03*
X297635Y530949D03*
X294289Y537049D03*
X307992Y533100D03*
X321123Y552000D03*
X308100D03*
X307992Y570900D03*
X321334D03*
X294289Y574849D03*
Y585714D03*
X304328Y568749D03*
X307675Y574757D03*
X300982Y574849D03*
X307848Y588334D03*
X300982Y585714D03*
X297635Y568749D03*
X334292Y552000D03*
X337793Y529014D03*
X351179Y536957D03*
X347833Y529022D03*
X341140Y536957D03*
X334292Y570900D03*
X304328Y606549D03*
X297635D03*
X294289Y612249D03*
X300982D03*
X307675Y611600D03*
X307892Y591000D03*
X321192Y589800D03*
X304278Y591414D03*
X297635D03*
X334292Y589800D03*
X375792Y6500D03*
X377592Y-10880D03*
X380232Y-10900D03*
X380200Y-1200D03*
X378792Y6500D03*
X358592Y30736D03*
X380792Y27812D03*
X357492Y14314D03*
X380792Y24933D03*
X357492Y11714D03*
X358619Y33342D03*
X394192Y-9700D03*
X409522Y-20794D03*
X408184Y32100D03*
Y13200D03*
X357762Y49659D03*
X371042Y46900D03*
X380792Y56500D03*
X357762Y52333D03*
X357872Y65736D03*
X357965Y92500D03*
X357872Y87500D03*
X358491Y73479D03*
X374292Y77200D03*
Y74100D03*
X408184Y51000D03*
X401375Y92757D03*
X398029Y84800D03*
Y73742D03*
X408068Y87392D03*
X411415Y89964D03*
X408069Y73742D03*
X386292Y98800D03*
X408126Y105750D03*
X414820Y105800D03*
X401375D03*
X362497Y209109D03*
X382777D03*
X376017D03*
X389537D03*
X415634Y204496D03*
Y212296D03*
X396296Y209109D03*
X415634Y208397D03*
X407706Y209109D03*
X379397Y238360D03*
X362497Y220809D03*
X379397Y250060D03*
X369257Y220809D03*
X382777D03*
X376017D03*
X386157Y238360D03*
X372637Y250060D03*
X389537Y248109D03*
Y220809D03*
X376017Y248109D03*
X382777D03*
X386157Y250060D03*
X359117Y238360D03*
X365877D03*
X372637D03*
X365877Y253960D03*
X362497Y255909D03*
X359117Y257860D03*
X369257Y252009D03*
X392916Y250060D03*
Y238360D03*
X396296Y248109D03*
Y220809D03*
X399676Y250060D03*
X407706Y248109D03*
X415634Y247396D03*
Y235696D03*
Y223996D03*
X407706Y220809D03*
X370650Y312441D03*
X378156D03*
X375674D03*
X373162Y312400D03*
X368165Y312504D03*
X359117Y339760D03*
X362497Y341709D03*
X379397Y359260D03*
X382777Y349509D03*
X379397Y347560D03*
X369257Y345609D03*
X376017D03*
X386157Y351460D03*
Y359260D03*
X372637Y347560D03*
X389537Y353409D03*
X372637Y359260D03*
X365877D03*
X359117D03*
X365877Y343660D03*
X376017Y376809D03*
X369257D03*
X382777Y388509D03*
X369257D03*
X362497D03*
X376017D03*
X389537D03*
Y376809D03*
X382777D03*
X362497D03*
X396296Y353409D03*
X411086Y351460D03*
X405306Y347109D03*
X399676Y351460D03*
X392916D03*
Y359260D03*
X396296Y388509D03*
Y376809D03*
X411086Y374860D03*
X403056Y376809D03*
Y388509D03*
X385244Y504027D03*
X359042Y515200D03*
X358918Y510114D03*
X401375Y518157D03*
X398029Y509999D03*
X411415Y515364D03*
X408068Y512792D03*
X357539Y550511D03*
X376829Y546303D03*
X357539Y553111D03*
X376785Y538305D03*
X363760Y529293D03*
X357872Y528942D03*
X357910Y536727D03*
X357724Y569474D03*
X376892Y577500D03*
X356798Y588366D03*
X357724Y571973D03*
X398029Y536942D03*
X408069D03*
X408184Y552000D03*
Y570900D03*
X413324Y623559D03*
X399824D03*
X356798Y590939D03*
X373400Y593800D03*
X376204Y593650D03*
X374039Y611186D03*
X408184Y589800D03*
X447744Y-7180D03*
X451573Y-1801D03*
Y9114D03*
X436392Y-20760D03*
X422892Y-20789D03*
X448226Y28100D03*
X433508Y32100D03*
X448292Y31900D03*
X421368Y32100D03*
X433508Y13200D03*
X448292Y13700D03*
X421368Y13200D03*
X448892Y17000D03*
X458266Y-1751D03*
X460912Y-7700D03*
X454533Y-7851D03*
X458116Y9114D03*
X469832Y-2051D03*
X464732Y-1801D03*
X474998Y-1751D03*
X469845Y-9864D03*
X478344Y-7851D03*
X464758Y-9652D03*
X474998Y9114D03*
X464732Y9098D03*
X478344Y29949D03*
X460912Y30100D03*
Y14814D03*
X469832Y17114D03*
X454569Y14714D03*
X454533Y29949D03*
X469792Y9300D03*
X478344Y14814D03*
X469845Y27936D03*
X464792Y28100D03*
X464692Y16900D03*
X448414Y35761D03*
X448973Y54883D03*
X451573Y35999D03*
X448517Y46975D03*
X448492Y51000D03*
X421368D03*
X433508D03*
X451573Y46900D03*
X418108Y65807D03*
X441533D03*
X428147Y92500D03*
X424801Y84800D03*
X431400D03*
X431494Y73742D03*
X441533Y87392D03*
Y92500D03*
Y73742D03*
X418108Y89964D03*
Y84599D03*
Y73742D03*
X424801D03*
X434840Y92500D03*
X451573Y84714D03*
Y73799D03*
X474998Y36049D03*
X464732Y46898D03*
X460912Y52614D03*
X458266Y36049D03*
X458116Y46914D03*
X464758Y65950D03*
X474998Y46914D03*
X454533Y67749D03*
X454569Y52514D03*
X469832Y54914D03*
X469792Y47100D03*
Y35800D03*
X464692Y54700D03*
X464732Y35999D03*
X478344Y52614D03*
X460912Y67900D03*
X478344Y67749D03*
X469845Y65736D03*
X458116Y84714D03*
X464708Y92500D03*
X464732Y84698D03*
X469808Y84700D03*
X474998Y73849D03*
X469858Y73550D03*
X474998Y84714D03*
X478344Y90414D03*
X469832Y92714D03*
X460912Y90314D03*
X464732Y73799D03*
X458266Y73849D03*
X454569Y90314D03*
X427696Y105800D03*
X421503D03*
X441743Y199841D03*
X421464Y199583D03*
X446253Y206446D03*
X425974D03*
X453013Y218147D03*
X449633Y212296D03*
Y216196D03*
X422594D03*
X419214Y214247D03*
X436113Y212296D03*
X432733Y214247D03*
X429354Y216196D03*
X432733Y218147D03*
X425974D03*
X429353Y212296D03*
X446253Y218147D03*
X442873Y216196D03*
X439493Y214247D03*
X436113Y216196D03*
X453013Y214247D03*
X439493Y210346D03*
X434983Y198931D03*
X455263Y198050D03*
X473292Y218147D03*
X469913Y216196D03*
X469912Y212296D03*
X475692Y199900D03*
X466533Y218147D03*
X473292Y214247D03*
X476672Y212296D03*
Y216196D03*
X459773Y214247D03*
X466533Y206446D03*
X456393Y216196D03*
X462023Y198327D03*
X456393Y212296D03*
X463153Y216196D03*
X429354Y251296D03*
X453013Y245447D03*
Y229847D03*
Y237647D03*
X449633Y251296D03*
Y247396D03*
Y227896D03*
Y223996D03*
X436113Y243496D03*
X442873D03*
X422594D03*
X425974Y245447D03*
Y249347D03*
X432733D03*
X436113Y251296D03*
X429354Y247396D03*
X422594Y251296D03*
X446253Y245447D03*
X419214Y249347D03*
X432733Y245447D03*
X439493Y237647D03*
X446253D03*
X422594Y223996D03*
Y231797D03*
X419214Y233746D03*
Y237647D03*
X436113Y231797D03*
X439493Y241547D03*
X419214D03*
X436113Y223996D03*
X429354D03*
Y220096D03*
Y227896D03*
X446253Y229847D03*
X432733D03*
X425974D03*
X439493Y233746D03*
X442873Y231797D03*
Y223996D03*
X425974Y237647D03*
X432733D03*
X449633Y220096D03*
X439493Y253247D03*
X449633Y255196D03*
Y259096D03*
X446253Y257147D03*
X442873Y255196D03*
X453013Y257147D03*
Y261047D03*
X448900Y269600D03*
X469913Y251296D03*
X466533Y245447D03*
X473292D03*
X476672Y223996D03*
Y243496D03*
Y251296D03*
X469913Y247396D03*
Y223996D03*
X473292Y229847D03*
X469913Y227896D03*
X466533Y229847D03*
X473292Y237647D03*
X466533D03*
X469913Y220096D03*
X456393Y243496D03*
Y251296D03*
X459773Y233746D03*
Y241547D03*
Y237647D03*
X456393Y223996D03*
Y231797D03*
X476672D03*
X463153Y243496D03*
Y251296D03*
Y231797D03*
Y223996D03*
X476672Y259096D03*
X463153D03*
X458408Y278940D03*
X477792Y272747D03*
X462023Y271097D03*
X458643Y269146D03*
X456393Y262996D03*
Y259096D03*
X459773Y261047D03*
X469913Y255196D03*
X473292Y257147D03*
X466533D03*
X468783Y274997D03*
X469913Y270796D03*
X466533Y264947D03*
X469913Y305896D03*
X477792Y307851D03*
X469913Y286396D03*
X477792Y303947D03*
Y288347D03*
Y315647D03*
Y319547D03*
X458643Y338746D03*
X477792Y327347D03*
X462948Y315251D03*
X455263Y340697D03*
X462848Y312741D03*
X467653Y340996D03*
X474413D03*
Y337096D03*
X469913Y321496D03*
X443993Y358547D03*
X441743Y348497D03*
X440613Y352696D03*
X437233Y358547D03*
X450753Y366347D03*
Y350747D03*
Y358547D03*
X437233Y362447D03*
X423714D03*
X433854Y368296D03*
X427094D03*
X440613Y364396D03*
X427094Y372197D03*
X447373D03*
Y368296D03*
X440613Y372197D03*
Y368296D03*
X443993Y366347D03*
X427094Y356596D03*
X433854Y352696D03*
X437233Y354647D03*
X423714D03*
X430474D03*
X427094Y360496D03*
X433854D03*
X445123Y346546D03*
X427094Y352696D03*
X430474Y385847D03*
X450753Y397547D03*
X440613Y395595D03*
X429354Y399496D03*
X433854Y379996D03*
X423714Y374146D03*
X437233D03*
X430474Y378047D03*
X433854Y376096D03*
X443993Y397546D03*
Y401447D03*
Y393647D03*
X440613Y391696D03*
X443993Y385847D03*
X427094Y376096D03*
X437233Y381947D03*
X447373Y376096D03*
X440613Y379996D03*
X443993Y378047D03*
X423715Y397548D03*
X430474Y393647D03*
X433854Y391696D03*
X423715Y401449D03*
X450753Y385847D03*
Y393647D03*
Y378047D03*
X437233Y389747D03*
Y385847D03*
X423714D03*
X477792Y342947D03*
Y362447D03*
Y354647D03*
Y358547D03*
X457513Y362447D03*
X454133Y372197D03*
Y364396D03*
Y348796D03*
Y352696D03*
X464273Y366347D03*
X474413Y372197D03*
X471033Y366347D03*
X467653Y372197D03*
X474413Y364396D03*
X464273Y350747D03*
X474413Y348796D03*
X471033Y350747D03*
X474413Y352696D03*
X471033Y358547D03*
X464273D03*
X467653Y368296D03*
Y348796D03*
X460893Y372197D03*
Y364396D03*
Y352696D03*
X457513Y354647D03*
Y358547D03*
Y346847D03*
X477792Y389747D03*
X457513D03*
X471033Y393647D03*
X460893Y395595D03*
X464273Y401447D03*
X471033D03*
X460893Y391696D03*
X457513Y385847D03*
Y381947D03*
X460893Y379996D03*
X477792Y381947D03*
X474413Y391696D03*
X464273Y385847D03*
X454133Y391696D03*
Y379996D03*
X471033Y385847D03*
X464273Y393647D03*
X474413Y379996D03*
X471033Y378047D03*
X467653Y376096D03*
X464273Y378047D03*
Y397546D03*
X477792Y385847D03*
X447091Y407782D03*
X428224Y407800D03*
X443993Y405347D03*
X467653Y407296D03*
X464273Y405347D03*
X441533Y512792D03*
Y518057D03*
X433192Y497650D03*
X434840Y518157D03*
X431494Y509999D03*
X424801Y510114D03*
X418108Y515364D03*
Y509999D03*
X428147Y518157D03*
X451573Y510114D03*
X448692Y515300D03*
X474998Y510114D03*
X464732Y510098D03*
X460912Y515714D03*
X458116Y510114D03*
X454569Y515714D03*
X478344Y515814D03*
X464708Y517900D03*
X469832Y518114D03*
X418108Y536942D03*
Y529007D03*
X431494Y536942D03*
X424801D03*
X441533Y536957D03*
Y529007D03*
X451573Y547914D03*
Y536999D03*
X448510Y549843D03*
X448410Y531156D03*
X448432Y536723D03*
X448692Y553100D03*
X448557Y534061D03*
X433508Y552000D03*
X421368D03*
X433508Y570900D03*
X421368D03*
X451573Y585714D03*
Y574799D03*
X448226Y569200D03*
X448291Y574773D03*
X464732Y536999D03*
X460912Y553514D03*
X458116Y547914D03*
X454569Y553514D03*
X454533Y530949D03*
X460912Y531100D03*
X458266Y537049D03*
X469845Y528936D03*
X474998Y537049D03*
X464758Y529150D03*
X469858Y536750D03*
X478344Y553614D03*
X464732Y547898D03*
X474998Y547914D03*
X469808Y547900D03*
X478344Y530949D03*
Y568749D03*
X464732Y574799D03*
X469808Y585700D03*
X469858Y574550D03*
X474998Y574849D03*
Y585714D03*
X464732Y585698D03*
X464758Y566950D03*
X469845Y566736D03*
X458266Y574849D03*
X460912Y568900D03*
X458116Y585714D03*
X454533Y568749D03*
X464708Y555700D03*
X469832Y555914D03*
X474998Y612649D03*
X464732Y612599D03*
X458266Y612649D03*
X427324Y623541D03*
X451573Y612599D03*
X447744Y607220D03*
X448692Y590900D03*
X420634Y589800D03*
X433500D03*
X478344Y591414D03*
X464708Y593500D03*
X469832Y593714D03*
X464758Y604750D03*
X469845Y604536D03*
X478344Y606549D03*
X469858Y612350D03*
X460912Y591314D03*
Y606700D03*
X454533Y606549D03*
X454569Y591314D03*
X511809Y-1751D03*
Y9114D03*
X495077Y-1751D03*
X501544Y-1801D03*
X506692Y-2000D03*
X488384Y-1801D03*
X481691Y-1751D03*
X485037Y-7851D03*
X491344D03*
X506657Y-9864D03*
X497723Y-7700D03*
X501592Y-9700D03*
X481691Y9114D03*
X494927D03*
X488384D03*
X501544Y9098D03*
X497723Y14814D03*
X506644Y17114D03*
X506657Y27936D03*
X497723Y30100D03*
X491380Y14714D03*
X506604Y9300D03*
X485037Y14814D03*
X501504Y16900D03*
X485037Y29949D03*
X491344D03*
X501603Y28100D03*
X515155Y-7851D03*
X538355Y9098D03*
X518502Y-1751D03*
X521848Y-7851D03*
X538355Y-1801D03*
X531888Y-1751D03*
X525195Y-1801D03*
X538403Y-9700D03*
X528155Y-7851D03*
X534534Y-7700D03*
X518502Y9114D03*
X531738D03*
X525195D03*
X521848Y14814D03*
Y29949D03*
X528191Y14714D03*
X538315Y16900D03*
X534534Y30100D03*
X515155Y29949D03*
Y14814D03*
X534534D03*
X528155Y29949D03*
X538415Y28100D03*
X488384Y35999D03*
X501492Y54700D03*
X497723Y52614D03*
Y67900D03*
X501544Y46898D03*
X511809Y46914D03*
X491344Y67749D03*
X506657Y65736D03*
X501570Y65950D03*
X481691Y36049D03*
X495077D03*
X506644Y54914D03*
X494927Y46914D03*
X485037Y52614D03*
X481691Y46914D03*
X511809Y36049D03*
X485037Y67749D03*
X488384Y46914D03*
X506603Y35800D03*
X506592Y47000D03*
X501544Y35999D03*
X511809Y84714D03*
X501544Y84698D03*
X494927Y84714D03*
X506670Y73550D03*
X481691Y84714D03*
X488384D03*
X501520Y92500D03*
X506620Y84700D03*
X511809Y73849D03*
X488384Y73799D03*
X481691Y73849D03*
X506644Y92714D03*
X491380Y90314D03*
X497723Y90414D03*
X485037D03*
X495077Y73849D03*
X501544Y73799D03*
X518502Y36049D03*
Y46914D03*
X521848Y67749D03*
X531888Y36049D03*
X538355Y35999D03*
X534534Y52614D03*
X531738Y46914D03*
X525195Y35999D03*
X515155Y67749D03*
Y52614D03*
X521848D03*
X534534Y67900D03*
X538381Y65950D03*
X528155Y67749D03*
X538355Y46898D03*
X538304Y54700D03*
X525195Y46914D03*
X515155Y90414D03*
X534534D03*
X528191Y90314D03*
X521848Y90414D03*
X518502Y73849D03*
Y84714D03*
X531738D03*
X525195D03*
X538355Y84698D03*
X538331Y92500D03*
X531888Y73849D03*
X525195Y73799D03*
X538355D03*
X512024Y104314D03*
X497723Y109564D03*
X501544Y113114D03*
X506670Y112865D03*
X501570Y105265D03*
X491430Y109564D03*
X506657Y105051D03*
X488634Y104314D03*
X495077D03*
X514820Y109564D03*
X521113D03*
X528191Y109914D03*
X534534Y109564D03*
X538355Y113114D03*
X531738Y104314D03*
X525134D03*
X538381Y105265D03*
X518467Y104314D03*
X511592Y206447D03*
Y210346D03*
Y218147D03*
X486812Y214247D03*
Y218147D03*
X498350Y209900D03*
X501452Y212296D03*
X480052Y214247D03*
Y206447D03*
X486812Y210346D03*
X508212Y212296D03*
X518352Y218147D03*
Y206445D03*
X538631Y210346D03*
Y214247D03*
Y206447D03*
X528491Y208397D03*
X525111Y218147D03*
X528491Y216196D03*
X535251Y204496D03*
X525111Y206447D03*
X531871D03*
X521731Y208397D03*
X511592Y241547D03*
Y249347D03*
X486812Y245447D03*
X494692Y247396D03*
X483432Y251296D03*
X501452Y247396D03*
X480052Y237647D03*
X508212Y239596D03*
X498072Y233746D03*
X486812D03*
Y229847D03*
X494692Y235696D03*
X504832Y229847D03*
X486812Y225947D03*
X498072Y222047D03*
Y225947D03*
X486812Y222047D03*
Y237647D03*
X480052Y233746D03*
X504832Y241547D03*
X480052D03*
X486812D03*
X494692Y243496D03*
X483432D03*
X504832Y245447D03*
X501452Y223996D03*
X508212Y231797D03*
Y220096D03*
Y223996D03*
X483432Y235696D03*
Y223996D03*
X494692Y251296D03*
X501452Y274696D03*
X508212Y278596D03*
X484552Y268847D03*
X494692Y255196D03*
X486812Y257147D03*
X504832Y253247D03*
X487932Y278596D03*
Y274696D03*
X494692Y278596D03*
X501452Y266896D03*
Y259096D03*
X483432D03*
X481172Y274696D03*
Y278596D03*
X508212Y270796D03*
X494692D03*
X480052Y261047D03*
X518352Y229847D03*
X521731Y231797D03*
Y235696D03*
Y247396D03*
Y220096D03*
X538631Y225947D03*
Y222047D03*
Y237647D03*
X528491Y247396D03*
Y243496D03*
X538631Y249347D03*
X535251Y235696D03*
X528491Y227896D03*
Y235696D03*
Y220096D03*
X535251Y247396D03*
Y251296D03*
Y239596D03*
X531871Y222047D03*
X525111Y237647D03*
X514972Y247396D03*
Y227896D03*
Y235696D03*
Y239596D03*
Y223996D03*
X535251Y259096D03*
X531871Y261047D03*
X514972Y270796D03*
Y278596D03*
X525111Y253247D03*
X518352D03*
X528491Y274696D03*
X531871Y268847D03*
Y276646D03*
X535251Y266896D03*
X525111Y280547D03*
X521731Y266896D03*
Y259096D03*
Y274696D03*
X538631Y257147D03*
X504832Y307847D03*
X525111Y315647D03*
X494692Y294196D03*
X501452Y290296D03*
Y282496D03*
X491312Y292245D03*
Y300047D03*
X508212Y290296D03*
Y294196D03*
X511592Y307847D03*
Y284447D03*
X481172Y309797D03*
X494692D03*
X481172Y301996D03*
X487932Y309797D03*
X498072Y303947D03*
X487932Y282496D03*
X484552Y300047D03*
Y292245D03*
X494692Y286396D03*
X501452Y298096D03*
X481172Y290296D03*
X508212Y329296D03*
X487932Y317596D03*
X504832Y319547D03*
X484552Y323446D03*
X508212Y317596D03*
Y325396D03*
X491312Y339047D03*
X494692Y337096D03*
X511592Y327347D03*
Y339047D03*
Y331247D03*
Y335147D03*
Y315647D03*
Y323446D03*
X508212Y313696D03*
X481172D03*
X494692Y340996D03*
X504832Y331247D03*
X508212Y337096D03*
Y333196D03*
X504832Y335147D03*
X501452Y333196D03*
X504832Y339047D03*
X501452Y340996D03*
X504832Y315647D03*
X498072Y319547D03*
X504832Y323446D03*
X498072Y327347D03*
X491312Y331247D03*
X511592Y319547D03*
X538631Y311747D03*
X535251Y290296D03*
X514972Y301996D03*
Y290296D03*
Y286396D03*
Y294196D03*
X525111Y284447D03*
X531871Y288347D03*
Y292245D03*
X528491Y294196D03*
X525111Y300047D03*
X531871D03*
X521731Y301996D03*
X528491Y286396D03*
Y298096D03*
X535251Y294196D03*
X538631Y292245D03*
Y288347D03*
Y284447D03*
X531871Y303947D03*
X535251Y301996D03*
X531871Y311747D03*
Y307847D03*
X535251Y309797D03*
X514972Y333196D03*
Y321496D03*
Y317596D03*
Y329296D03*
Y325396D03*
Y337096D03*
X518352Y319547D03*
Y323446D03*
Y315647D03*
X521731Y317596D03*
Y325396D03*
X518352Y327347D03*
Y339047D03*
X531871Y335147D03*
X525111D03*
X528491Y337096D03*
X531871Y327347D03*
X535251Y329296D03*
X538631Y335147D03*
Y339047D03*
X528491Y317596D03*
X531871Y319547D03*
X535251Y321496D03*
X538631Y319547D03*
X504832Y342947D03*
X491312Y370247D03*
X498072Y366347D03*
X494692Y372197D03*
X504832Y366347D03*
X501452Y368296D03*
X487932D03*
X484552Y362447D03*
X498072D03*
X491312D03*
X494692Y360496D03*
X487932D03*
X501452Y344896D03*
X504832Y354647D03*
X494692Y344896D03*
Y348796D03*
X491312Y350747D03*
Y366347D03*
X487932Y372197D03*
X484552Y370247D03*
X481172Y372197D03*
X484552Y366347D03*
X487932Y364396D03*
X494692D03*
X501452D03*
X491312Y358547D03*
X498072Y350747D03*
Y346847D03*
X501452Y360496D03*
X498072Y342947D03*
X491312Y346847D03*
X494692Y356596D03*
X498072Y358547D03*
Y354647D03*
X481172Y344896D03*
Y360496D03*
X484552Y346847D03*
X508212Y352696D03*
Y360496D03*
X504832Y346847D03*
Y358547D03*
X501452Y356596D03*
Y348796D03*
Y352696D03*
X511592Y370247D03*
X481172Y352696D03*
X484552Y393647D03*
X481172Y391696D03*
X484552Y385847D03*
X498072Y393647D03*
X494692Y391696D03*
X491312Y385847D03*
X498072D03*
X508212Y387796D03*
X501452Y391696D03*
Y395597D03*
X491312Y389747D03*
X504832Y381947D03*
Y378047D03*
X501452Y379996D03*
X481172Y395596D03*
X511592Y378047D03*
Y397546D03*
X491312Y378047D03*
X484552D03*
X481172Y379996D03*
X487932Y376096D03*
X491312Y381947D03*
Y374146D03*
X498072Y397546D03*
X487932Y403396D03*
Y399496D03*
X491312Y397546D03*
X487932Y395597D03*
X514972Y372197D03*
Y356596D03*
X521731Y360496D03*
Y356596D03*
Y348796D03*
X518352Y342947D03*
Y362447D03*
X521731Y372197D03*
X518352Y370247D03*
X525111Y354647D03*
X531871Y346847D03*
X535251Y356596D03*
X538631Y366347D03*
X528491Y364396D03*
X525111Y342947D03*
X514972Y403396D03*
Y379996D03*
X531871Y374146D03*
X521731Y399496D03*
X518352Y397546D03*
Y389747D03*
X535251Y383896D03*
X525111Y381947D03*
X538631Y393647D03*
Y378047D03*
X528491Y403396D03*
X531871Y401447D03*
Y389747D03*
X525111Y393647D03*
X484552Y405347D03*
X538750Y406200D03*
X511712Y495800D03*
X488384Y495887D03*
X494777D03*
X491380Y493744D03*
X506644Y490867D03*
X501560D03*
X497723Y493494D03*
X506620Y510100D03*
X506644Y518114D03*
X501544Y510098D03*
X485037Y515814D03*
X481691Y510114D03*
X491380Y515714D03*
X511809Y510114D03*
X497723Y515814D03*
X494927Y510114D03*
X488384D03*
X501520Y517900D03*
X506644Y498867D03*
X501560D03*
X514755Y491044D03*
X521048Y491144D03*
X538370Y490609D03*
X528241Y490944D03*
X534534Y490794D03*
X515155Y515814D03*
X530792Y495787D03*
X524595D03*
X517892Y495800D03*
X534534Y515814D03*
X528191Y515714D03*
X531738Y510114D03*
X525195D03*
X538355Y510098D03*
X538331Y517900D03*
X521848Y515814D03*
X518502Y510114D03*
X538370Y498609D03*
X506670Y536750D03*
X501570Y529150D03*
X506657Y528936D03*
X501544Y536999D03*
X511809Y547914D03*
Y537049D03*
X491380Y553514D03*
X497723Y553614D03*
X485037D03*
X506620Y547900D03*
X501544Y547898D03*
X481691Y547914D03*
X494927D03*
X488384D03*
X481691Y537049D03*
X491344Y530949D03*
X488384Y536999D03*
X495077Y537049D03*
X497723Y531100D03*
X485037Y530949D03*
Y568749D03*
X481691Y574849D03*
Y585714D03*
X501544Y585698D03*
Y574799D03*
X506657Y566736D03*
X501570Y566950D03*
X506670Y574550D03*
X506620Y585700D03*
X488384Y585714D03*
X511809D03*
Y574849D03*
X494927Y585714D03*
X491344Y568749D03*
X501520Y555700D03*
X506644Y555914D03*
X497723Y568900D03*
X488384Y574799D03*
X495077Y574849D03*
X515155Y553614D03*
Y530949D03*
X534534Y531100D03*
X531888Y537049D03*
X528155Y530949D03*
X525195Y536999D03*
X538355D03*
X538381Y529150D03*
X525195Y547914D03*
X531738D03*
X538355Y547898D03*
X534534Y553614D03*
X528191Y553514D03*
X518502Y547914D03*
X521848Y553614D03*
X518502Y537049D03*
X521848Y530949D03*
X515155Y568749D03*
X538331Y555700D03*
X518502Y585714D03*
Y574849D03*
X521848Y568749D03*
X538355Y585698D03*
Y574799D03*
X538381Y566950D03*
X531738Y585714D03*
X525195D03*
X534534Y568900D03*
X525195Y574799D03*
X528155Y568749D03*
X531888Y574849D03*
X525195Y612599D03*
X518502Y612649D03*
X538355Y612599D03*
X531888Y612649D03*
X501544Y612599D03*
X495077Y612649D03*
X488384Y612599D03*
X511809Y612649D03*
X497723Y591414D03*
X486250Y591020D03*
X491380Y591314D03*
X501520Y593500D03*
X506644Y593714D03*
X501570Y604750D03*
X506657Y604536D03*
X491344Y606549D03*
X497723Y606700D03*
X485037Y607230D03*
X506670Y612350D03*
X480950Y612430D03*
X515155Y606549D03*
Y591414D03*
X521848D03*
Y606549D03*
X534534Y591414D03*
X528191Y591314D03*
X538331Y593500D03*
X538381Y604750D03*
X534534Y606700D03*
X528155Y606549D03*
X562006Y9114D03*
X568549D03*
X555313D03*
X548620D03*
X571345Y-7700D03*
X551966Y-7851D03*
X564966D03*
X558659D03*
X562006Y-1801D03*
X555313Y-1751D03*
X568699D03*
X548620D03*
X543503Y-2000D03*
X543468Y-9864D03*
X543455Y17114D03*
X564992Y14714D03*
X543415Y9300D03*
X558659Y14814D03*
Y29949D03*
X551966Y14814D03*
Y29949D03*
X564966D03*
X571345Y14814D03*
Y30100D03*
X543468Y27936D03*
X575166Y9098D03*
X602163Y16999D03*
X575214Y-9700D03*
X575166Y-1801D03*
X580279Y-9864D03*
X580314Y-2000D03*
X588777Y-7851D03*
X598817Y-9901D03*
X595470Y-7851D03*
X592124Y-1751D03*
X598817D03*
X585431D03*
X602163Y-9901D03*
X598817Y9157D03*
X592124Y9114D03*
X585431D03*
X575182Y16900D03*
X575192Y28100D03*
X580192Y9300D03*
X588777Y29949D03*
X580279Y27936D03*
X595470Y29949D03*
Y14814D03*
X598817Y27899D03*
X588777Y14814D03*
X580266Y17114D03*
X562006Y46914D03*
X551966Y52614D03*
X565352Y52864D03*
X548620Y46914D03*
Y36049D03*
X558659Y52614D03*
X568699Y36049D03*
X555313D03*
X562006Y35999D03*
X551966Y67749D03*
X564966D03*
X571345Y52614D03*
Y67900D03*
X558659Y67749D03*
X568549Y46914D03*
X555313D03*
X543468Y65736D03*
X543404Y47000D03*
X543415Y35800D03*
X543455Y54914D03*
Y92714D03*
X548620Y84714D03*
X568549D03*
X555313D03*
X562006D03*
X543481Y73550D03*
X543431Y84700D03*
X548620Y73849D03*
X568699D03*
X562006Y73799D03*
X555313Y73849D03*
X558659Y90414D03*
X551966D03*
X571345D03*
X575166Y46898D03*
Y35999D03*
X575192Y65950D03*
X585431Y46914D03*
X595470Y52614D03*
X588777D03*
X585431Y36049D03*
X592124D03*
X598817D03*
Y46957D03*
X592124Y46914D03*
X598817Y65699D03*
X595470Y67749D03*
X588777D03*
X580266Y54914D03*
X580192Y35750D03*
X580279Y65736D03*
X602163Y65699D03*
X592124Y84714D03*
X585431D03*
X598817Y84757D03*
X580242Y84700D03*
X580266Y92714D03*
X588777Y90414D03*
X602163Y92599D03*
X575166Y73799D03*
X575142Y92500D03*
X575166Y84698D03*
X595470Y90414D03*
X585431Y73849D03*
X592124D03*
X598817D03*
X580292Y73550D03*
X548620Y104314D03*
X555313D03*
X558659Y110014D03*
X551966D03*
X543481Y112865D03*
X543468Y105051D03*
X602100Y109600D03*
X555531Y216196D03*
X557000Y206800D03*
X548771Y212296D03*
X552151Y214247D03*
X547800Y201400D03*
X545391Y210346D03*
X552151Y218147D03*
Y225947D03*
X558911Y222047D03*
X552151Y233746D03*
X548771Y235696D03*
X558911Y229847D03*
X552151D03*
X562591Y220096D03*
X564084Y235685D03*
X545391Y225947D03*
Y222047D03*
Y233746D03*
X542011Y239596D03*
Y247396D03*
X552151Y241547D03*
X548771Y239596D03*
X552151Y249347D03*
X555531Y247396D03*
X562591Y251296D03*
X548771Y243496D03*
X562591D03*
X572930Y232750D03*
Y228130D03*
X552151Y257147D03*
X562591Y255196D03*
X548771D03*
X573200Y262600D03*
X573100Y258600D03*
X548771Y266896D03*
X558911Y264947D03*
X563800Y275900D03*
X559211Y280547D03*
X548771Y278596D03*
X558911Y272747D03*
X555531Y274696D03*
X564500Y264800D03*
Y268800D03*
X552151Y261047D03*
X545391Y272747D03*
Y280547D03*
Y264947D03*
Y268847D03*
X542011Y274696D03*
X580360Y234590D03*
Y230060D03*
X545391Y307847D03*
X555831Y309797D03*
Y305896D03*
X548771Y309797D03*
X555831Y298096D03*
X552151Y284447D03*
X548771Y286396D03*
X552151Y288347D03*
Y296147D03*
X558145Y286727D03*
X545391Y296147D03*
Y288347D03*
Y292245D03*
Y300047D03*
X542011Y294196D03*
Y298096D03*
X545391Y303947D03*
X548771Y313696D03*
X561971Y317320D03*
X548771Y325396D03*
X558911Y335147D03*
X555531Y333196D03*
X562591D03*
X548771Y340996D03*
X561966Y325502D03*
X559211Y319547D03*
X552151Y323446D03*
X545391Y319547D03*
X542011Y321496D03*
X545391Y335147D03*
Y331247D03*
Y315647D03*
X552151Y350747D03*
X558911Y342947D03*
X559212Y370247D03*
X548771Y368296D03*
X562591Y352696D03*
Y344896D03*
X563200Y356596D03*
X545391Y354647D03*
Y346847D03*
X542011Y368296D03*
X545391Y366347D03*
Y358547D03*
X542011Y360496D03*
Y348796D03*
X559212Y374146D03*
X555531Y387797D03*
X559212Y381947D03*
Y393647D03*
X552151Y378047D03*
X545391Y397546D03*
Y385847D03*
X542011Y376096D03*
X573867Y459903D03*
X575614Y461694D03*
X584076Y443828D03*
X588285Y448306D03*
X586136Y446335D03*
X558659Y493444D03*
X551366Y490744D03*
X543455Y490909D03*
X555313Y510114D03*
X548492Y495800D03*
X554792Y495887D03*
X543431Y510100D03*
X543455Y518114D03*
X551966Y515814D03*
X548620Y510114D03*
X543455Y498909D03*
X568549Y510114D03*
X562006D03*
X571345Y515814D03*
X558659D03*
X582912Y468948D03*
X581032Y467202D03*
X575166Y510098D03*
X575142Y517900D03*
X580266Y518114D03*
X580242Y510100D03*
X598817Y510157D03*
X595470Y515814D03*
X588777D03*
X602163Y517999D03*
X592124Y510114D03*
X585431D03*
X543468Y528936D03*
X543481Y536750D03*
X543431Y547900D03*
X548620Y547914D03*
X551966Y553614D03*
X548620Y537049D03*
X551966Y530949D03*
X558659D03*
X555313Y537049D03*
X562006Y536999D03*
X564966Y530949D03*
X568699Y537049D03*
X571345Y553614D03*
Y531100D03*
X558659Y553614D03*
X555313Y547914D03*
X568549D03*
X562006D03*
X543455Y555914D03*
X571345Y568900D03*
X564966Y568749D03*
X562006Y574799D03*
X555313Y585714D03*
Y574849D03*
X558659Y568749D03*
X568549Y585714D03*
X562006D03*
X568699Y574849D03*
X551966Y568749D03*
X548620Y574849D03*
Y585714D03*
X543481Y574550D03*
X543431Y585700D03*
X543468Y566736D03*
X575166Y547898D03*
X575192Y529150D03*
X575166Y536999D03*
X598817Y547957D03*
X592124Y547914D03*
X595470Y530949D03*
X580242Y547900D03*
X580279Y528936D03*
X580292Y536750D03*
X592124Y537049D03*
X588777Y530949D03*
X598817Y528899D03*
Y537049D03*
X602163Y528899D03*
X585431Y547914D03*
Y537049D03*
X588777Y553614D03*
X595470D03*
X580279Y566736D03*
X585431Y574849D03*
Y585714D03*
X598817Y585757D03*
Y574849D03*
Y566699D03*
X592124Y585714D03*
X595470Y568749D03*
X588777D03*
X592124Y574849D03*
X575142Y555700D03*
X575192Y566950D03*
X575166Y585698D03*
Y574799D03*
X580266Y555914D03*
X580292Y574550D03*
X580242Y585700D03*
X575166Y612599D03*
X585431Y612649D03*
X592124D03*
X598817D03*
X555313D03*
X562006Y612599D03*
X568699Y612649D03*
X548620D03*
X571345Y591414D03*
X558659D03*
X571345Y606700D03*
X558659Y606549D03*
X564966D03*
X551966D03*
Y591414D03*
X543455Y593714D03*
X543468Y604536D03*
X543481Y612350D03*
X580292D03*
X580266Y593714D03*
X595470Y591414D03*
X588777D03*
X598817Y604499D03*
X595470Y606549D03*
X588777D03*
X575192Y604750D03*
X575142Y593500D03*
X602163Y593599D03*
Y604499D03*
X580279Y604536D03*
X620092Y13078D03*
X620192Y31978D03*
Y-5822D03*
X647317Y-1310D03*
X660676Y-2600D03*
X651300Y20000D03*
X659200Y31500D03*
X651300Y17500D03*
X620070Y50878D03*
X620192Y69778D03*
X620092Y88678D03*
X663500Y48000D03*
X663700Y65600D03*
X663476Y45296D03*
X616115Y108339D03*
X622200Y112200D03*
X616167Y118627D03*
X605300Y124600D03*
X630000Y126572D03*
X624500Y129400D03*
X626900Y128300D03*
X633580Y125560D03*
X661700Y142300D03*
X636481Y124951D03*
X635951Y127419D03*
X661053Y115971D03*
X658490Y115432D03*
X650307Y115518D03*
X647809Y116121D03*
X645311Y116724D03*
X650120Y122700D03*
X660900Y123650D03*
Y126650D03*
X647120Y122700D03*
X657900Y126650D03*
Y123650D03*
X651920Y125750D03*
X656111Y121550D03*
X653111D03*
X654558Y115101D03*
X640043Y117728D03*
X639100Y124200D03*
X638800Y126700D03*
X648690Y125590D03*
X643674Y123573D03*
X644950Y125750D03*
X641950D03*
X642899Y117112D03*
X632500Y238500D03*
Y235000D03*
X632692Y248172D03*
X632532Y241717D03*
X630200Y248100D03*
X633308Y263808D03*
X662800Y248600D03*
X643500Y272262D03*
X659900Y256900D03*
Y269200D03*
X652000Y284500D03*
X663200Y298600D03*
X644800Y292150D03*
X654500Y298600D03*
X652100Y288300D03*
X639045Y299555D03*
X639100Y309500D03*
X649000Y339400D03*
X638790Y329500D03*
X639350Y339980D03*
X639100Y319500D03*
X655900Y307700D03*
X656300Y312300D03*
X660700Y307700D03*
X655900Y316500D03*
X656000Y329800D03*
X655900Y320500D03*
X656000Y325100D03*
X660900Y329800D03*
X664100Y348000D03*
X648800D03*
X658900D03*
X662936Y367171D03*
X659936Y364171D03*
X662936D03*
X654000Y348000D03*
X634200Y436800D03*
X637300Y437200D03*
X625430Y490100D03*
X607012Y465997D03*
X623660Y466746D03*
X632113Y496892D03*
X619392Y514700D03*
X656900Y482290D03*
X649600Y492400D03*
X660500Y492000D03*
X652000Y513900D03*
X655000D03*
X661500D03*
X658500D03*
X620192Y532978D03*
X618892Y555800D03*
X618292Y574300D03*
X651750Y584150D03*
X653100Y587000D03*
X618192Y593600D03*
X620033Y608878D03*
X660230Y598170D03*
X674300Y9847D03*
X671800D03*
X669300D03*
X673900Y23100D03*
X671400D03*
X668900D03*
X690000Y15300D03*
X683800Y24856D03*
X670430Y29253D03*
X716858Y-14448D03*
X717720Y23279D03*
X715114Y26395D03*
X704500Y26300D03*
X714337Y7852D03*
Y5352D03*
Y2852D03*
X718555Y-16147D03*
X666500Y48000D03*
X665100Y68600D03*
X668100D03*
X666700Y65600D03*
X678020Y69870D03*
X678300Y92630D03*
Y95130D03*
X675630Y94988D03*
X681300Y95130D03*
Y92630D03*
X684300D03*
X687400Y93900D03*
X673830Y83050D03*
X676430D03*
X676500Y80500D03*
X673900D03*
X674010Y77970D03*
X676610D03*
X692200Y83800D03*
X695000Y67000D03*
X699880Y66840D03*
X724200Y64730D03*
X722460Y69550D03*
X713680Y60910D03*
X700360Y72160D03*
X694910Y72220D03*
X713050Y63650D03*
X710440Y63710D03*
X704880Y66750D03*
X697747Y72184D03*
X723700Y67400D03*
X713620Y58270D03*
X715800Y59490D03*
Y57000D03*
X713590Y53260D03*
X713610Y55730D03*
X700640Y69500D03*
X703120Y69380D03*
X702380Y66840D03*
X697440Y66900D03*
X699800Y89100D03*
X713830Y82730D03*
X692000Y45000D03*
Y48500D03*
X697500D03*
Y45000D03*
X664700Y142800D03*
X675600Y144900D03*
Y150000D03*
X679900Y128200D03*
X682400Y127085D03*
X684900D03*
X673566Y116724D03*
X676494Y116940D03*
X668665Y118185D03*
X671249Y118744D03*
X677896Y119093D03*
X674896D03*
X715505Y155076D03*
X720700Y154750D03*
X725650Y155000D03*
X691583Y200124D03*
X689033D03*
X686533D03*
Y196624D03*
X689033D03*
X691583D03*
X715550Y158880D03*
X705550D03*
X710550D03*
X709200Y198700D03*
X720369Y205199D03*
X716557Y198557D03*
X692513Y213800D03*
X692673Y206200D03*
X692500Y210100D03*
X690861Y211917D03*
Y215717D03*
X692400Y218100D03*
X690861Y204317D03*
Y208117D03*
X706500Y217400D03*
Y214900D03*
X719315Y239104D03*
X669900Y224000D03*
X672500Y224100D03*
X678454Y278000D03*
X675380Y246340D03*
X678000Y246400D03*
X668100Y232200D03*
X667240Y246600D03*
X672530Y246300D03*
X677400Y232300D03*
X674300Y232200D03*
X675200Y224100D03*
X667600Y250200D03*
X688643Y225980D03*
X688388Y231280D03*
X678400Y224100D03*
X690380Y252240D03*
X690939Y266630D03*
X693530Y261240D03*
X690660Y264000D03*
X690704Y271324D03*
X671100Y232200D03*
X701800Y246480D03*
X669750Y246350D03*
X710572Y244773D03*
X719360Y241504D03*
X710627Y242061D03*
X702000Y243900D03*
X722050Y221150D03*
X707653Y226347D03*
X718300Y227400D03*
X700900Y264100D03*
X694361Y223317D03*
Y220817D03*
X690861D03*
Y223317D03*
X672300Y269200D03*
X672200Y256800D03*
X706561Y219917D03*
X719900Y269300D03*
X725500Y279300D03*
X725300Y269400D03*
X719600Y279400D03*
X704175Y287275D03*
X704214Y290775D03*
X680000Y281900D03*
X672150Y288350D03*
X695300Y338100D03*
X695400Y328000D03*
X684100Y338200D03*
X695400Y318000D03*
X695800Y308000D03*
X696088Y297069D03*
X704500Y293800D03*
X707130Y310150D03*
X718200Y295000D03*
X706300Y318400D03*
X678200Y307800D03*
X672700Y307700D03*
X667100D03*
X678100Y324800D03*
X672200Y329800D03*
X678100Y329600D03*
X666900Y329700D03*
X678200Y313700D03*
Y319300D03*
X679000Y348000D03*
X688600Y365100D03*
X671936Y367171D03*
X665936Y370171D03*
X684900Y348000D03*
X674600D03*
X671936Y370171D03*
X665936Y367171D03*
X668936Y370171D03*
Y367171D03*
X665936Y364171D03*
X668936D03*
X669093Y348120D03*
X671936Y373171D03*
X668936D03*
X670300Y375600D03*
X713900Y347800D03*
X698560Y374430D03*
X713900Y342800D03*
Y352800D03*
Y350300D03*
Y345300D03*
X690040Y412030D03*
X685600Y432500D03*
X690600D03*
Y437500D03*
X703876Y414949D03*
X705850Y417093D03*
X710600Y420267D03*
X710423Y417423D03*
X708346Y415859D03*
X708011Y419078D03*
X712980Y417900D03*
X713493Y420449D03*
X723748Y499091D03*
X676900Y489400D03*
X666500Y487600D03*
Y484600D03*
X669500D03*
Y481600D03*
X664610Y512810D03*
X685050Y503970D03*
X704500Y512850D03*
X716267Y522020D03*
X703028Y495600D03*
X709028D03*
X706028D03*
X703028Y492600D03*
X706028D03*
X674200Y588900D03*
X690100Y575860D03*
X689193Y573493D03*
X693126Y581380D03*
X671599Y573493D03*
X671791Y588920D03*
X674099Y573493D03*
X669099D03*
X668891Y588900D03*
X713650Y540750D03*
X715650Y542250D03*
Y545250D03*
X713650Y546750D03*
X708000Y553250D03*
X720200Y551750D03*
X715650Y551250D03*
X696000Y553250D03*
X715650Y548250D03*
X713650Y549750D03*
X723200Y551750D03*
X699000Y553250D03*
X702000D03*
X705000D03*
X713650Y543750D03*
X723200Y554750D03*
X706500Y555750D03*
X703500D03*
X700500D03*
X720200Y554750D03*
X709500Y555750D03*
X712600Y571900D03*
X716300Y569400D03*
X707500Y587800D03*
X691900Y531350D03*
Y534850D03*
X697500Y534750D03*
Y531250D03*
X725173Y598171D03*
X724106Y609550D03*
X721106D03*
X708900Y589850D03*
X706100D03*
X732600Y3600D03*
X755500Y8700D03*
X753600Y-4300D03*
X736715Y33487D03*
X734201Y33510D03*
X726250Y23550D03*
X731457Y8471D03*
X732335Y6000D03*
X786414Y-9650D03*
X779771Y9114D03*
X773228D03*
Y-1801D03*
X779921Y-1751D03*
X776188Y-7851D03*
X769881Y-9901D03*
X782567Y-7700D03*
X786388Y9098D03*
Y-1801D03*
X786414Y28150D03*
X769881Y27899D03*
X782567Y14814D03*
Y30100D03*
X769881Y16839D03*
X776224Y14714D03*
X776188Y29949D03*
X786364Y16900D03*
X736631Y36122D03*
X736655Y38531D03*
X731887Y40916D03*
X734155Y38531D03*
X734131Y36122D03*
X731843Y43571D03*
X756100Y36200D03*
X755500Y46700D03*
X737800Y55800D03*
X751708Y73800D03*
X755500Y84361D03*
X786388Y35999D03*
X786364Y54700D03*
X786388Y46898D03*
X773228Y46914D03*
X779771D03*
X776188Y67749D03*
X769881Y66000D03*
X782567Y67900D03*
Y52614D03*
X769881Y54839D03*
X779921Y35983D03*
X773228D03*
X776224Y52514D03*
X769881Y92500D03*
X773228Y84714D03*
X779771D03*
X776224Y90314D03*
X782567Y90414D03*
X779921Y73849D03*
X773228Y73799D03*
X786414Y65950D03*
X786388Y73799D03*
X786364Y92500D03*
X786388Y84698D03*
X730600Y154984D03*
X746000Y150500D03*
X740718Y150957D03*
X769100Y102900D03*
X758400Y156200D03*
X747600Y161450D03*
X740650Y164800D03*
X735600Y164900D03*
X740650Y158800D03*
X754726Y205037D03*
X752226D03*
X749726D03*
X754726Y207537D03*
X752226D03*
X749726D03*
X742937Y218574D03*
X758400Y159200D03*
X774582Y212033D03*
X770200Y208600D03*
X775171Y218616D03*
X787371Y215216D03*
Y217716D03*
X777700Y218600D03*
X727969Y236770D03*
X736612Y237908D03*
X727997Y239195D03*
X736625Y240308D03*
X742897Y229573D03*
X746303Y243122D03*
X746321Y240569D03*
X760304Y235827D03*
X768560Y244055D03*
X769019Y276400D03*
X762616Y270113D03*
X761480Y242720D03*
X731100Y269300D03*
Y279300D03*
X787371Y247216D03*
Y249716D03*
X775232Y221133D03*
X777700Y250600D03*
X775232Y223633D03*
X775171Y250616D03*
X775232Y253133D03*
Y255633D03*
X787371Y279216D03*
X774347Y339983D03*
X762760Y339500D03*
X727300Y302910D03*
X727474Y338363D03*
Y335363D03*
X732474D03*
Y338363D03*
X756114Y316209D03*
X729974Y338363D03*
Y335363D03*
X771278Y307918D03*
X762842Y302434D03*
X765730Y335064D03*
X777700Y282600D03*
X775232Y287633D03*
Y285133D03*
X775171Y282616D03*
X787371Y281716D03*
Y311216D03*
X777800Y314700D03*
X775171Y314616D03*
X787371Y313716D03*
X775232Y317133D03*
Y319633D03*
X727474Y344663D03*
Y367463D03*
X732474D03*
X729974D03*
X727474Y364863D03*
X732474D03*
X729974D03*
Y347663D03*
X727474D03*
X732474D03*
Y344663D03*
X727574Y373463D03*
X732574D03*
X730074D03*
X732574Y376063D03*
X730074D03*
X729974Y344663D03*
X731100Y362300D03*
X772443Y371976D03*
X760140Y362819D03*
X758952Y384100D03*
X763333Y400212D03*
X772300Y403520D03*
X775171Y346616D03*
X787371Y343216D03*
Y345716D03*
X775232Y349133D03*
X777600Y346600D03*
X775232Y351633D03*
X787321Y374916D03*
Y377316D03*
X775182Y383633D03*
Y381133D03*
X778000Y378700D03*
X775121Y378616D03*
X749640Y431797D03*
X728940Y457806D03*
X775417Y435799D03*
X777979Y436516D03*
X752496Y515974D03*
X732522Y526808D03*
Y524308D03*
X750518Y522108D03*
X734922Y526808D03*
X776224Y515714D03*
X779771Y510114D03*
X773228D03*
X769881Y517900D03*
X782567Y515814D03*
X786388Y510098D03*
X786364Y517900D03*
X732442Y529300D03*
X734842D03*
X736300Y541500D03*
X756000Y537000D03*
X737400Y529400D03*
X734900Y531800D03*
X732400D03*
X726200Y551750D03*
X754910Y556400D03*
X726200Y554750D03*
X727400Y571300D03*
X755000Y574800D03*
X752500Y585150D03*
X727106Y586550D03*
X773228Y536999D03*
X763677Y547783D03*
X776188Y530949D03*
X782567Y531100D03*
X769818Y529200D03*
X779921Y537049D03*
X782567Y553614D03*
X773228Y547914D03*
X779771D03*
X776224Y553514D03*
X786388Y536999D03*
X786414Y529150D03*
X786388Y547898D03*
X786364Y555700D03*
X769881D03*
X773228Y574799D03*
X782567Y568900D03*
X769700Y566900D03*
X776188Y568749D03*
X779921Y574849D03*
X773228Y585714D03*
X779771D03*
X786388Y574799D03*
Y585698D03*
X786414Y566950D03*
X779921Y612649D03*
X773228Y612599D03*
X786388D03*
X755000Y614500D03*
X727000Y606600D03*
X766600Y590700D03*
X769700Y604900D03*
X776188Y606549D03*
X782567Y606700D03*
Y591414D03*
X776224Y591314D03*
X786414Y604750D03*
X786364Y593500D03*
X803346Y-1751D03*
X810039Y-1801D03*
X791514Y-2050D03*
X791501Y-9864D03*
X812999Y-7851D03*
X806692D03*
X799999D03*
X816582Y9114D03*
X796653D03*
X791464Y9100D03*
X810039Y9114D03*
X803346D03*
X816732Y-1751D03*
X796653D03*
X799999Y29949D03*
X806692D03*
X812999D03*
X791501Y27936D03*
X791488Y17114D03*
X799999Y14814D03*
X813035Y14714D03*
X806692Y14814D03*
X828275Y9100D03*
X833464Y9114D03*
X840157D03*
X819378Y-7700D03*
X823199Y9098D03*
Y-1801D03*
X823225Y-9650D03*
X828312Y-9864D03*
X843503Y-7851D03*
X836810D03*
X846850Y-1801D03*
X828325Y-2050D03*
X833464Y-1751D03*
X840157D03*
X846850Y9114D03*
X819378Y14814D03*
Y30100D03*
X843503Y14814D03*
X823175Y16900D03*
X823225Y28150D03*
X828312Y27936D03*
X836810Y29949D03*
X828299Y17114D03*
X836810Y14814D03*
X843503Y29949D03*
X791488Y54914D03*
X799999Y52614D03*
X796653Y46914D03*
X791464Y46900D03*
X810039Y35999D03*
X803346Y36049D03*
X799999Y90414D03*
X791488Y92714D03*
X806692Y90414D03*
X816582Y46914D03*
X816732Y36049D03*
X799999Y67749D03*
X812999D03*
X806692D03*
X791501Y65736D03*
X803346Y46914D03*
X806692Y52614D03*
X813035Y52514D03*
X810039Y46914D03*
X791514Y35750D03*
X796653Y36049D03*
X816582Y73849D03*
X791514Y73550D03*
X796653Y73849D03*
X810039Y73799D03*
X803346Y73849D03*
X816582Y84714D03*
X813035Y90314D03*
X803346Y84714D03*
X810039D03*
X796653D03*
X791464Y84700D03*
X819378Y67900D03*
Y52614D03*
X846850Y35999D03*
X833464Y36049D03*
X840157D03*
X823225Y65950D03*
X823175Y54700D03*
X823199Y46898D03*
Y35999D03*
X828299Y54914D03*
X828275Y46900D03*
X828325Y35750D03*
X833464Y46914D03*
X836810Y52614D03*
X840157Y46914D03*
X828312Y65736D03*
X836810Y67749D03*
X843503D03*
X846850Y46914D03*
X843503Y52614D03*
X823175Y92500D03*
X823199Y84698D03*
X846850Y73799D03*
X843503Y90414D03*
X846850Y84714D03*
X828325Y73550D03*
X840157Y73849D03*
X833464D03*
X828299Y92714D03*
X836810Y90414D03*
X840157Y84714D03*
X833464D03*
X828275Y84700D03*
X819378Y90364D03*
X823199Y73799D03*
X790871Y215216D03*
Y217716D03*
X845100Y268200D03*
X847600D03*
X842600D03*
X847600Y243400D03*
X841400Y243300D03*
X847600Y238400D03*
X841400Y238300D03*
X847600Y240900D03*
X841400Y240800D03*
X789500Y231800D03*
X790900Y234000D03*
Y229700D03*
X790846Y225774D03*
X790882Y221723D03*
X790871Y247216D03*
Y249716D03*
X789471Y227742D03*
X789576Y223737D03*
X789554Y219723D03*
X790900Y253900D03*
X789432Y252000D03*
X790871Y266216D03*
X789432Y255800D03*
X790867Y257724D03*
X789432Y259800D03*
X789500Y263900D03*
X790885Y261711D03*
X790871Y279216D03*
X842600Y299900D03*
X845100D03*
X847600D03*
X845100Y331500D03*
X842600D03*
X847600D03*
X790871Y311216D03*
X789432Y284200D03*
Y288300D03*
Y292400D03*
X789400Y296200D03*
X790871Y298216D03*
X790937Y294270D03*
X790900Y290300D03*
Y286200D03*
X790871Y281716D03*
Y313716D03*
X789432Y319900D03*
Y323900D03*
X790900Y322000D03*
Y326000D03*
X790871Y330216D03*
X789500Y328000D03*
X789478Y315671D03*
X790800Y317700D03*
X847600Y363000D03*
X845100D03*
X842600D03*
X847577Y381842D03*
X789432Y348100D03*
Y352100D03*
X789597Y356105D03*
X789500Y360200D03*
X790900Y358200D03*
X790835Y354048D03*
X790867Y350024D03*
X790871Y345716D03*
Y343216D03*
Y362216D03*
X790821Y374916D03*
X790900Y389300D03*
X789500Y391300D03*
X790900Y393400D03*
Y381100D03*
X789582Y383200D03*
X790900Y385300D03*
X789500Y387300D03*
X790821Y377316D03*
X789282Y379200D03*
X816582Y510114D03*
X806692Y515814D03*
X813035Y515714D03*
X810039Y510114D03*
X791488Y518114D03*
X791464Y510100D03*
X799999Y515814D03*
X796653Y510114D03*
X803346D03*
X819378Y515764D03*
X843503Y515814D03*
X846850Y510114D03*
X823175Y517900D03*
X823199Y510098D03*
X828299Y518114D03*
X840157Y510114D03*
X833464D03*
X836810Y515814D03*
X816582Y537049D03*
Y547914D03*
X810039Y536999D03*
X806692Y530949D03*
X812999D03*
X803346Y537049D03*
X796653D03*
X799999Y530949D03*
X791501Y528936D03*
X791514Y536750D03*
X799999Y553614D03*
X810039Y547914D03*
X796653D03*
X803346D03*
X791464Y547900D03*
X806692Y553614D03*
X813035Y553514D03*
X791488Y555914D03*
X810039Y585714D03*
X806692Y568749D03*
X810039Y574799D03*
X812999Y568749D03*
X803346Y585714D03*
X796653D03*
X791514Y574550D03*
X791464Y585700D03*
X799999Y568749D03*
X796653Y574849D03*
X803346D03*
X791501Y566736D03*
X816582Y585714D03*
Y574849D03*
X819378Y553564D03*
Y531100D03*
X836810Y530949D03*
X833464Y537049D03*
X846850Y547914D03*
X833464D03*
X840157D03*
X828275Y547900D03*
X843503Y553614D03*
X836810D03*
X846850Y536999D03*
X843503Y530949D03*
X823199Y547898D03*
Y536999D03*
X823225Y529150D03*
X828325Y536750D03*
X840157Y537049D03*
X828312Y528936D03*
X819378Y568900D03*
X823175Y555700D03*
X828299Y555914D03*
X828275Y585700D03*
X823225Y566950D03*
X823199Y585698D03*
Y574799D03*
X828312Y566736D03*
X840157Y585714D03*
X833464D03*
X828325Y574550D03*
X840157Y574849D03*
X833464D03*
X836810Y568749D03*
X846850Y585714D03*
Y574799D03*
X843503Y568749D03*
X846850Y612599D03*
X840157Y612649D03*
X833464D03*
X823199Y612599D03*
X810039D03*
X803346Y612649D03*
X796653D03*
X816582D03*
X791514Y612350D03*
X806692Y606549D03*
X812999D03*
X799999D03*
X791501Y604536D03*
X806692Y591414D03*
X813035Y591314D03*
X799999Y591414D03*
X791488Y593714D03*
X819378Y606700D03*
Y591364D03*
X823225Y604750D03*
X823175Y593500D03*
X843503Y591414D03*
X828312Y604536D03*
X843503Y606549D03*
X836810D03*
X828325Y612350D03*
X836810Y591414D03*
X828299Y593714D03*
X870275Y9114D03*
X865086Y9100D03*
X860010Y9098D03*
X876968Y9114D03*
Y-1751D03*
X873621Y-7851D03*
X865123Y-9864D03*
X860036Y-9650D03*
X849810Y-7851D03*
X856189Y-7700D03*
X860010Y-1801D03*
X865136Y-2050D03*
X853543Y-1751D03*
X870275D03*
X853393Y9114D03*
X860036Y28150D03*
X859986Y16900D03*
X865110Y17114D03*
X856189Y14814D03*
X849846Y14714D03*
X873621Y14814D03*
Y29949D03*
X865123Y27936D03*
X849810Y29949D03*
X856189Y30100D03*
X896847Y-9650D03*
X910432Y-7851D03*
X883661Y-1801D03*
X880314Y-7851D03*
X886621D03*
X907086Y-1751D03*
X890354D03*
X896821Y-1801D03*
X901947Y-2050D03*
X901934Y-9864D03*
X893000Y-7700D03*
X883661Y9114D03*
X907086D03*
X896821Y9098D03*
X901897Y9100D03*
X890204Y9114D03*
X910432Y29949D03*
X896797Y16900D03*
X893000Y14814D03*
X901921Y17114D03*
X901934Y27936D03*
X893000Y30100D03*
X880314Y14814D03*
X886657Y14714D03*
X886621Y29949D03*
X880314D03*
X896847Y28150D03*
X910432Y14814D03*
X859986Y54700D03*
X870275Y36049D03*
X865136Y35750D03*
X865086Y46900D03*
X876968Y46914D03*
Y36049D03*
X873621Y67749D03*
Y52614D03*
X860010Y46898D03*
X860036Y65950D03*
X865123Y65736D03*
X849810Y67749D03*
X856189Y67900D03*
X853393Y46914D03*
X870275D03*
X865110Y54914D03*
X860010Y35999D03*
X856189Y52614D03*
X853543Y36049D03*
X849846Y52514D03*
X876968Y84714D03*
Y73849D03*
X873621Y90414D03*
X870275Y73849D03*
X853543D03*
X860010Y73799D03*
X849846Y90314D03*
X856189Y90414D03*
X865110Y92714D03*
X870275Y84714D03*
X865086Y84700D03*
X853393Y84714D03*
X860010Y84698D03*
X859986Y92500D03*
X865136Y73550D03*
X910432Y67749D03*
X893000Y67900D03*
X901934Y65736D03*
X896847Y65950D03*
X910432Y52614D03*
X890204Y46914D03*
X896821Y35999D03*
X901921Y54914D03*
X896797Y54700D03*
X883661Y35999D03*
X886621Y67749D03*
X880314D03*
X883661Y46914D03*
X880314Y52614D03*
X886657Y52514D03*
X901947Y35750D03*
X901897Y46900D03*
X896821Y46898D03*
X893000Y52614D03*
X890354Y36049D03*
X907086D03*
X883661Y73799D03*
X910432Y90414D03*
X907086Y84714D03*
X901897Y84700D03*
X907086Y46914D03*
X896821Y84698D03*
X893000Y90414D03*
X890204Y84714D03*
X896797Y92500D03*
X901921Y92714D03*
X890354Y73849D03*
X896821Y73799D03*
X901947Y73550D03*
X907086Y73849D03*
X883661Y84714D03*
X886657Y90314D03*
X880314Y90414D03*
X886657Y109884D03*
X907086Y104284D03*
X901934Y105051D03*
X896847Y105265D03*
X890204Y104284D03*
X893000Y109534D03*
X896821Y113114D03*
X901947Y112865D03*
X910432Y109984D03*
X883661Y104284D03*
X873621Y515814D03*
X876968Y510114D03*
X870275D03*
X859986Y517900D03*
X865086Y510100D03*
X860010Y510098D03*
X865110Y518114D03*
X853393Y510114D03*
X856189Y515814D03*
X849846Y515714D03*
X907000Y495800D03*
X882900Y495900D03*
X893000Y493094D03*
X886500Y493400D03*
X910432Y491044D03*
X901921Y490514D03*
X896785D03*
X901921Y498514D03*
X896785D03*
X889100Y498500D03*
X901897Y510100D03*
X893000Y515814D03*
X890204Y510114D03*
X896821Y510098D03*
X901921Y518114D03*
X896797Y517900D03*
X880314Y515814D03*
X886657Y515714D03*
X883661Y510114D03*
X910432Y515814D03*
X907086Y510114D03*
X860010Y536999D03*
X865123Y528936D03*
X873621Y530949D03*
Y553614D03*
X876968Y537049D03*
Y547914D03*
X860010Y547898D03*
X870275Y547914D03*
X853393D03*
X865086Y547900D03*
X856189Y553614D03*
X849846Y553514D03*
X870275Y537049D03*
X853543D03*
X856189Y531100D03*
X849810Y530949D03*
X865136Y536750D03*
X860036Y529150D03*
X849810Y568749D03*
X865086Y585700D03*
X860010Y585698D03*
X865136Y574550D03*
X859986Y555700D03*
X865110Y555914D03*
X860010Y574799D03*
X853393Y585714D03*
X870275D03*
X873621Y568749D03*
X876968Y574849D03*
Y585714D03*
X860036Y566950D03*
X865123Y566736D03*
X870275Y574849D03*
X853543D03*
X856189Y568900D03*
X890354Y537049D03*
X893000Y531100D03*
X896821Y536999D03*
X901934Y528936D03*
X901947Y536750D03*
X910432Y530949D03*
X907086Y537049D03*
X886621Y530949D03*
X883661Y536999D03*
X880314Y530949D03*
Y553614D03*
X886657Y553514D03*
X883661Y547914D03*
X893000Y553614D03*
X910432D03*
X890204Y547914D03*
X896821Y547898D03*
X901897Y547900D03*
X907086Y547914D03*
X880314Y568749D03*
X886621D03*
X883661Y574799D03*
Y585714D03*
X901921Y555914D03*
X896797Y555700D03*
X901934Y566736D03*
X896847Y566950D03*
X901897Y585700D03*
X890354Y574849D03*
X896821Y574799D03*
X893000Y568900D03*
X901947Y574550D03*
X896821Y585698D03*
X890204Y585714D03*
X910432Y568749D03*
X907086Y574849D03*
Y585714D03*
X890354Y612649D03*
X896821Y612599D03*
X883661D03*
X907086Y612649D03*
X870275D03*
X876968D03*
X860010Y612599D03*
X853543Y612649D03*
X859986Y593500D03*
X865110Y593714D03*
X856189Y591414D03*
X849846Y591314D03*
X860036Y604750D03*
X865123Y604536D03*
X856189Y606700D03*
X849810Y606549D03*
X865136Y612350D03*
X873621Y606549D03*
Y591414D03*
X886657Y591314D03*
X896847Y604750D03*
X901934Y604536D03*
X901947Y612350D03*
X896797Y593500D03*
X901921Y593714D03*
X893000Y591414D03*
X910432D03*
Y606549D03*
X893000Y606700D03*
X880314Y606549D03*
X886621D03*
X880314Y591414D03*
X923432Y-7851D03*
X929811Y-7700D03*
X933658Y-9650D03*
X917125Y-7851D03*
X913779Y-1751D03*
X933632Y-1801D03*
X927165Y-1751D03*
X920472Y-1801D03*
X927015Y9114D03*
X933632Y9098D03*
X913779Y9114D03*
X920472D03*
X923432Y29949D03*
X917125D03*
Y14814D03*
X929811D03*
X933608Y16900D03*
X923468Y14714D03*
X933658Y28150D03*
X929811Y30100D03*
X938745Y-9864D03*
X938758Y-2050D03*
X938708Y9100D03*
X947243Y-7851D03*
X950590Y-1751D03*
X957283Y-1843D03*
X953936Y-7851D03*
X943897Y-1751D03*
Y9114D03*
X950590D03*
X938745Y27936D03*
X938732Y17114D03*
X957283Y9300D03*
X953936Y14814D03*
Y29949D03*
X957600Y13200D03*
X957700Y32100D03*
X970800Y13200D03*
X970942Y32100D03*
X947243Y29949D03*
Y14814D03*
X933658Y65950D03*
X923432Y67749D03*
X929811Y67900D03*
X917125Y67749D03*
X920472Y35999D03*
X917125Y52614D03*
X913779Y46914D03*
Y36049D03*
X927015Y73849D03*
X913779D03*
X920472Y73799D03*
X933632D03*
X913779Y84714D03*
X920472D03*
X933608Y92500D03*
X920472Y46914D03*
X933632Y35999D03*
X927165Y36049D03*
X927015Y46914D03*
X933608Y54700D03*
X933632Y46898D03*
X929811Y52614D03*
X933632Y84698D03*
X927015Y84714D03*
X923468Y90314D03*
X929811Y90414D03*
X917125D03*
X953936Y52614D03*
X957558Y50729D03*
X938758Y35750D03*
X938708Y46900D03*
X938732Y54914D03*
X938745Y65736D03*
X950590Y36049D03*
X953936Y67749D03*
X950590Y46914D03*
X970800Y50860D03*
X947243Y67749D03*
X943897Y36049D03*
Y46914D03*
X947243Y52614D03*
X957283Y35957D03*
X970669Y87392D03*
Y73757D03*
X938708Y84700D03*
X938732Y92714D03*
X938758Y73550D03*
X957600Y70400D03*
X943897Y84714D03*
X947243Y90414D03*
X943897Y73849D03*
X950590D03*
X953886Y90414D03*
X950590Y84714D03*
X957774Y87394D03*
X957200Y73800D03*
X933658Y105265D03*
X929811Y109534D03*
X933632Y113114D03*
X923468Y109884D03*
X917125Y109984D03*
X920472Y104284D03*
X913779D03*
X927015D03*
X938758Y112865D03*
X938745Y105051D03*
X947250Y107700D03*
X950600Y112300D03*
X953800Y105000D03*
X927607Y203260D03*
Y207159D03*
X934367D03*
Y199360D03*
X930987Y201309D03*
X934367Y214960D03*
X930987Y213009D03*
X920847Y211060D03*
X927607Y214960D03*
Y211060D03*
X937747Y216909D03*
X924227D03*
Y213009D03*
X968166Y218860D03*
X951256Y194841D03*
X958026Y201309D03*
X967036Y193507D03*
X947887Y203260D03*
Y207159D03*
X944507Y213009D03*
Y201309D03*
X947887Y199360D03*
X941127D03*
Y207159D03*
X947887Y211060D03*
Y218860D03*
X941127D03*
Y214960D03*
X962526Y205210D03*
X961406Y214960D03*
Y211060D03*
Y218860D03*
X951267Y209109D03*
X958026Y213009D03*
X954647Y211060D03*
Y218860D03*
X964786Y213009D03*
Y216909D03*
Y209109D03*
X934367Y226660D03*
X924227Y236409D03*
X920847Y238360D03*
X913787Y226660D03*
X913700Y222710D03*
X913787Y238360D03*
X924227Y232509D03*
X927607Y230559D03*
Y234460D03*
X930987Y232509D03*
X934367Y234460D03*
X924227Y228610D03*
X930987Y220809D03*
X924227Y224709D03*
X937747Y232509D03*
Y236409D03*
X924227Y240309D03*
X917467D03*
X930987D03*
X924227Y248109D03*
Y244209D03*
X917467D03*
X913787Y250060D03*
X934367Y246160D03*
X927607Y250060D03*
X924227Y220809D03*
X913787Y253960D03*
X927607D03*
X934367D03*
X937747Y252009D03*
X930987D03*
X924227D03*
X917467D03*
Y259809D03*
X924227D03*
X930987D03*
X920847Y265660D03*
X930987Y275409D03*
X937747D03*
Y271509D03*
Y255909D03*
X934367Y277360D03*
X930987Y271509D03*
X934367Y273460D03*
X927607Y269560D03*
X917467Y263709D03*
X913787Y265660D03*
X924227Y267609D03*
X934367Y265660D03*
X924227Y263709D03*
Y275409D03*
X927607Y277360D03*
X920847Y273460D03*
Y269560D03*
X924227Y255909D03*
X951267Y248109D03*
X958026Y244209D03*
X968166Y242260D03*
X944507Y228610D03*
Y224709D03*
Y244209D03*
Y248109D03*
X941127Y242260D03*
Y250060D03*
Y246160D03*
X947887D03*
X941127Y222760D03*
X947887Y226660D03*
Y234460D03*
X941127Y238360D03*
Y234460D03*
Y230559D03*
Y226660D03*
X971546Y248109D03*
X968166Y246160D03*
X951267Y240309D03*
X958026D03*
X964786D03*
X954647Y246160D03*
Y250060D03*
X958026Y228610D03*
Y236409D03*
X961406Y238360D03*
X951267Y228610D03*
X954647Y226660D03*
X958026Y224709D03*
Y232509D03*
X954647Y230559D03*
X961406Y222760D03*
X968166Y226660D03*
X971546Y236409D03*
X968166Y238360D03*
X971546Y220809D03*
X964786Y232509D03*
Y220809D03*
X947887Y253960D03*
X941127D03*
X958026Y252009D03*
X968166Y277360D03*
X951267Y275409D03*
X961406Y277360D03*
X958026Y263709D03*
X968166Y269560D03*
X961406Y261760D03*
X958026Y255909D03*
X951267Y259809D03*
X958026D03*
X954647Y277360D03*
Y265660D03*
X951267Y267609D03*
X954647Y273460D03*
X958026Y275409D03*
X954647Y269560D03*
X961406D03*
X971546Y275409D03*
Y263709D03*
X941127Y277360D03*
Y265660D03*
X944507Y275409D03*
Y263709D03*
X941127Y269560D03*
Y257860D03*
Y261760D03*
X947887Y277360D03*
Y265660D03*
X971546Y259809D03*
Y255909D03*
X964786Y279310D03*
X934367Y285160D03*
Y300760D03*
X927607D03*
Y308560D03*
X934367D03*
X927607Y285160D03*
Y292959D03*
X934367D03*
X937747Y318309D03*
Y341709D03*
Y326110D03*
X917467Y333909D03*
Y341709D03*
X913787Y339760D03*
X924227Y333909D03*
Y337809D03*
Y341709D03*
X913787Y328060D03*
X924227Y330009D03*
X920847Y328060D03*
X917467Y330009D03*
X930987Y326110D03*
X934367Y331960D03*
X927607Y328060D03*
X934367Y324160D03*
X924227Y322209D03*
X927607Y320260D03*
X930987Y318309D03*
X934367Y316360D03*
X927607D03*
X930987Y337809D03*
X924227Y326110D03*
X961406Y292959D03*
Y285160D03*
X954647Y292959D03*
Y285160D03*
X968166Y292959D03*
Y300760D03*
X971546Y310509D03*
X964786D03*
X954647Y308560D03*
X961406D03*
X954647Y300760D03*
X961406D03*
X964786Y283209D03*
X971546D03*
X947887Y308560D03*
X941127D03*
Y300760D03*
X947887D03*
X941127Y285160D03*
Y292959D03*
X947887D03*
Y285160D03*
X968166Y281260D03*
X958026Y333909D03*
Y337809D03*
Y341709D03*
Y318309D03*
X951267D03*
X954647Y316360D03*
X961406D03*
Y324160D03*
X971546Y337809D03*
X964786Y330009D03*
X971546D03*
X951267D03*
X958026D03*
X968166Y312460D03*
X964786Y314409D03*
X951267Y337809D03*
X954647Y331960D03*
Y328060D03*
X971546Y322209D03*
X968166Y320260D03*
X964786Y322209D03*
X958026Y326110D03*
X947887Y316360D03*
X941127D03*
X944507Y322209D03*
Y318309D03*
X947887Y331960D03*
Y328060D03*
X941127Y331960D03*
Y328060D03*
Y339760D03*
Y335860D03*
X944507Y333909D03*
X937747Y365109D03*
Y345609D03*
Y361209D03*
X924227Y365109D03*
X930987D03*
X927607Y367060D03*
X934367Y370959D03*
Y363160D03*
X927607D03*
X924227Y369010D03*
X913787Y343660D03*
X934367D03*
X927607D03*
Y347560D03*
X934367Y351460D03*
X930987Y357309D03*
Y345609D03*
X917467Y353409D03*
Y349509D03*
X913787Y355360D03*
X924227Y349509D03*
Y345609D03*
Y353409D03*
Y361209D03*
Y357309D03*
X920847Y355360D03*
X917167Y361209D03*
Y369010D03*
X934367Y382660D03*
X930987Y384609D03*
Y376809D03*
X934367Y390460D03*
X927607Y386560D03*
Y390460D03*
X930987Y396309D03*
X934367Y398260D03*
X927607Y394359D03*
X917467Y388509D03*
X924227Y392410D03*
X920847Y390460D03*
X924227Y372909D03*
X937747Y400209D03*
X917100Y380709D03*
X937747D03*
X924227D03*
X920847Y382660D03*
X924227Y376809D03*
X927607Y382660D03*
X968166Y370959D03*
X958026Y361209D03*
X954647Y347560D03*
X961406Y359260D03*
X958026Y357309D03*
X951267D03*
X941127Y355360D03*
Y347560D03*
Y351460D03*
X958026Y345609D03*
X951267Y349509D03*
X954647Y351460D03*
X958026Y353409D03*
X968166Y355360D03*
Y351460D03*
X964786Y357309D03*
X971546Y361209D03*
X968166Y359260D03*
X958026Y365109D03*
X964786D03*
X954647Y370959D03*
Y367060D03*
X958026Y369010D03*
X951267D03*
X971546Y349509D03*
X947887Y363160D03*
X941127D03*
X947887Y370959D03*
X941127D03*
Y367060D03*
X944507Y369010D03*
X947887Y343660D03*
X941127Y359260D03*
X944507Y349509D03*
Y353409D03*
X941127Y343660D03*
X947887Y351460D03*
X958026Y372909D03*
X941127Y374860D03*
X961406D03*
X944507Y372909D03*
X941127Y382660D03*
Y378760D03*
X947887D03*
X944507Y384609D03*
X947887Y390460D03*
Y386560D03*
X941127Y390460D03*
X947887Y398260D03*
X941127D03*
X944507Y396309D03*
X947887Y394359D03*
X964786Y376809D03*
X971546D03*
X968166Y378760D03*
Y386560D03*
X964786Y392410D03*
X968166Y390460D03*
Y394359D03*
X964786Y388509D03*
X961406Y378760D03*
X954647D03*
X958026Y384609D03*
X961406Y382660D03*
X951267Y388509D03*
X958026D03*
X954647Y394359D03*
X961406Y386560D03*
X952216Y402421D03*
X970416Y401941D03*
X971546Y380709D03*
X968166Y382660D03*
X920700Y495944D03*
X913800Y495800D03*
X927165Y495944D03*
X929811Y515814D03*
X933632Y510098D03*
X923600Y491144D03*
X917192Y491219D03*
X933632Y490644D03*
X929811D03*
X933632Y498644D03*
X933608Y517900D03*
X913779Y510114D03*
X917125Y515814D03*
X923468Y515714D03*
X920472Y510114D03*
X927015D03*
X938732Y490644D03*
X950700Y490700D03*
X943897Y490444D03*
X970669Y512792D03*
X967322Y515364D03*
X938708Y510100D03*
X938732Y518114D03*
Y498644D03*
X954000Y497300D03*
X953886Y515814D03*
X950590Y510114D03*
X943897D03*
X947243Y515814D03*
X947443Y497644D03*
X957774Y512794D03*
X933632Y536999D03*
X929811Y531100D03*
X933658Y529150D03*
X913779Y537049D03*
X917125Y530949D03*
X927015Y537049D03*
X923432Y530949D03*
X920472Y536999D03*
X923468Y553514D03*
X917125Y553614D03*
X913779Y547914D03*
X927015D03*
X920472D03*
X933632Y547898D03*
X929811Y553614D03*
X933608Y555700D03*
X933632Y585698D03*
X933658Y566950D03*
X929811Y568900D03*
X933632Y574799D03*
X920472D03*
X927015Y585714D03*
X920472D03*
X913779Y574849D03*
X917125Y568749D03*
X913779Y585714D03*
X923432Y568749D03*
X927015Y574849D03*
X970669Y536957D03*
X967322Y529014D03*
X938745Y528936D03*
X938758Y536750D03*
X938708Y547900D03*
X957600Y533100D03*
X957701Y552000D03*
X970731D03*
X950590Y537049D03*
X957283Y536957D03*
X953936Y530949D03*
X957283Y548200D03*
X953886Y553614D03*
X950590Y547914D03*
X947243Y530949D03*
X943897Y537049D03*
Y547914D03*
X947243Y553614D03*
X938732Y555914D03*
X938745Y566736D03*
X938758Y574550D03*
X938708Y585700D03*
X957600Y570900D03*
X970942D03*
X950590Y574849D03*
Y585714D03*
X957283Y574757D03*
X957456Y588334D03*
X953936Y568749D03*
X943897Y574849D03*
X947243Y568749D03*
X943897Y585714D03*
X933632Y612599D03*
X923432Y606549D03*
X917125D03*
X933658Y604750D03*
X923468Y591314D03*
X917125Y591414D03*
X933608Y593500D03*
X929811Y591414D03*
X927015Y612449D03*
X920472Y612399D03*
X913779Y612449D03*
X929811Y606700D03*
X938758Y612350D03*
X938745Y604536D03*
X938732Y593714D03*
X957500Y591000D03*
X970731Y589800D03*
X953936Y606549D03*
X957283Y611600D03*
X950590Y612249D03*
X953886Y591414D03*
X947243Y606549D03*
X943897Y612249D03*
X947243Y591414D03*
X983900Y13200D03*
Y32100D03*
X1028400Y6500D03*
X1030407Y-8938D03*
X1008200Y30736D03*
X1007100Y11714D03*
X1008227Y33342D03*
X1030400Y26150D03*
X1030450Y23150D03*
X1007100Y14314D03*
X987401Y65814D03*
X977362D03*
X997441Y65822D03*
X983900Y51000D03*
X997441Y92757D03*
X990748Y73757D03*
Y87392D03*
X977362Y92757D03*
X987401Y89964D03*
X980708Y84714D03*
Y73757D03*
X1007370Y52333D03*
Y49659D03*
X1007480Y65736D03*
X1014350Y73000D03*
X1000787Y84599D03*
Y73757D03*
X1007480Y87500D03*
X1008099Y73479D03*
X1030400Y56500D03*
X1031600Y42900D03*
X1023900Y74100D03*
Y77200D03*
X974100Y103500D03*
X983936Y199108D03*
X973808Y201308D03*
X998586Y209109D03*
X981686Y218860D03*
X974926Y211060D03*
X985066Y216909D03*
X988446Y211058D03*
X979426Y214958D03*
X1005345Y209109D03*
X1001965Y211060D03*
X1025625Y209109D03*
X1012105D03*
X1032385D03*
X995206Y238360D03*
X988446Y234460D03*
X998586Y248109D03*
Y220809D03*
X985066Y248109D03*
X981686Y250060D03*
X974926D03*
X988446Y246160D03*
X981686Y242260D03*
X974926D03*
X988446D03*
Y238360D03*
X985066Y236409D03*
X981686Y234460D03*
X974926Y226660D03*
X991826Y220809D03*
X974926Y230559D03*
Y234460D03*
Y222760D03*
X985066Y224709D03*
X978306Y232509D03*
Y220809D03*
X974926Y253960D03*
X988446D03*
X978306Y252009D03*
X985066D03*
X974926Y265660D03*
X991826Y259809D03*
X985066D03*
X981686Y269560D03*
X995206D03*
X985066Y267609D03*
X991826Y263709D03*
X988446Y265660D03*
X998586Y263709D03*
X991826Y271509D03*
X995206Y273460D03*
X991826Y279310D03*
Y275409D03*
X974926Y269560D03*
X978306Y267609D03*
Y259809D03*
X991826Y255909D03*
X995206Y265660D03*
X991826Y267609D03*
X974926Y273460D03*
X1029005Y238360D03*
X1005345Y248109D03*
X1008725Y238360D03*
X1001965D03*
X1005345Y220809D03*
X1029005Y250060D03*
X1032385Y248109D03*
X1025625D03*
X1022245Y250060D03*
X1025625Y220809D03*
X1012105D03*
X1015485Y238360D03*
X1022245D03*
X1018865Y220809D03*
X1032385D03*
X1001965Y261760D03*
X1012105Y255909D03*
X1015485Y253960D03*
X1018865Y252009D03*
X1005345Y259809D03*
X1008725Y257860D03*
X981686Y281260D03*
Y292959D03*
Y300760D03*
X988446D03*
X978306Y310509D03*
X991826D03*
X985066D03*
X974926Y300760D03*
X988446Y292959D03*
X991826Y283209D03*
X988446Y281260D03*
X985066Y283209D03*
X978306D03*
X974926Y292959D03*
Y281260D03*
X991826Y333909D03*
X995206Y335860D03*
Y339760D03*
Y328060D03*
X991826Y326110D03*
X981686Y339760D03*
X978306Y333909D03*
Y330009D03*
Y326110D03*
X981686Y331960D03*
X985066Y330009D03*
X974926Y324160D03*
X988446Y339760D03*
X974926Y312460D03*
X981686D03*
X988446D03*
X991826Y314409D03*
Y330009D03*
X995206Y331960D03*
X988446D03*
X995206Y324160D03*
X988446Y316360D03*
X991826Y318309D03*
X995206Y320260D03*
X991826Y322209D03*
X998586Y333909D03*
X974926Y339760D03*
Y335860D03*
X1017957Y312421D03*
X1025438Y312381D03*
X1022915Y312372D03*
X1020404Y312408D03*
X1028039Y312414D03*
X1008725Y339760D03*
X1005345Y337809D03*
X1001965Y335860D03*
X1012105Y341709D03*
X995206Y343660D03*
X985066Y361209D03*
X974926Y355360D03*
Y347560D03*
X981686D03*
X978306Y345609D03*
X981686Y355360D03*
X985066Y349509D03*
X998586D03*
X978306Y365109D03*
X981686Y363160D03*
X974926D03*
Y367060D03*
Y370959D03*
Y343660D03*
X995206Y359260D03*
X988446D03*
Y347560D03*
X991826Y345609D03*
X988446Y351460D03*
Y355360D03*
X985066Y372909D03*
X974926Y374860D03*
X985066Y384609D03*
X998586Y376809D03*
X991826Y388509D03*
X995206Y390460D03*
X974926Y386560D03*
X991826Y376809D03*
X974066Y399911D03*
X978306Y376809D03*
X974926Y378760D03*
X981686D03*
X985066Y380709D03*
X1001965Y359260D03*
X1005345Y349509D03*
X1008725Y359260D03*
X1015485D03*
X1018865Y345609D03*
X1022245Y347560D03*
X1015485Y343660D03*
X1025625Y345609D03*
X1022245Y359260D03*
X1029005Y347560D03*
Y359260D03*
X1032385Y349509D03*
Y388509D03*
Y376809D03*
X1005345D03*
Y388509D03*
X1001965Y386560D03*
X1025625Y376809D03*
Y388509D03*
X1018865Y376809D03*
X1012105D03*
X1018865Y388509D03*
X1012105D03*
X987401Y515364D03*
X990748Y512792D03*
X997441Y518157D03*
X973795Y499793D03*
X980708Y510114D03*
X977362Y518157D03*
X1034200Y506956D03*
X1000490Y509999D03*
X1008650Y515200D03*
X990748Y536957D03*
X977362Y529014D03*
X980708Y536957D03*
X987401Y529014D03*
X997441Y529022D03*
X983900Y552000D03*
Y570900D03*
X1007147Y550511D03*
Y553111D03*
X1013500Y529200D03*
X1026500Y538500D03*
Y541000D03*
Y546400D03*
X1000787Y536957D03*
X1007518Y536727D03*
X1007480Y528942D03*
X1006406Y588366D03*
X1007332Y572010D03*
X1016473Y585714D03*
X1026500Y577500D03*
X1007332Y569410D03*
X983900Y589800D03*
X1023200Y610700D03*
X1022950Y593650D03*
X1025450D03*
X1006406Y590966D03*
X1043800Y-9700D03*
X1057792Y13200D03*
Y32100D03*
X1083116Y13200D03*
Y32100D03*
X1070976Y13200D03*
Y32100D03*
X1057676Y87392D03*
X1050983Y92757D03*
X1047637Y84599D03*
X1057677Y73742D03*
X1047637D03*
X1057792Y51000D03*
X1067716Y65807D03*
X1091141D03*
X1083116Y51000D03*
X1070976D03*
X1067716Y89964D03*
Y84599D03*
X1081102D03*
X1091141Y87392D03*
Y92657D03*
X1077755Y92757D03*
X1074409Y84714D03*
X1084448Y92757D03*
X1061023Y89964D03*
X1067716Y73742D03*
X1074409D03*
X1081102D03*
X1091141D03*
X1050983Y105800D03*
X1057734Y105750D03*
X1035900Y98800D03*
X1077304Y105800D03*
X1071111D03*
X1064428D03*
X1057314Y209109D03*
X1045904D03*
X1039145D03*
X1072202Y216196D03*
X1065242Y208397D03*
X1068822Y214247D03*
X1065242Y212296D03*
Y204496D03*
X1071072Y199583D03*
X1095861Y218147D03*
X1089101Y214247D03*
Y210346D03*
X1092481Y216196D03*
X1095861Y206446D03*
X1091351Y199841D03*
X1075582Y206446D03*
Y218147D03*
X1082341D03*
X1078962Y216196D03*
X1078961Y212296D03*
X1082341Y214247D03*
X1085721Y212296D03*
Y216196D03*
X1084591Y198931D03*
X1045904Y220809D03*
X1057314D03*
X1035765Y238360D03*
Y250060D03*
X1057314Y248109D03*
X1039145D03*
X1042524Y250060D03*
X1049284D03*
X1045904Y248109D03*
X1042524Y238360D03*
X1039145Y220809D03*
X1095861Y229847D03*
X1068822Y233746D03*
X1065242Y235696D03*
Y223996D03*
X1068822Y237647D03*
Y249347D03*
X1065242Y247396D03*
X1068822Y241547D03*
X1072202Y243496D03*
Y251296D03*
X1092481Y223996D03*
Y231797D03*
X1089101Y233746D03*
Y237647D03*
X1095861D03*
Y245447D03*
X1078962Y251296D03*
X1082341Y245447D03*
Y249347D03*
X1078962Y247396D03*
X1092481Y243496D03*
X1075582Y245447D03*
X1085721Y251296D03*
X1075582Y249347D03*
X1085721Y243496D03*
X1089101Y241547D03*
X1085721Y223996D03*
X1075582Y229847D03*
X1082341D03*
X1078962Y227896D03*
Y220096D03*
Y223996D03*
X1085721Y231797D03*
X1082341Y237647D03*
X1075582D03*
X1072202Y231797D03*
Y223996D03*
X1089101Y253247D03*
X1092481Y255196D03*
X1095861Y257147D03*
X1042524Y359260D03*
X1049284Y351460D03*
X1045904Y353409D03*
X1035765Y351460D03*
Y359260D03*
X1039145Y353409D03*
X1042524Y351460D03*
X1054914Y347000D03*
X1039145Y388509D03*
X1045904D03*
X1052664D03*
X1039145Y376809D03*
X1045904D03*
X1052664D03*
X1060694Y351460D03*
X1086841Y358547D03*
X1094731Y346546D03*
X1086841Y354647D03*
X1090221Y352696D03*
X1091351Y348497D03*
X1073322Y354647D03*
X1076702Y356596D03*
X1080082Y354647D03*
X1083462Y368296D03*
X1076702Y372197D03*
Y368296D03*
X1073322Y362447D03*
X1086841D03*
X1090221Y372197D03*
Y364396D03*
X1093601Y366347D03*
X1090221Y368296D03*
X1076702Y360496D03*
X1083462D03*
Y352696D03*
X1076702D03*
X1093601Y358547D03*
X1090221Y379996D03*
X1073323Y401449D03*
X1078962Y399496D03*
X1093601Y401447D03*
X1060694Y374860D03*
X1073322Y374146D03*
X1086841D03*
X1073323Y397548D03*
X1073322Y385847D03*
X1080082Y393647D03*
X1083462Y391696D03*
X1080082Y385847D03*
X1083462Y376096D03*
X1080082Y378047D03*
X1083462Y379996D03*
X1076702Y376096D03*
X1090221Y395595D03*
X1086841Y389747D03*
X1093601Y393647D03*
X1090221Y391696D03*
X1093601Y385847D03*
X1086841D03*
X1093601Y397546D03*
Y378047D03*
X1086841Y381947D03*
X1093601Y405347D03*
X1077832Y407800D03*
X1035750Y503006D03*
X1047637Y509999D03*
X1057676Y512792D03*
X1050983Y518157D03*
X1067716Y509999D03*
X1074409Y510114D03*
X1061023Y515364D03*
X1091141Y518057D03*
X1077755Y518157D03*
X1081102Y509999D03*
X1084448Y518157D03*
X1082800Y497650D03*
X1091141Y512792D03*
X1067716Y515364D03*
X1057792Y552000D03*
X1057677Y536942D03*
X1047637D03*
X1057792Y570900D03*
X1091141Y529007D03*
Y536942D03*
X1074409D03*
X1081102D03*
X1067716D03*
Y529007D03*
X1070976Y552000D03*
X1083116D03*
X1070976Y570900D03*
X1083116D03*
X1057792Y589800D03*
X1070242D03*
X1083108D03*
X1119453Y-9864D03*
X1097352Y-7180D03*
X1104141Y-7851D03*
X1110520Y-7700D03*
X1114340Y-1801D03*
X1107874Y-1751D03*
X1101181Y-1801D03*
X1107724Y9114D03*
X1101181D03*
X1114340Y9098D03*
X1114400Y28100D03*
X1110520Y14814D03*
X1104177Y14714D03*
X1098500Y17000D03*
X1114300Y16900D03*
X1119400Y9300D03*
X1119453Y27936D03*
X1119440Y17114D03*
X1097900Y13700D03*
Y31900D03*
X1110520Y30100D03*
X1097834Y28100D03*
X1104141Y29949D03*
X1156300Y-2000D03*
X1151152Y-1801D03*
X1131299Y9114D03*
X1124606D03*
X1151152Y9098D03*
X1137992Y9114D03*
X1144535D03*
X1127952Y-7851D03*
X1124606Y-1751D03*
X1131299D03*
X1134645Y-7851D03*
X1156265Y-9864D03*
X1151200Y-9700D03*
X1147331Y-7700D03*
X1140952Y-7851D03*
X1137992Y-1801D03*
X1144685Y-1751D03*
X1156212Y9300D03*
X1127952Y14814D03*
X1151211Y28100D03*
X1156252Y17114D03*
X1151112Y16900D03*
X1147331Y30100D03*
Y14814D03*
X1134645Y29949D03*
X1140952D03*
X1140988Y14714D03*
X1134645Y14814D03*
X1156265Y27936D03*
X1127952Y29949D03*
X1114340Y35999D03*
X1110520Y67900D03*
X1104141Y67749D03*
X1114366Y65950D03*
X1119440Y54914D03*
X1119400Y47100D03*
Y35800D03*
X1098100Y51000D03*
X1119453Y65736D03*
X1107874Y36049D03*
X1098022Y35761D03*
X1101181Y35999D03*
X1107724Y46914D03*
X1110520Y52614D03*
X1098581Y54883D03*
X1104177Y52514D03*
X1101181Y46900D03*
X1098125Y46975D03*
X1114300Y54700D03*
X1114340Y46898D03*
X1101181Y84714D03*
X1114340Y73799D03*
X1107874Y73849D03*
X1101181Y73799D03*
X1110520Y90314D03*
X1114340Y84698D03*
X1114316Y92500D03*
X1107724Y84714D03*
X1119440Y92714D03*
X1119416Y84700D03*
X1119466Y73550D03*
X1098300Y89900D03*
X1104177Y90314D03*
X1127952Y67749D03*
X1156211Y35800D03*
X1156200Y47000D03*
X1151152Y35999D03*
Y46898D03*
X1151100Y54700D03*
X1147331Y52614D03*
X1134645D03*
X1137992Y46914D03*
Y35999D03*
X1144535Y46914D03*
X1144685Y36049D03*
X1156252Y54914D03*
X1134645Y67749D03*
X1140952D03*
X1156265Y65736D03*
X1151178Y65950D03*
X1147331Y67900D03*
X1131299Y46914D03*
X1124606D03*
X1127952Y52614D03*
X1131299Y36049D03*
X1124606D03*
X1131299Y73849D03*
X1124606D03*
X1127952Y90414D03*
X1131299Y84714D03*
X1124606D03*
X1147331Y90414D03*
X1137992Y73799D03*
X1144535Y84714D03*
X1140988Y90314D03*
X1137992Y84714D03*
X1134645Y90414D03*
X1144685Y73849D03*
X1156252Y92714D03*
X1151128Y92500D03*
X1151152Y84698D03*
X1156228Y84700D03*
X1156278Y73550D03*
X1151152Y73799D03*
X1138242Y104314D03*
X1144685D03*
X1156278Y112865D03*
X1151152Y113114D03*
X1141038Y109564D03*
X1147331D03*
X1156265Y105051D03*
X1151178Y105265D03*
X1116141Y206446D03*
X1136420Y210346D03*
X1099241Y216196D03*
Y212296D03*
X1109381Y214247D03*
X1116141Y218147D03*
X1106001Y212296D03*
X1102621Y218147D03*
Y214247D03*
X1119521Y216196D03*
X1119520Y212296D03*
X1104871Y198050D03*
X1106001Y216196D03*
X1112761D03*
X1129660Y206447D03*
X1126280Y216196D03*
Y212296D03*
X1125300Y199900D03*
X1122900Y214247D03*
Y218147D03*
X1129660Y214247D03*
X1147950Y209900D03*
X1136420Y218147D03*
Y214247D03*
X1151060Y212296D03*
X1157820D03*
X1099241Y227896D03*
Y220096D03*
X1102621Y229847D03*
X1099241Y223996D03*
X1109381Y233746D03*
X1112761Y231797D03*
Y223996D03*
X1116141Y237647D03*
X1109381D03*
X1106001Y223996D03*
X1102621Y237647D03*
Y245447D03*
X1112761Y251296D03*
X1116141Y245447D03*
X1106001Y243496D03*
X1112761D03*
X1109381Y241547D03*
X1106001Y251296D03*
X1099241D03*
Y247396D03*
X1119521Y223996D03*
Y220096D03*
Y227896D03*
Y247396D03*
Y251296D03*
X1106001Y231797D03*
X1116141Y229847D03*
X1107561Y269038D03*
X1116141Y264947D03*
X1111631Y271300D03*
X1106001Y262996D03*
Y259096D03*
X1099241Y255196D03*
Y259096D03*
X1119521Y270796D03*
X1118391Y274997D03*
X1119521Y255196D03*
X1102621Y261047D03*
Y257147D03*
X1109381Y261047D03*
X1116141Y257147D03*
X1112761Y259096D03*
X1110648Y276899D03*
X1100200Y273300D03*
X1129660Y237647D03*
X1126280Y223996D03*
Y231797D03*
X1122900Y229847D03*
Y237647D03*
X1129660Y233746D03*
Y241547D03*
X1126280Y251296D03*
Y243496D03*
X1122900Y245447D03*
X1144300Y243496D03*
X1151060Y247396D03*
X1154440Y245447D03*
X1144300Y247396D03*
Y251296D03*
X1136420Y245447D03*
X1154440Y241547D03*
X1136420D03*
X1157820Y239596D03*
X1147680Y222047D03*
X1144300Y235696D03*
X1136420Y229847D03*
Y233746D03*
Y222047D03*
Y225947D03*
Y237647D03*
X1133040Y223996D03*
Y235696D03*
Y243496D03*
Y251296D03*
X1147680Y225947D03*
X1151060Y223996D03*
X1147680Y233746D03*
X1154440Y229847D03*
X1157820Y220096D03*
Y223996D03*
Y231797D03*
X1154440Y253247D03*
X1130780Y278596D03*
X1129660Y261047D03*
X1130780Y274696D03*
X1126280Y259096D03*
X1122900Y257147D03*
X1157820Y278596D03*
Y270796D03*
X1151060Y266896D03*
Y274696D03*
X1137540D03*
X1151060Y259096D03*
X1144300Y255196D03*
X1133040Y259096D03*
X1134160Y268847D03*
X1136420Y257147D03*
X1144300Y278596D03*
Y270796D03*
X1137540Y278596D03*
X1119521Y286396D03*
Y305896D03*
X1108251Y338746D03*
X1117261Y340996D03*
X1104871Y340697D03*
X1119521Y321496D03*
X1130780Y290296D03*
X1127400Y288347D03*
X1130780Y309797D03*
Y301996D03*
X1127400Y303947D03*
Y307847D03*
X1157820Y290296D03*
X1151060Y298096D03*
Y290296D03*
Y282496D03*
X1144300Y286396D03*
Y294196D03*
X1157820D03*
X1140920Y300047D03*
X1134160Y292247D03*
Y300047D03*
X1140920Y292247D03*
X1137540Y282496D03*
X1144300Y309797D03*
X1137540D03*
X1147680Y303947D03*
X1154440Y307847D03*
X1130780Y313696D03*
X1157820D03*
X1124021Y340996D03*
Y337096D03*
X1127400Y327347D03*
X1157820Y337096D03*
Y333196D03*
X1134160Y323446D03*
X1151060Y340996D03*
Y333196D03*
X1154440Y319547D03*
X1157820Y317596D03*
X1137540D03*
X1157820Y329296D03*
X1147680Y327347D03*
X1154440Y335147D03*
X1144300Y340996D03*
Y337096D03*
X1140920Y339047D03*
Y331247D03*
X1154440Y323446D03*
Y315647D03*
X1147680Y319547D03*
X1157820Y325396D03*
X1154440Y339047D03*
Y331247D03*
X1127400Y319547D03*
Y315647D03*
X1100361Y350747D03*
X1113881D03*
Y358547D03*
X1117261Y348796D03*
X1100361Y358547D03*
X1103741Y348796D03*
Y352696D03*
X1110501D03*
X1107121Y346847D03*
Y354647D03*
Y358547D03*
Y362447D03*
X1103741Y372197D03*
X1110501Y364396D03*
X1103741D03*
X1113881Y366347D03*
X1117261Y372197D03*
Y368296D03*
X1110501Y372197D03*
X1096981Y368296D03*
Y372197D03*
X1100361Y366347D03*
X1113881Y401447D03*
X1110501Y391696D03*
Y395595D03*
X1107121Y389747D03*
X1100361Y385847D03*
X1107121D03*
X1100361Y393647D03*
X1103741Y391696D03*
X1100361Y397547D03*
X1113881Y385847D03*
Y397546D03*
Y393647D03*
X1103741Y379996D03*
X1113881Y378047D03*
X1117261Y376096D03*
X1110501Y379996D03*
X1107121Y381947D03*
X1096981Y376096D03*
X1100361Y378047D03*
X1151060Y368296D03*
X1147680Y366347D03*
X1120641Y350747D03*
Y358547D03*
Y366347D03*
X1127400Y362447D03*
X1124021Y348796D03*
Y352696D03*
X1127400Y354647D03*
Y358547D03*
X1130780Y360496D03*
X1127400Y342947D03*
X1134160Y346847D03*
Y362447D03*
Y366347D03*
Y370247D03*
X1147680Y342947D03*
X1151060Y356596D03*
Y360496D03*
X1144300D03*
X1137540D03*
X1144300Y356596D03*
X1140920Y358547D03*
X1147680Y346847D03*
Y350747D03*
X1151060Y352696D03*
Y348796D03*
X1147680Y358547D03*
X1157820Y360496D03*
X1154440Y358547D03*
Y342947D03*
Y354647D03*
X1157820Y352696D03*
X1147680Y354647D03*
X1144300Y348796D03*
X1140920Y346847D03*
Y350747D03*
X1144300Y344896D03*
X1151060D03*
X1154440Y346847D03*
X1140920Y362447D03*
X1154440Y366347D03*
X1144300Y372197D03*
X1137540D03*
Y368296D03*
X1140920Y366347D03*
Y370247D03*
X1151060Y364396D03*
X1144300D03*
X1137540D03*
X1147680Y362447D03*
X1130780Y352696D03*
Y344896D03*
X1124021Y372197D03*
X1130780D03*
X1124021Y364396D03*
X1137540Y403396D03*
Y399496D03*
X1124021Y391696D03*
X1130780Y395596D03*
X1127400Y385847D03*
Y389747D03*
X1130780Y391696D03*
X1124021Y379996D03*
X1127400Y381947D03*
X1130780Y379996D03*
X1137540Y395597D03*
X1140920Y397546D03*
X1137540Y376096D03*
X1157820Y387796D03*
X1140920Y378047D03*
Y381947D03*
X1147680Y393647D03*
X1120641Y385847D03*
Y393647D03*
Y378047D03*
Y401447D03*
X1140920Y374146D03*
X1151060Y395597D03*
Y391696D03*
X1147680Y385847D03*
Y397546D03*
X1151060Y379996D03*
X1154440Y378047D03*
Y381947D03*
X1140920Y389747D03*
X1134160Y393647D03*
Y385847D03*
Y378047D03*
X1140920Y385847D03*
X1144300Y391696D03*
X1117261Y407296D03*
X1113881Y405347D03*
X1096699Y407782D03*
X1134160Y405347D03*
X1119440Y518114D03*
X1114316Y517900D03*
X1114340Y510098D03*
X1110520Y515714D03*
X1104177D03*
X1101181Y510114D03*
X1098300Y515300D03*
X1107724Y510114D03*
X1137992Y495887D03*
X1144385D03*
X1140988Y493744D03*
X1156252Y490867D03*
X1147331Y493494D03*
X1151168Y490867D03*
X1127952Y515814D03*
X1124606Y510114D03*
X1131299D03*
X1156252Y518114D03*
X1147331Y515814D03*
X1151128Y517900D03*
X1156252Y498867D03*
X1151168D03*
X1151152Y510098D03*
X1134645Y515814D03*
X1137992Y510114D03*
X1140988Y515714D03*
X1144535Y510114D03*
X1156228Y510100D03*
X1104141Y530949D03*
X1098040Y536723D03*
X1098160Y533809D03*
X1119416Y547900D03*
X1119466Y536750D03*
X1119453Y528936D03*
X1098300Y553100D03*
X1114340Y547898D03*
X1107724Y547914D03*
X1101181D03*
X1110520Y553514D03*
X1104177D03*
X1098118Y549843D03*
X1098018Y531156D03*
X1114366Y529150D03*
X1114340Y536999D03*
X1110520Y531100D03*
X1107874Y537049D03*
X1101181Y536999D03*
X1119440Y555914D03*
X1114316Y555700D03*
X1119416Y585700D03*
X1119466Y574550D03*
X1119453Y566736D03*
X1104141Y568749D03*
X1097899Y574773D03*
X1101181Y585714D03*
X1097834Y569200D03*
X1107724Y585714D03*
X1107874Y574849D03*
X1110520Y568900D03*
X1101181Y574799D03*
X1114340D03*
Y585698D03*
X1114366Y566950D03*
X1140988Y553514D03*
X1151152Y547898D03*
X1156228Y547900D03*
X1137992Y547914D03*
X1144535D03*
X1127952Y553614D03*
X1131299Y547914D03*
X1124606D03*
X1131299Y537049D03*
X1124606D03*
X1127952Y530949D03*
X1151178Y529150D03*
X1151152Y536999D03*
X1147331Y531100D03*
X1156278Y536750D03*
X1156265Y528936D03*
X1134645Y530949D03*
X1140952D03*
X1137992Y536999D03*
X1144685Y537049D03*
X1147331Y553614D03*
X1134645D03*
X1156252Y555914D03*
X1151128Y555700D03*
X1156265Y566736D03*
X1151178Y566950D03*
X1134645Y568749D03*
X1137992Y585714D03*
X1144535D03*
X1140952Y568749D03*
X1137992Y574799D03*
X1144685Y574849D03*
X1151152Y585698D03*
Y574799D03*
X1147331Y568900D03*
X1156228Y585700D03*
X1156278Y574550D03*
X1131299Y585714D03*
X1124606D03*
X1131299Y574849D03*
X1127952Y568749D03*
X1124606Y574849D03*
X1137992Y612599D03*
X1144685Y612649D03*
X1151152Y612599D03*
X1124606Y612649D03*
X1131299D03*
X1114340Y612599D03*
X1107874Y612649D03*
X1101181Y612599D03*
X1097352Y607220D03*
X1110520Y606700D03*
X1119453Y604536D03*
X1119466Y612350D03*
X1119440Y593714D03*
X1104177Y591314D03*
X1110520D03*
X1114316Y593500D03*
X1098300Y590900D03*
X1114366Y604750D03*
X1104141Y606549D03*
X1156265Y604536D03*
X1147331Y606700D03*
X1134645Y606549D03*
X1140952D03*
X1156278Y612350D03*
X1134645Y591414D03*
X1140988Y591314D03*
X1151128Y593500D03*
X1147331Y591414D03*
X1156252Y593714D03*
X1151178Y604750D03*
X1127952Y606549D03*
Y591414D03*
X1161417Y9114D03*
X1168110D03*
X1174803D03*
X1171456Y-7851D03*
X1164763D03*
X1177763D03*
X1168110Y-1751D03*
X1161417D03*
X1174803Y-1801D03*
X1171456Y14814D03*
X1164763Y29949D03*
X1171456D03*
X1164763Y14814D03*
X1177799Y14714D03*
X1177763Y29949D03*
X1181496Y-1751D03*
X1181346Y9114D03*
X1187963Y9098D03*
X1204921Y9114D03*
X1198228D03*
X1188011Y-9700D03*
X1193076Y-9864D03*
X1184142Y-7700D03*
X1193111Y-2000D03*
X1187963Y-1801D03*
X1201574Y-7851D03*
X1204921Y-1751D03*
X1198228D03*
X1218307D03*
X1211614Y-1801D03*
X1214574Y-7851D03*
X1208267D03*
X1218157Y9114D03*
X1211614D03*
X1193023Y9300D03*
X1184142Y30100D03*
Y14814D03*
X1188023Y28100D03*
X1187923Y16900D03*
X1193063Y17114D03*
X1193076Y27936D03*
X1201574Y14814D03*
Y29949D03*
X1208267Y14814D03*
Y29949D03*
X1214600Y14714D03*
X1214574Y29949D03*
X1161417Y36049D03*
X1164763Y52614D03*
X1168110Y36049D03*
Y46914D03*
X1161417D03*
X1174803D03*
X1171456Y52614D03*
X1174803Y35999D03*
X1177763Y67749D03*
X1171456D03*
X1164763D03*
X1177799Y90314D03*
X1174803Y84714D03*
X1168110D03*
Y73849D03*
X1161417D03*
X1174803Y73799D03*
X1161417Y84714D03*
X1164763Y90414D03*
X1171456D03*
X1181346Y46914D03*
X1181496Y36049D03*
X1184142Y52614D03*
X1193012Y47000D03*
X1187963Y46898D03*
Y35999D03*
X1187912Y54700D03*
X1187989Y65950D03*
X1193076Y65736D03*
X1193063Y54914D03*
X1193023Y35800D03*
X1204921Y36049D03*
X1198228D03*
Y46914D03*
X1204921D03*
X1201574Y52614D03*
X1184142Y67900D03*
X1201574Y67749D03*
X1218307Y36049D03*
X1211614Y35999D03*
X1214960Y52864D03*
X1211614Y46914D03*
X1218157D03*
X1208267Y52614D03*
X1211614Y73799D03*
X1218307Y73849D03*
X1208267Y90414D03*
X1218157Y84714D03*
X1211614D03*
X1214574Y67749D03*
X1208267D03*
X1181346Y84714D03*
X1181496Y73849D03*
X1184142Y90414D03*
X1193039Y84700D03*
X1193063Y92714D03*
X1187939Y92500D03*
X1187963Y84698D03*
Y73799D03*
X1193089Y73550D03*
X1198228Y73849D03*
X1204921D03*
X1198228Y84714D03*
X1204921D03*
X1201574Y90414D03*
X1177799Y109914D03*
X1161632Y104314D03*
X1170721Y109564D03*
X1164428D03*
X1168075Y104314D03*
X1174742D03*
X1208267Y110014D03*
X1181346Y104314D03*
X1187963Y113114D03*
X1193089Y112865D03*
X1184142Y109564D03*
X1193076Y105051D03*
X1187989Y105265D03*
X1201574Y110014D03*
X1198228Y104314D03*
X1204921D03*
X1161200Y206446D03*
X1167960Y206447D03*
Y218147D03*
X1171339Y208397D03*
X1174719Y218147D03*
Y206447D03*
X1178099Y208397D03*
Y216196D03*
X1161200Y210346D03*
Y218147D03*
X1181479Y206447D03*
X1188239Y210346D03*
Y206447D03*
X1201759Y218147D03*
X1205759Y206682D03*
X1197492Y201356D03*
X1198379Y212296D03*
X1194999Y210346D03*
X1184859Y204496D03*
X1188239Y214247D03*
X1164580Y235696D03*
X1167960Y229847D03*
X1164580Y223996D03*
Y227896D03*
Y239596D03*
X1178099Y247396D03*
X1161200Y241547D03*
X1164580Y247396D03*
X1161200Y249347D03*
X1171339Y247396D03*
X1178099Y243496D03*
X1171339Y235696D03*
Y220096D03*
Y231797D03*
X1178099Y227896D03*
Y235696D03*
Y220096D03*
X1174719Y237647D03*
X1167960Y253247D03*
X1174719D03*
X1164580Y270796D03*
X1171339Y274696D03*
X1174719Y280547D03*
X1171339Y266896D03*
X1164580Y278596D03*
X1159578Y265117D03*
X1171339Y259096D03*
X1178099Y274696D03*
X1181479Y222047D03*
X1188239D03*
X1191619Y239596D03*
X1188239Y225947D03*
X1184859Y235696D03*
X1188239Y237647D03*
X1184859Y247396D03*
X1188239Y249347D03*
X1201759Y229847D03*
Y225947D03*
Y233746D03*
X1198379Y235696D03*
Y243496D03*
X1201759Y241547D03*
Y249347D03*
X1198379Y239596D03*
X1194999Y225947D03*
Y222047D03*
Y233746D03*
X1184859Y239596D03*
Y251296D03*
X1212199D03*
Y243496D03*
X1208519Y233746D03*
X1215700Y223600D03*
X1194999Y264947D03*
Y268847D03*
Y272747D03*
Y280547D03*
X1188239Y257147D03*
X1208519Y272747D03*
X1208819Y280547D03*
X1181479Y261047D03*
Y268847D03*
Y276646D03*
X1212199Y274696D03*
X1217200Y270500D03*
X1213808Y264800D03*
X1208519Y264947D03*
X1184859Y259096D03*
X1191619Y274696D03*
X1205139D03*
X1198379Y278596D03*
X1201759Y261047D03*
X1198379Y255196D03*
X1201759Y257147D03*
X1174719Y300047D03*
Y284447D03*
X1164580Y294196D03*
Y290296D03*
Y286396D03*
X1161200Y284447D03*
X1178099Y294196D03*
Y298096D03*
Y286396D03*
X1164580Y301996D03*
X1171339D03*
X1161200Y307847D03*
Y335147D03*
Y339047D03*
X1164580Y329296D03*
Y333196D03*
Y337096D03*
X1167960Y339047D03*
Y327347D03*
X1161200Y331247D03*
Y327347D03*
X1178099Y337096D03*
Y317596D03*
X1164580Y321496D03*
Y317596D03*
X1161200Y323446D03*
Y319547D03*
Y315647D03*
X1167960Y323446D03*
Y315647D03*
Y319547D03*
X1174719Y315647D03*
X1171339Y317596D03*
X1164580Y325396D03*
X1171339D03*
X1174719Y335147D03*
X1205500Y309797D03*
X1198379D03*
X1194999Y288347D03*
Y292247D03*
Y296147D03*
Y300047D03*
Y307847D03*
Y303947D03*
X1191619Y298096D03*
X1181479Y300047D03*
Y288347D03*
Y292247D03*
Y311747D03*
Y307847D03*
Y303947D03*
X1188239Y288347D03*
Y284447D03*
Y292247D03*
X1184859Y294196D03*
Y290296D03*
X1191619Y294196D03*
X1184859Y309797D03*
X1188239Y311747D03*
X1184859Y301996D03*
X1201759Y284447D03*
Y288347D03*
X1205439Y298096D03*
X1198379Y286396D03*
X1205439Y305896D03*
X1194999Y335147D03*
Y331247D03*
X1212200Y333196D03*
X1208519Y339047D03*
X1208826Y319544D03*
X1181479Y327347D03*
Y319547D03*
Y335147D03*
X1198379Y313696D03*
X1188239Y319547D03*
X1184859Y321496D03*
X1188239Y339047D03*
Y335147D03*
X1184859Y329296D03*
X1191619Y321496D03*
X1198379Y325396D03*
Y340996D03*
X1201759Y323446D03*
X1205139Y333196D03*
X1194999Y319547D03*
Y315647D03*
X1167960Y370247D03*
X1164580Y372197D03*
X1171339Y356596D03*
Y360496D03*
X1164580Y356596D03*
X1167960Y342947D03*
X1171339Y348796D03*
X1174719Y354647D03*
Y342947D03*
X1161200Y370247D03*
X1171339Y372197D03*
X1167960Y362447D03*
X1178099Y364396D03*
X1171339Y399496D03*
X1164580Y403396D03*
X1178099D03*
X1167960Y389747D03*
X1161200Y397546D03*
X1167960Y397547D03*
X1174719Y393647D03*
X1161200Y378047D03*
X1164580Y379996D03*
X1174719Y381947D03*
X1194999Y346847D03*
Y354647D03*
X1209219Y370247D03*
X1212199Y356597D03*
Y344896D03*
Y352696D03*
X1181479Y346847D03*
X1188239Y366347D03*
X1194999D03*
X1191619Y348796D03*
X1184859Y356596D03*
X1191619Y360496D03*
X1201759Y350747D03*
X1205139Y360496D03*
X1181479Y374146D03*
Y389747D03*
X1209769Y374146D03*
X1184859Y383896D03*
X1188239Y393647D03*
X1201759Y389747D03*
X1197258Y397546D03*
X1194999Y385847D03*
X1188239Y378047D03*
X1201759D03*
X1208819Y393647D03*
Y381897D03*
X1195555Y405773D03*
X1192200Y409550D03*
X1185989Y407800D03*
X1180400Y495787D03*
X1167500Y495800D03*
X1174203Y495787D03*
X1161320Y495800D03*
X1170656Y491144D03*
X1164363Y491044D03*
X1177849Y490944D03*
X1168110Y510114D03*
X1164763Y515814D03*
X1161417Y510114D03*
X1177799Y515714D03*
X1171456Y515814D03*
X1174803Y510114D03*
X1208267Y493444D03*
X1200974Y490744D03*
X1193063Y490909D03*
X1187978Y490609D03*
X1184142Y490794D03*
X1181346Y510114D03*
X1204400Y495887D03*
X1198100Y495800D03*
X1208267Y515814D03*
X1211614Y510114D03*
X1218157D03*
X1187963Y510098D03*
X1204921Y510114D03*
X1198228D03*
X1201574Y515814D03*
X1184142D03*
X1187939Y517900D03*
X1193039Y510100D03*
X1193063Y518114D03*
X1187978Y498609D03*
X1193063Y498909D03*
X1161417Y547914D03*
X1168110D03*
X1174803D03*
X1177799Y553514D03*
X1177763Y530949D03*
X1168110Y537049D03*
X1164763Y530949D03*
X1161417Y537049D03*
X1171456Y530949D03*
X1174803Y536999D03*
X1164763Y553614D03*
X1171456D03*
X1174803Y574799D03*
X1161417Y574849D03*
X1171456Y568749D03*
X1168110Y585714D03*
X1161417D03*
X1168110Y574849D03*
X1164763Y568749D03*
X1174803Y585714D03*
X1177763Y568749D03*
X1181496Y537049D03*
X1181346Y547914D03*
X1211614Y536999D03*
X1214574Y530949D03*
X1184142Y531100D03*
X1193076Y528936D03*
X1198228Y547914D03*
X1204921D03*
X1201574Y553614D03*
Y530949D03*
X1204921Y537049D03*
X1198228D03*
X1193039Y547900D03*
X1187963Y547898D03*
X1184142Y553614D03*
X1193089Y536750D03*
X1187989Y529150D03*
X1187963Y536999D03*
X1218307Y537049D03*
X1211614Y547914D03*
X1208267Y553614D03*
Y530949D03*
X1218157Y547914D03*
X1181346Y585714D03*
X1181496Y574849D03*
X1193063Y555914D03*
X1187939Y555700D03*
X1218157Y585714D03*
X1218307Y574849D03*
X1208267Y568749D03*
X1214574D03*
X1211614Y574799D03*
Y585714D03*
X1184142Y568900D03*
X1187989Y566950D03*
X1193076Y566736D03*
X1193039Y585700D03*
X1187963Y585698D03*
X1193089Y574550D03*
X1187963Y574799D03*
X1198228Y585714D03*
Y574849D03*
X1204921Y585714D03*
Y574849D03*
X1201574Y568749D03*
X1181496Y612649D03*
X1218307D03*
X1211614Y612599D03*
X1187963D03*
X1204921Y612649D03*
X1198228D03*
X1168110D03*
X1161417D03*
X1174803Y612599D03*
X1171456Y606549D03*
X1164763D03*
Y591414D03*
X1171456D03*
X1177799Y591314D03*
X1177763Y606549D03*
X1208267Y591414D03*
X1214574Y606549D03*
X1208267D03*
X1187939Y593500D03*
X1184142Y591414D03*
X1193063Y593714D03*
X1187989Y604750D03*
X1193076Y604536D03*
X1193089Y612350D03*
X1184142Y606700D03*
X1201574Y591414D03*
Y606549D03*
X1238385Y29949D03*
Y14814D03*
X1245078Y29949D03*
Y14814D03*
X1251771Y16999D03*
X1248425Y27899D03*
X1269700Y13078D03*
X1267960Y28494D03*
X1241732Y-1751D03*
X1238385Y-7851D03*
X1241732Y9114D03*
X1248425Y-1751D03*
Y-9901D03*
X1251771D03*
X1245078Y-7851D03*
X1248425Y9157D03*
X1269800Y-5822D03*
X1235039Y9114D03*
X1224774Y9098D03*
X1224822Y-9700D03*
X1229887Y-9864D03*
X1224774Y-1801D03*
X1235039Y-1751D03*
X1229922Y-2000D03*
X1220953Y-7700D03*
X1229800Y9300D03*
X1224790Y16900D03*
X1229874Y17114D03*
X1229887Y27936D03*
X1220953Y30100D03*
X1224800Y28100D03*
X1220953Y14814D03*
X1241732Y36049D03*
Y46914D03*
X1238385Y52614D03*
Y67749D03*
X1245078Y52614D03*
X1251771Y65699D03*
X1248425D03*
Y36049D03*
Y46957D03*
X1245078Y67749D03*
X1267976Y73676D03*
X1268022Y54443D03*
X1241732Y84714D03*
Y73849D03*
X1238385Y90414D03*
X1251771Y92599D03*
X1245078Y90414D03*
X1248425Y84757D03*
Y73849D03*
X1268581Y92706D03*
X1224774Y84698D03*
X1224750Y92500D03*
X1224774Y73799D03*
X1235039Y84714D03*
Y73849D03*
X1229800Y35750D03*
X1229874Y54914D03*
X1235039Y46914D03*
Y36049D03*
X1224774Y46898D03*
X1220953Y52614D03*
X1224774Y35999D03*
X1229887Y65736D03*
X1224800Y65950D03*
X1220953Y67900D03*
X1229900Y73550D03*
X1229850Y84700D03*
X1229874Y92714D03*
X1220953Y90414D03*
X1240927Y154932D03*
X1266200Y122500D03*
X1254024Y128013D03*
X1246251Y130066D03*
X1257800Y110900D03*
X1260500Y117500D03*
X1247326Y122802D03*
X1254300Y105200D03*
X1277660Y109450D03*
X1277230Y117570D03*
X1237400Y103100D03*
X1241712Y187710D03*
X1220167Y194407D03*
X1220017Y220323D03*
X1220194Y243384D03*
X1223100Y258600D03*
X1223508Y262600D03*
X1259800Y463300D03*
X1255530Y474770D03*
X1269050Y486650D03*
X1269600Y480800D03*
X1272830Y471660D03*
X1257720Y493060D03*
X1255388Y483557D03*
X1256130Y467820D03*
X1241732Y510114D03*
X1238385Y515814D03*
X1269000Y514700D03*
X1245078Y515814D03*
X1251771Y517999D03*
X1248425Y510157D03*
X1235039Y510114D03*
X1220953Y515814D03*
X1229874Y518114D03*
X1229850Y510100D03*
X1224750Y517900D03*
X1224774Y510098D03*
X1241732Y547914D03*
Y537049D03*
X1238385Y530949D03*
Y553614D03*
X1269800Y532978D03*
X1251771Y528899D03*
X1248425Y537049D03*
Y528899D03*
X1245078Y553614D03*
Y530949D03*
X1248425Y547957D03*
X1241732Y574849D03*
Y585714D03*
X1238385Y568749D03*
X1268500Y555800D03*
X1267900Y574300D03*
X1248425Y585757D03*
Y574849D03*
Y566699D03*
X1245078Y568749D03*
X1220953Y531100D03*
X1229887Y528936D03*
X1229900Y536750D03*
X1224800Y529150D03*
X1224774Y536999D03*
X1235039Y537049D03*
Y547914D03*
X1229850Y547900D03*
X1224774Y547898D03*
X1220953Y553614D03*
X1229874Y555914D03*
X1224750Y555700D03*
X1220953Y568900D03*
X1229900Y574550D03*
X1224774Y574799D03*
X1229850Y585700D03*
X1224774Y585698D03*
X1229887Y566736D03*
X1224800Y566950D03*
X1235039Y585714D03*
Y574849D03*
X1241732Y612649D03*
X1238385Y606549D03*
Y591414D03*
X1263800Y606800D03*
X1267800Y593600D03*
X1248425Y612649D03*
X1251771Y604499D03*
X1248425D03*
X1245078Y606549D03*
X1251771Y593599D03*
X1245078Y591414D03*
X1224774Y612599D03*
X1235039Y612649D03*
X1220953Y591414D03*
X1229874Y593714D03*
X1224750Y593500D03*
X1224800Y604750D03*
X1229887Y604536D03*
X1220953Y606700D03*
X1229900Y612350D03*
X1304940Y32350D03*
X1296928Y48700D03*
X1301000Y62000D03*
X1323500Y68000D03*
X1318341Y60000D03*
X1321841Y63000D03*
X1304000Y62000D03*
X1318341Y63000D03*
X1341400Y46100D03*
X1336900Y89896D03*
X1323500Y75000D03*
Y71500D03*
X1286000Y134500D03*
Y139500D03*
Y137000D03*
X1298400Y144500D03*
X1288500Y137000D03*
Y139500D03*
Y134500D03*
X1286000Y132000D03*
X1288500D03*
X1322628Y100134D03*
X1323800Y104250D03*
X1326800D03*
Y107250D03*
X1323800D03*
X1326600Y123450D03*
X1323600D03*
X1326600Y126450D03*
X1323600D03*
X1340100Y145000D03*
X1335100Y155000D03*
Y145000D03*
X1330100Y150000D03*
X1340100D03*
Y155000D03*
X1315100Y145000D03*
X1335100Y150000D03*
X1330100Y145000D03*
Y155000D03*
Y160000D03*
X1340100D03*
X1306363Y169928D03*
X1335100Y160000D03*
X1324938Y209251D03*
X1322500D03*
X1320390Y216824D03*
X1303838Y169922D03*
X1320400Y234959D03*
X1325900D03*
X1314900D03*
X1336900D03*
X1331400D03*
X1342400D03*
X1334113Y273115D03*
X1340866Y268795D03*
X1327625Y275971D03*
X1336480Y309755D03*
X1336793Y303784D03*
X1342500Y312100D03*
X1316300Y282000D03*
X1325300Y282600D03*
X1341920Y309755D03*
X1342480Y303852D03*
X1319906Y338025D03*
X1338500Y319600D03*
X1326626Y464400D03*
X1300100Y442500D03*
X1301000Y460900D03*
X1305100Y432500D03*
X1320100Y427500D03*
Y432500D03*
X1325100Y427500D03*
Y432500D03*
X1305181Y427834D03*
X1310100Y427500D03*
Y432500D03*
X1315100Y427500D03*
Y432500D03*
X1340100Y427500D03*
X1330100Y432500D03*
Y427500D03*
X1335100Y457500D03*
Y452500D03*
Y447500D03*
Y442500D03*
X1330100D03*
X1305100D03*
X1310100D03*
X1320100D03*
X1315100D03*
X1325100D03*
X1340100Y457500D03*
Y452500D03*
Y447500D03*
Y442500D03*
X1319738Y477497D03*
X1326877Y469279D03*
X1319699Y472327D03*
X1301000Y466500D03*
X1319300Y525450D03*
X1321800D03*
X1311772Y501000D03*
X1319075D03*
X1316675Y500983D03*
X1314272Y501000D03*
X1343100Y566300D03*
X1340700D03*
X1338000D03*
X1340526Y563337D03*
X1343026D03*
X1338026D03*
X1333026D03*
X1335526D03*
Y566237D03*
X1321800Y532750D03*
X1319300Y532650D03*
X1321800Y527850D03*
X1319300D03*
Y530250D03*
X1321800D03*
X1333026Y566237D03*
X1298100Y598300D03*
Y595800D03*
Y590000D03*
Y592500D03*
X1307600Y620100D03*
X1357400Y-19800D03*
X1360400Y10600D03*
X1350654Y-18411D03*
X1348154Y-15911D03*
Y-18411D03*
X1357600Y5140D03*
X1345518Y-18476D03*
X1353154Y-18411D03*
X1375676Y7630D03*
X1385608Y-17485D03*
X1388294Y-5675D03*
X1389523Y4966D03*
X1355950Y-16507D03*
X1359450Y-7D03*
X1355950D03*
X1357489Y-1924D03*
X1359450Y2493D03*
X1355950D03*
X1357489Y-14424D03*
Y-10524D03*
Y-6124D03*
X1355889Y-8524D03*
X1355847Y-12275D03*
X1355989Y-3924D03*
X1356261Y32017D03*
X1356300Y20100D03*
X1356376Y24167D03*
X1356200Y28200D03*
X1357900Y30200D03*
X1357800Y26100D03*
X1357803Y22200D03*
X1356261Y15517D03*
X1357700Y17800D03*
X1359761Y32317D03*
X1371650Y-907D03*
X1371589Y-3424D03*
Y-5924D03*
X1371900Y28600D03*
Y26100D03*
Y31100D03*
X1369408Y50479D03*
X1375500Y76000D03*
X1397500Y51000D03*
X1365855Y46972D03*
X1359800Y37300D03*
X1357300D03*
X1344000Y83000D03*
X1402700Y51100D03*
X1381817Y46484D03*
X1388627Y35032D03*
X1380500Y54500D03*
X1380900Y59820D03*
X1372400Y37785D03*
X1389138Y58499D03*
X1370100Y82500D03*
X1366100D03*
X1364700Y86550D03*
X1389068Y78556D03*
X1389100Y74600D03*
X1350830Y60730D03*
X1356261Y34517D03*
X1356950Y54370D03*
X1356760Y66660D03*
X1357000Y60500D03*
X1359761Y34817D03*
X1350800Y66600D03*
X1351190Y54710D03*
X1363170Y54280D03*
X1362900Y60500D03*
X1363040Y66660D03*
X1380500Y50500D03*
X1356230Y126500D03*
X1359230D03*
X1360730Y129000D03*
X1362230Y126500D03*
X1355100Y155000D03*
Y145000D03*
Y150000D03*
X1360100Y155000D03*
Y145000D03*
Y150000D03*
X1345100D03*
X1350100Y155000D03*
Y150000D03*
Y145000D03*
X1345100D03*
Y155000D03*
X1397994Y103350D03*
X1397952Y105998D03*
X1395326Y100913D03*
Y103413D03*
X1395347Y106040D03*
X1386700Y125450D03*
Y128450D03*
X1383700Y125450D03*
Y128450D03*
X1380700Y125450D03*
Y128450D03*
X1376100Y116100D03*
X1376669Y121763D03*
Y118763D03*
X1376100Y124950D03*
X1373850Y114450D03*
X1369730Y129000D03*
X1363730D03*
X1366730D03*
X1373850Y117450D03*
X1368230Y126500D03*
X1373850Y123450D03*
X1365230Y126500D03*
X1397193Y112602D03*
X1394253Y116989D03*
X1385100Y155000D03*
X1375100D03*
X1365100D03*
X1380100D03*
Y145000D03*
X1385100D03*
X1380100Y150000D03*
X1385100D03*
X1365100Y145000D03*
Y150000D03*
X1375100D03*
X1370100Y155000D03*
Y145000D03*
X1375100D03*
X1370100Y150000D03*
X1352200Y104950D03*
Y108400D03*
X1357700D03*
Y104950D03*
X1373850Y120450D03*
X1380100Y160000D03*
X1360100D03*
X1355100D03*
X1345100D03*
X1350100D03*
X1390100D03*
X1370100D03*
X1390100Y170000D03*
X1385100Y160000D03*
Y165000D03*
Y170000D03*
X1365100Y160000D03*
X1375100D03*
X1390100Y165000D03*
X1383753Y265548D03*
X1397400Y234959D03*
X1391900D03*
X1386400D03*
X1358900D03*
X1353400D03*
X1347900D03*
X1349500Y265500D03*
X1359100Y265600D03*
X1380900Y234959D03*
X1369900D03*
X1364400D03*
X1375400Y235100D03*
X1369100Y265500D03*
X1374864Y265629D03*
X1398062Y315743D03*
X1403100Y321350D03*
X1383639Y315274D03*
X1389600Y315200D03*
X1384024Y320225D03*
X1386048Y310310D03*
X1386265Y304310D03*
X1389600Y320100D03*
X1397640Y310631D03*
X1397880Y304640D03*
X1392380D03*
X1392340Y310625D03*
X1403260Y310623D03*
X1403300Y304640D03*
X1388208Y341489D03*
X1348080Y309825D03*
X1353142Y309761D03*
X1358792Y309760D03*
X1358800Y303700D03*
X1353359Y303767D03*
X1348190Y303810D03*
X1346550Y322350D03*
X1350650Y315050D03*
X1357452Y319395D03*
X1369540Y310125D03*
X1374900Y310130D03*
X1381100Y304360D03*
X1380910Y310300D03*
X1364044Y309691D03*
X1364213Y303694D03*
X1375040Y304135D03*
X1369540D03*
X1371000Y322400D03*
X1363059Y314514D03*
X1368947Y313993D03*
X1358500Y338400D03*
X1370200D03*
X1364300Y338300D03*
X1392144Y364617D03*
X1389450Y372250D03*
X1384700Y359700D03*
X1392500Y344600D03*
X1392805Y360466D03*
X1388500Y350864D03*
X1391200Y386300D03*
X1384531Y382957D03*
X1394760Y394720D03*
X1362510Y360717D03*
X1354024Y398985D03*
X1352338Y404153D03*
X1351379Y399227D03*
X1352239Y401593D03*
X1358512Y371792D03*
X1360450Y402100D03*
X1359360Y398810D03*
X1357880Y403760D03*
X1356560Y398910D03*
X1362250Y399160D03*
X1354681Y401444D03*
X1354982Y404154D03*
X1357542Y401381D03*
X1364856Y366666D03*
X1382017Y367584D03*
X1363250Y401700D03*
X1371200Y402100D03*
X1381500Y396200D03*
X1375201Y396303D03*
X1365731Y360698D03*
X1358500Y374500D03*
X1360200Y377400D03*
X1358655Y379352D03*
X1362068Y393385D03*
X1360300Y381100D03*
X1360200Y384700D03*
Y389000D03*
X1358700Y386700D03*
X1358568Y390885D03*
Y393385D03*
X1358600Y382800D03*
X1362068Y390885D03*
X1374268Y389985D03*
X1374207Y384968D03*
Y387468D03*
X1370300Y350200D03*
X1358300Y344200D03*
X1358400Y350100D03*
X1370200Y343900D03*
X1364100Y350200D03*
X1385416Y410502D03*
X1404558Y416575D03*
X1402725Y408136D03*
X1402520Y413246D03*
X1388085Y410479D03*
X1403998Y429775D03*
X1404558Y421575D03*
X1398275Y453561D03*
X1397975Y457561D03*
X1403998Y434775D03*
X1382849Y410471D03*
X1380449Y410479D03*
X1358990Y411040D03*
X1358910Y408480D03*
X1358980Y406060D03*
X1355100Y427500D03*
Y432500D03*
X1361558Y410527D03*
X1345100Y442500D03*
X1350100D03*
X1345100Y437500D03*
X1350100D03*
X1355100D03*
Y442500D03*
X1369034Y458075D03*
X1369907Y410513D03*
X1372535Y410512D03*
X1375239Y410590D03*
X1377928Y410451D03*
X1366984Y410481D03*
X1364403Y410496D03*
X1380100Y447500D03*
X1370100Y442500D03*
X1365100Y452500D03*
X1379857Y458108D03*
X1365100Y442500D03*
X1375100D03*
X1380100Y452500D03*
X1365100Y447500D03*
X1388900Y525230D03*
X1395581Y525357D03*
X1383600Y482504D03*
X1386041Y493723D03*
X1383519Y487445D03*
X1390330Y516690D03*
X1385033Y516848D03*
X1387568Y516892D03*
X1388865Y519788D03*
X1388850Y522266D03*
X1386033Y498811D03*
X1344073Y508263D03*
X1363800Y481600D03*
X1363662Y486636D03*
X1365741Y492723D03*
X1382578Y516805D03*
X1377492Y516892D03*
X1369757Y517465D03*
X1365719Y497545D03*
X1352490Y515470D03*
X1346870Y515450D03*
X1352590Y519170D03*
X1346970Y519150D03*
X1401777Y557632D03*
X1385033Y544267D03*
X1390623Y574986D03*
X1400830Y564090D03*
X1400288Y570099D03*
X1404420Y576330D03*
X1404519Y560280D03*
Y557380D03*
X1361600Y559400D03*
X1358529Y537492D03*
X1361163Y540052D03*
X1358518Y540073D03*
X1356018D03*
X1356029Y537492D03*
X1363674Y537471D03*
X1355548Y559959D03*
X1361926Y584037D03*
Y586537D03*
X1359100Y586200D03*
X1357400Y588400D03*
X1360100D03*
X1344613Y556376D03*
Y561376D03*
Y558876D03*
X1347700Y554100D03*
X1353520Y537480D03*
X1344613Y553876D03*
X1361174Y537471D03*
X1358439Y559959D03*
X1375479Y540117D03*
X1375500Y537717D03*
X1366265Y537437D03*
X1363663Y540052D03*
X1363568Y550589D03*
X1380521Y535276D03*
X1378021D03*
X1375621Y535254D03*
X1371265Y537437D03*
X1368765D03*
X1366459Y550589D03*
X1377979Y537717D03*
Y540117D03*
X1380479Y537717D03*
X1368596Y539889D03*
X1371096D03*
X1366096D03*
X1380479Y540117D03*
X1376800Y584328D03*
X1364426Y586637D03*
Y584137D03*
X1360500Y570900D03*
Y574700D03*
X1360261Y578873D03*
X1360247Y567390D03*
X1360261Y562373D03*
Y581373D03*
X1362000Y576700D03*
Y572800D03*
X1362100Y569100D03*
X1362000Y565600D03*
X1363761Y581373D03*
X1375961Y577973D03*
X1376000Y575456D03*
Y572956D03*
X1387050Y615350D03*
X1392500Y592000D03*
X1376556Y615756D03*
X1357726Y591037D03*
X1360226D03*
X1363761Y612573D03*
X1360261D03*
X1360200Y597800D03*
X1361600Y599900D03*
X1361500Y595700D03*
X1360100Y610100D03*
X1360200Y606300D03*
Y602000D03*
X1361900Y608200D03*
X1361500Y604200D03*
X1360261Y593573D03*
X1363761Y610073D03*
X1375961Y609173D03*
X1375900Y604156D03*
Y606656D03*
X1454715Y2784D03*
X1450508Y2756D03*
X1410571Y13170D03*
X1420019Y13466D03*
X1448367Y13533D03*
X1438918D03*
X1429469Y13466D03*
X1457814D03*
X1436131Y5248D03*
X1432661Y5220D03*
X1406674Y46120D03*
X1411254Y46018D03*
X1412250Y65359D03*
X1407150Y58859D03*
X1410150D03*
X1407150Y52859D03*
X1410150D03*
X1409250Y65359D03*
X1407150Y55859D03*
X1410150D03*
X1413721Y36749D03*
X1412250Y68359D03*
X1409250D03*
X1409150Y71259D03*
X1412150D03*
X1442067Y34830D03*
X1423170Y36635D03*
X1432619Y34830D03*
X1451516D03*
X1460965D03*
X1452648Y103788D03*
X1451273Y148905D03*
X1449847Y202322D03*
X1439000Y208500D03*
X1442251Y180818D03*
X1418300Y199900D03*
X1440150Y175550D03*
X1440124Y166180D03*
X1451427Y167818D03*
X1434800Y248900D03*
X1462700Y221700D03*
X1464200Y231400D03*
X1458800Y254882D03*
X1410800Y316100D03*
X1408580Y310632D03*
X1408760Y304637D03*
X1410550Y320800D03*
X1419343Y310652D03*
X1419283Y304570D03*
X1413983Y304645D03*
X1413943Y310628D03*
X1417656Y367547D03*
X1420101Y396236D03*
X1418138Y386361D03*
X1415000Y399000D03*
X1412220Y388360D03*
X1417217Y379129D03*
X1417349Y382137D03*
X1417773Y374107D03*
X1464124Y353776D03*
X1465500Y395400D03*
X1456750Y381850D03*
X1459033Y395334D03*
X1446700Y387900D03*
X1437897Y402315D03*
X1443100Y368950D03*
X1439934Y403730D03*
X1411900Y429775D03*
X1405375Y453561D03*
X1405608Y456761D03*
X1411900Y434775D03*
X1435479Y423107D03*
X1439350Y406900D03*
X1459200Y459800D03*
Y454100D03*
X1459000Y449997D03*
X1451400Y454100D03*
Y459800D03*
X1445000Y437000D03*
X1429000Y437059D03*
X1444800Y442500D03*
X1444500Y448000D03*
X1429100Y453400D03*
X1429000Y448000D03*
Y442600D03*
X1448800Y427800D03*
X1412447Y416368D03*
X1412545Y421974D03*
X1413300Y454400D03*
X1413075Y457561D03*
X1448800Y416500D03*
X1464300Y404900D03*
X1439000Y423000D03*
X1464600Y428000D03*
X1459300Y430000D03*
X1464525Y420014D03*
X1464731Y432942D03*
X1445100Y431500D03*
X1459200Y465500D03*
X1451400D03*
X1408753Y527518D03*
X1415541Y489523D03*
X1416100Y483500D03*
X1415800Y477500D03*
Y495200D03*
X1420200Y520500D03*
X1447749Y485395D03*
X1439314Y477723D03*
X1439400Y483600D03*
X1439341Y489323D03*
X1453700Y501600D03*
X1458357Y523271D03*
X1461100Y523600D03*
X1439400Y494700D03*
X1409693Y560343D03*
X1412093D03*
X1410850Y564210D03*
X1410340Y570370D03*
X1407019Y557380D03*
X1412019D03*
X1409519D03*
X1406993Y560343D03*
X1447852Y575687D03*
X1445800Y574300D03*
X1445750Y539000D03*
X1461500Y540000D03*
X1439861Y540497D03*
X1461653Y580762D03*
X1461707Y583162D03*
X1461878Y585556D03*
X1441805Y570887D03*
X1443797Y572482D03*
X1422500Y579800D03*
X1414800D03*
X1461930Y587956D03*
X1409500Y538000D03*
X1420500Y549800D03*
X1420400Y538000D03*
X1462039Y590354D03*
X1462155Y592761D03*
X1465334Y618564D03*
X1451314Y623298D03*
X1458000Y623400D03*
X1455000D03*
X1461000D03*
X1442200D03*
X1445200D03*
X1448200D03*
X1463419Y606912D03*
X1527700Y6963D03*
X1506900Y3500D03*
X1469807Y2967D03*
X1473674Y2953D03*
X1476712Y13466D03*
X1467264Y13533D03*
X1492900Y4000D03*
X1489600D03*
X1495611Y13466D03*
X1486162Y13500D03*
X1470414Y34830D03*
X1479863D03*
X1497711Y34427D03*
X1489311Y34830D03*
X1499613Y84046D03*
X1515294Y91306D03*
X1523563Y93565D03*
X1511700Y84600D03*
X1482300Y118400D03*
X1469747Y148276D03*
X1483093Y130796D03*
X1523950Y104050D03*
X1523889Y99033D03*
X1523557Y116165D03*
X1523813Y120546D03*
X1523756Y108762D03*
X1501603Y108500D03*
X1499618Y124520D03*
X1497699Y112140D03*
X1511634Y121195D03*
X1511635Y114535D03*
X1511650Y109400D03*
Y103400D03*
X1511651Y98675D03*
X1500775Y98101D03*
X1501700Y103300D03*
X1513023Y140630D03*
X1511664Y133603D03*
X1488350Y149450D03*
X1523719Y149488D03*
X1499800Y199300D03*
X1491196Y218527D03*
X1523400Y217900D03*
X1483523Y181100D03*
X1517328Y186208D03*
X1527500Y167726D03*
X1502192Y164871D03*
X1494783Y177907D03*
X1469150Y242931D03*
X1479500Y238500D03*
X1498685Y224715D03*
X1491700Y241661D03*
X1491407Y258353D03*
X1523470Y242580D03*
X1472500Y341074D03*
X1526722Y295400D03*
X1501583Y339389D03*
X1521817Y330937D03*
X1526000Y341000D03*
X1517600Y320940D03*
X1487426Y330100D03*
X1514722Y293257D03*
X1515482Y280800D03*
X1512300Y280847D03*
X1511900Y287500D03*
X1472550Y397500D03*
X1470800Y402250D03*
X1472680Y380630D03*
X1483172Y351806D03*
X1474500Y365500D03*
X1478500D03*
X1483500D03*
X1482000Y395098D03*
Y399035D03*
Y383287D03*
Y387224D03*
X1473255Y376254D03*
X1528146Y349842D03*
X1519626Y365817D03*
X1488394Y365466D03*
X1497275Y401174D03*
X1508975D03*
X1483950Y401650D03*
X1491425Y391034D03*
X1503125Y377514D03*
X1491425D03*
X1526525D03*
X1514825D03*
X1526525Y384274D03*
Y391034D03*
X1514825Y384274D03*
X1520675Y387654D03*
Y380894D03*
X1514825Y391034D03*
X1508975Y387654D03*
Y380894D03*
X1503125Y384274D03*
Y391034D03*
X1497275Y380894D03*
X1491425Y384274D03*
X1497275Y387654D03*
Y394414D03*
X1491425Y397794D03*
X1503125D03*
X1508975Y394414D03*
X1514825Y397794D03*
X1524575Y401174D03*
X1491425Y418074D03*
X1487525D03*
X1472449Y439421D03*
X1467000Y454100D03*
Y459800D03*
X1466800Y449997D03*
X1467401Y411557D03*
X1471900Y406900D03*
X1472530Y432731D03*
X1472400Y428063D03*
X1472800Y420689D03*
X1467000Y465500D03*
X1482000Y418720D03*
Y406909D03*
Y410846D03*
Y414783D03*
Y422658D03*
Y426595D03*
X1483400Y438100D03*
X1482603Y442418D03*
X1482000Y462028D03*
X1483115Y454379D03*
X1483200Y450455D03*
X1482500Y434600D03*
X1503125Y404554D03*
X1509200Y413600D03*
X1510925Y404554D03*
X1497275Y414694D03*
X1503125Y424834D03*
X1497275Y428214D03*
X1495325Y424834D03*
X1503125Y433406D03*
X1491425D03*
X1495325D03*
X1524950Y419900D03*
X1518650D03*
X1483818Y430597D03*
X1528100Y410550D03*
X1501219Y416596D03*
X1487525Y404554D03*
X1526525D03*
X1515500Y416750D03*
X1518700Y406500D03*
X1491425Y404554D03*
X1495325Y411314D03*
X1512350Y445100D03*
X1509200D03*
Y454550D03*
X1512400Y454500D03*
X1503125Y440166D03*
X1501175Y436786D03*
X1495325Y440166D03*
X1497275Y436786D03*
X1510925Y460446D03*
X1505442Y443900D03*
X1507025Y460446D03*
X1503125Y453786D03*
Y460446D03*
X1501175Y457066D03*
X1487525Y453686D03*
X1497275Y457066D03*
Y450306D03*
X1495325Y446926D03*
Y453686D03*
X1497275Y443546D03*
X1501175Y463826D03*
X1493375D03*
X1515500Y445100D03*
X1514825Y460446D03*
X1520675Y457066D03*
X1518725Y460446D03*
X1521800Y441950D03*
Y448250D03*
X1526525Y460446D03*
X1522625D03*
X1524950Y441950D03*
X1473140Y525407D03*
X1482000Y481713D03*
Y469902D03*
X1476800Y498900D03*
X1482300D03*
X1476800Y507300D03*
X1481700Y524200D03*
X1473800Y495800D03*
X1499225Y480726D03*
X1508975Y477346D03*
X1510925Y480726D03*
X1508975Y470586D03*
X1510925Y473966D03*
X1505075Y470586D03*
X1501175D03*
X1503125Y467206D03*
X1507025Y487486D03*
X1487525Y473966D03*
X1491425D03*
X1489475Y470586D03*
X1490100Y489700D03*
X1487525Y487486D03*
X1489475Y484106D03*
X1516775D03*
X1514825Y480726D03*
Y473966D03*
X1516775Y470586D03*
X1518725Y487486D03*
Y480726D03*
Y473966D03*
Y467206D03*
X1522625D03*
Y473966D03*
Y487486D03*
X1526525D03*
Y473966D03*
Y467206D03*
X1514825Y487486D03*
X1511752Y498780D03*
X1490929Y507104D03*
X1506060Y508180D03*
X1501490Y504988D03*
X1501934Y513047D03*
X1505743Y516117D03*
X1511215Y507781D03*
X1512400Y519020D03*
X1493930Y522800D03*
X1488410Y517810D03*
X1497267Y505323D03*
X1496174Y514221D03*
X1509000Y498750D03*
X1488500Y498900D03*
X1526500Y498671D03*
Y506400D03*
X1485300Y498962D03*
X1483804Y509928D03*
X1484200Y524200D03*
X1475316Y527194D03*
X1468101Y573963D03*
X1527698Y578870D03*
X1474776Y572315D03*
X1491776Y573571D03*
X1479893Y572315D03*
X1482293D03*
X1477493D03*
X1487093D03*
X1489493D03*
X1484693D03*
X1518000Y562330D03*
X1510740Y557860D03*
X1494422Y574000D03*
X1481400Y539700D03*
X1494200Y530600D03*
X1497106Y531368D03*
X1511388Y531045D03*
X1503200Y530500D03*
X1505600D03*
X1508772Y530416D03*
X1514118Y530411D03*
X1483900Y539700D03*
X1525500Y582674D03*
Y580184D03*
X1525837Y574700D03*
X1523416Y573949D03*
X1527822Y576130D03*
X1525500Y577684D03*
X1499900Y574000D03*
X1496900D03*
X1469701Y599554D03*
X1470353Y592128D03*
X1469767Y596353D03*
X1503008Y620018D03*
X1472412Y596032D03*
Y599532D03*
X1479029Y596132D03*
X1477129Y597656D03*
X1474912Y596032D03*
X1480760Y611602D03*
X1485429Y597571D03*
X1491412Y596032D03*
X1489229Y597571D03*
X1487329Y596032D03*
X1512500Y598639D03*
X1510450Y597300D03*
X1507950D03*
X1510450Y600800D03*
X1508031Y599922D03*
X1524800Y598778D03*
X1522900Y597300D03*
X1526950D03*
X1518800Y597200D03*
X1520813Y598508D03*
X1516800Y598639D03*
X1514500Y597300D03*
X1511350Y613000D03*
X1513867Y612939D03*
X1516367D03*
X1475812Y611732D03*
X1474912Y599532D03*
X1478329Y611671D03*
X1483104Y596072D03*
X1481229Y597571D03*
X1584447Y-6702D03*
X1579447D03*
X1570200Y12900D03*
X1579773Y13257D03*
X1589259Y10241D03*
X1541400Y12500D03*
X1528384Y28040D03*
X1551309Y12792D03*
X1560700Y13000D03*
X1589500Y-600D03*
X1589900Y84422D03*
X1583621Y87213D03*
X1588700Y94288D03*
X1573473Y37216D03*
X1582923D03*
X1532800Y78590D03*
X1542179Y39695D03*
X1554573Y37216D03*
X1564023D03*
X1578000Y113000D03*
X1585500Y101000D03*
X1555000Y139000D03*
X1548955Y101358D03*
X1558189Y107067D03*
X1554800Y129100D03*
Y98200D03*
X1558100D03*
X1558383Y121500D03*
X1554945Y133400D03*
X1583600Y207495D03*
X1535399Y190920D03*
X1533132Y158068D03*
X1531565Y176645D03*
X1537298Y162703D03*
X1557634Y175948D03*
X1562079Y163580D03*
X1530200Y257200D03*
X1528460Y244371D03*
X1563440Y250955D03*
X1559577Y236300D03*
X1547000Y263500D03*
Y269400D03*
X1541000Y263500D03*
Y269500D03*
X1544000Y266500D03*
X1578630Y293430D03*
X1580150Y329483D03*
X1528250Y311900D03*
X1530033Y340799D03*
X1539400Y320200D03*
X1544904Y334008D03*
X1557250Y315410D03*
X1554800Y290600D03*
X1586400Y392900D03*
X1567475Y380894D03*
Y387654D03*
X1582420Y377830D03*
X1582350Y374567D03*
X1582124Y381164D03*
X1573000Y391161D03*
X1571366Y401154D03*
X1582000Y396250D03*
X1567475Y394414D03*
X1570672Y362134D03*
X1567121Y365817D03*
X1576380Y362890D03*
X1582500Y369600D03*
X1573521Y365500D03*
X1532375Y380894D03*
Y387654D03*
Y394414D03*
X1538225Y377514D03*
Y384274D03*
X1544075Y380894D03*
Y387654D03*
X1538225Y391034D03*
Y397794D03*
X1544075Y394414D03*
X1558996Y365817D03*
X1555775Y394414D03*
X1549925Y397794D03*
X1561625D03*
X1555775Y401174D03*
X1549925Y377514D03*
X1561625D03*
Y391034D03*
Y384274D03*
X1549925Y391034D03*
Y384274D03*
X1555775Y387654D03*
Y380894D03*
X1571375Y421454D03*
X1569425Y418074D03*
X1571375Y414694D03*
X1559675Y463826D03*
X1563575Y421454D03*
X1557725Y424834D03*
X1567475Y450306D03*
X1565525Y440166D03*
X1571375Y457066D03*
X1567475D03*
X1569425Y460446D03*
X1582200Y456200D03*
X1565525Y431594D03*
X1569425D03*
Y404554D03*
X1583208Y412815D03*
X1569425Y411314D03*
X1571390Y464480D03*
X1567475Y421454D03*
X1531250Y419900D03*
Y451400D03*
Y441950D03*
X1530425Y460446D03*
X1551875Y407934D03*
Y414694D03*
X1563575Y407934D03*
X1559675Y414694D03*
X1546025Y404554D03*
X1561625Y424834D03*
X1551990Y421158D03*
X1551875Y428214D03*
X1561625Y431594D03*
X1563575Y428214D03*
X1555775Y443546D03*
Y436786D03*
X1563575Y457066D03*
X1549938Y453714D03*
X1547975Y457066D03*
X1549925Y446926D03*
X1557725D03*
X1561625Y460446D03*
X1555775Y457066D03*
X1551875D03*
X1557725Y453686D03*
X1559675Y443546D03*
Y436786D03*
X1547975Y463826D03*
X1551875D03*
X1555775D03*
X1534400Y419900D03*
X1540700D03*
X1543850Y429350D03*
Y426200D03*
X1537550Y419900D03*
X1534325Y404554D03*
X1538225D03*
X1542125D03*
X1540700Y410450D03*
X1534400Y451400D03*
Y441950D03*
X1537550D03*
X1534325Y460446D03*
X1537550Y451400D03*
X1544075Y457066D03*
X1540175D03*
X1540700Y451400D03*
Y441950D03*
X1540175Y463826D03*
X1543850Y435650D03*
X1537550D03*
X1582644Y495077D03*
X1568600Y494500D03*
X1565210Y509160D03*
X1567817Y499735D03*
X1569425Y473966D03*
X1571375Y470586D03*
X1565525Y480726D03*
X1570062Y487039D03*
X1587970Y472370D03*
X1587433Y490425D03*
X1567475Y470586D03*
X1532375D03*
X1530425Y473966D03*
X1528475Y470586D03*
Y477346D03*
X1534180Y498580D03*
X1534039Y502906D03*
X1531580Y510790D03*
X1534325Y487486D03*
X1536275Y484106D03*
X1544075Y470586D03*
X1542125Y473966D03*
X1540175Y477346D03*
X1536275Y470586D03*
X1544075Y477346D03*
X1538225Y473966D03*
X1542475Y504400D03*
X1542425Y512200D03*
X1546025Y467206D03*
X1553825Y487486D03*
Y480726D03*
X1557725D03*
X1549925Y473966D03*
X1547975Y470586D03*
X1553825Y473966D03*
Y467206D03*
X1555775Y470586D03*
X1557725Y473966D03*
X1555775Y477346D03*
Y484106D03*
X1549925Y487486D03*
X1546025Y480726D03*
X1548300Y499000D03*
X1564600Y500414D03*
X1555424Y504609D03*
X1555832Y512288D03*
X1548300Y506600D03*
X1580360Y565524D03*
X1580400Y568000D03*
X1580300Y563000D03*
Y560500D03*
X1566000Y575820D03*
X1565940Y573120D03*
X1565800Y570600D03*
X1565600Y568100D03*
Y565700D03*
X1529944Y574725D03*
X1529894Y577342D03*
X1532354Y577283D03*
X1532642Y579853D03*
X1529600Y582300D03*
X1532400D03*
X1529942Y579853D03*
X1563800Y564100D03*
X1561300Y564000D03*
X1558800Y563900D03*
X1563448Y566766D03*
X1563432Y569340D03*
X1589604Y585896D03*
X1581704D03*
X1587504Y605496D03*
Y607996D03*
X1563827Y621376D03*
X1554800Y620910D03*
X1537711Y613397D03*
X1538679Y615641D03*
X1534928Y610532D03*
X1538337Y601097D03*
X1534948Y613302D03*
X1545000Y591100D03*
X1581704Y590196D03*
X1589604D03*
X1558800Y599300D03*
X1560400Y611600D03*
X1564300Y599400D03*
X1564400Y605500D03*
X1561700Y602200D03*
X1552400Y607600D03*
X1554900Y607100D03*
X1556200Y602400D03*
X1554400Y599300D03*
X1564300Y611500D03*
X1602504Y-17346D03*
X1646200Y5300D03*
X1646400Y13400D03*
X1597700Y9000D03*
X1615000Y12000D03*
X1634200Y9700D03*
X1627500Y11700D03*
X1608123Y13302D03*
X1619100Y6500D03*
X1626400Y4600D03*
X1606700D03*
X1636500D03*
X1591270Y93940D03*
X1592200Y37700D03*
X1590464Y77962D03*
X1637700Y67400D03*
X1639623Y38100D03*
X1649073Y38200D03*
X1620050Y35550D03*
X1608500Y72688D03*
X1606730Y84230D03*
X1632000Y83000D03*
X1625451Y84288D03*
X1605184Y61044D03*
X1610450Y37300D03*
X1627380Y36652D03*
X1630121Y37609D03*
X1595943Y71522D03*
X1603138Y65890D03*
X1602840Y37382D03*
X1635900Y83000D03*
X1595335Y98135D03*
X1641600Y96500D03*
X1638500D03*
X1595522Y127278D03*
X1650300Y195251D03*
X1648400Y214100D03*
X1643887Y181841D03*
X1604401Y213500D03*
X1618500Y181680D03*
X1625524Y184531D03*
X1635100Y182800D03*
X1620036Y196186D03*
X1635112Y195181D03*
X1605250Y197250D03*
X1591174Y225017D03*
X1640871Y235210D03*
X1608489Y252095D03*
X1635503Y340146D03*
X1629503D03*
X1603307Y393224D03*
X1591912Y391052D03*
X1650624Y357884D03*
X1650480Y368215D03*
X1642126Y357894D03*
X1642114Y368142D03*
X1601060Y401010D03*
X1599100Y399100D03*
X1610828Y381387D03*
X1596151D03*
X1596168Y375135D03*
X1609761Y372584D03*
X1613474Y391105D03*
X1620447Y373926D03*
X1610642Y375135D03*
X1608020Y356500D03*
X1619889Y352841D03*
X1607443Y398649D03*
X1629503Y346146D03*
X1635503Y346046D03*
X1632503Y343146D03*
X1621010Y435870D03*
X1620500Y463727D03*
X1634500Y418500D03*
X1603650Y415469D03*
X1646540Y441240D03*
X1604200Y464387D03*
X1594880Y494880D03*
X1646700Y480300D03*
X1639394Y507798D03*
X1627032Y510226D03*
X1627068Y512626D03*
X1606200Y487100D03*
X1623814Y471400D03*
X1614000Y469500D03*
X1617700Y489700D03*
X1615200D03*
X1611506Y474768D03*
X1620500Y475000D03*
X1603500Y495300D03*
X1597178Y472226D03*
X1599900Y487100D03*
X1603802Y487205D03*
X1629530Y496374D03*
X1644800Y532800D03*
X1636848Y533794D03*
X1649900Y583500D03*
X1638674Y556178D03*
X1622040Y554827D03*
X1609829Y556599D03*
X1624293Y561747D03*
X1615030Y584260D03*
X1610080Y561367D03*
X1603060Y582920D03*
X1603120Y578020D03*
X1599170Y572780D03*
X1602000Y565700D03*
X1590004Y605496D03*
Y607996D03*
X1601504Y591526D03*
X1613721Y592325D03*
X1614700Y597000D03*
X1615862Y605507D03*
X1601489Y602812D03*
X1601270Y597200D03*
X1602150Y610720D03*
X1654800Y13518D03*
X1711863Y13276D03*
X1672427Y9700D03*
X1664200Y5400D03*
X1656600Y6300D03*
X1664823Y13287D03*
X1685500Y3000D03*
X1682985Y2901D03*
X1675800Y4100D03*
X1702421Y13231D03*
X1684902Y13472D03*
X1691541Y13226D03*
X1700710Y73292D03*
X1700300Y94703D03*
X1672000Y51500D03*
X1669350Y69962D03*
X1709600Y45800D03*
X1692573Y85833D03*
X1702513Y79885D03*
X1668009Y37000D03*
X1706500D03*
X1678000D03*
X1687500D03*
X1696795Y38260D03*
X1658559Y37890D03*
X1659038Y95111D03*
X1659000Y85500D03*
X1670250Y87873D03*
X1674455Y169991D03*
X1677605Y169986D03*
X1687950Y186150D03*
X1708250Y164950D03*
X1671556Y208379D03*
X1657498Y277300D03*
Y267100D03*
X1657949Y257240D03*
X1653091Y331618D03*
X1652991Y318741D03*
Y323941D03*
X1657500Y287800D03*
X1657600Y304500D03*
X1681192Y454286D03*
X1668000Y416200D03*
X1695658Y486945D03*
X1694410Y499830D03*
X1692120Y501410D03*
X1699900Y512300D03*
X1709400Y513000D03*
X1652500Y575600D03*
X1667277Y535221D03*
X1698600Y584800D03*
X1664113Y548380D03*
X1658466D03*
X1661880Y583900D03*
X1686036Y548251D03*
X1677300Y550200D03*
X1680007Y547917D03*
X1669121Y547923D03*
X1708140Y547538D03*
X1697839Y545759D03*
X1709183Y588700D03*
X1654100Y615790D03*
X1653970Y607340D03*
X1652700Y591300D03*
Y600850D03*
X1662580Y593200D03*
X1661200Y601300D03*
Y607300D03*
X1730550Y21160D03*
X1721559Y13500D03*
X1730768Y13313D03*
X1763100Y21500D03*
X1768807Y21512D03*
X1753903Y22116D03*
X1749941Y21163D03*
X1741000Y21200D03*
X1715259Y35602D03*
X1715100Y46100D03*
X1713550Y56000D03*
X1716900Y87900D03*
X1753059Y35300D03*
X1735150Y60650D03*
X1748500Y79500D03*
X1748854Y58533D03*
X1717600Y46100D03*
X1724758Y38600D03*
X1720600Y70200D03*
X1733910Y38233D03*
X1757054Y66059D03*
X1758100Y37000D03*
X1749364Y38971D03*
X1743500Y39300D03*
X1768450Y77376D03*
X1765900Y83700D03*
X1754703Y84053D03*
X1771459Y52695D03*
X1733900Y92200D03*
X1754600Y109200D03*
X1767250Y99500D03*
Y104500D03*
X1770850Y109500D03*
X1714189Y159550D03*
X1714528Y190189D03*
X1758650Y158650D03*
X1750189Y159550D03*
X1745689D03*
X1741189D03*
X1727689D03*
X1723189D03*
X1718689D03*
X1732189D03*
X1736689D03*
X1745777Y179574D03*
X1751975Y179374D03*
X1739377D03*
X1733178Y179574D03*
X1758375D03*
X1764673Y179374D03*
X1770973Y179574D03*
X1726700Y179400D03*
X1740900Y198800D03*
X1744000D03*
X1769100Y209700D03*
X1765950Y209600D03*
X1769016Y198872D03*
X1765866Y198772D03*
X1731260Y209600D03*
X1740709D03*
X1756000Y210000D03*
X1753400Y209900D03*
X1743900Y209700D03*
X1728616Y198872D03*
X1753311Y198700D03*
X1756600Y198800D03*
X1731216Y198872D03*
X1763554Y237712D03*
X1762795Y232106D03*
X1772244D03*
X1752554Y237712D03*
X1771451D03*
X1724944Y250324D03*
X1727444D03*
X1771243Y250100D03*
X1729944Y250324D03*
X1768516Y249983D03*
X1744603Y232489D03*
X1753347Y232106D03*
X1763300Y250100D03*
X1766100Y447900D03*
X1762992Y447938D03*
X1740963Y448476D03*
X1753543Y448100D03*
X1750393Y448037D03*
X1737795Y448100D03*
X1722000Y513000D03*
X1742900Y485000D03*
X1734000Y488100D03*
X1755000Y485000D03*
X1748600D03*
X1749396Y493969D03*
X1751868Y494045D03*
X1770325Y490255D03*
X1773500Y472100D03*
X1767300Y472700D03*
X1765325Y490255D03*
X1758500Y493800D03*
X1760900Y472800D03*
X1772459Y467005D03*
X1769309D03*
X1759860D03*
X1756710D03*
X1747262D03*
X1744112D03*
X1734663D03*
X1729200Y519000D03*
X1733830Y502650D03*
X1768900Y521124D03*
X1749090Y513790D03*
X1740400Y496300D03*
X1726600Y519000D03*
X1728700Y502600D03*
X1713600Y513000D03*
X1756417Y563840D03*
X1746000Y574000D03*
X1718000Y587723D03*
X1749000Y552863D03*
X1769000Y576378D03*
X1742381Y585530D03*
X1730814Y568814D03*
X1733000Y560000D03*
X1767455Y571695D03*
X1767000Y563500D03*
X1728245Y585244D03*
X1746052Y614796D03*
X1724092Y618700D03*
X1772158Y610960D03*
X1750739Y618718D03*
X1742509Y595869D03*
X1742381Y591530D03*
X1763500Y599100D03*
X1727843Y597142D03*
X1732443Y592342D03*
Y597142D03*
X1727743Y592342D03*
X1832449Y-8950D03*
X1785612Y10729D03*
X1782371Y26832D03*
X1804508Y11858D03*
X1798676Y11726D03*
X1830344Y13397D03*
X1828824Y3699D03*
X1816693Y13331D03*
X1819800Y35500D03*
X1790700Y34900D03*
X1799774Y34890D03*
X1808444Y37152D03*
X1800000Y80000D03*
X1827000Y87000D03*
X1834300Y41100D03*
X1788200Y93000D03*
Y89000D03*
Y85000D03*
X1818383Y133277D03*
X1788448Y98820D03*
X1788648Y101490D03*
X1807745Y104500D03*
X1803400Y114000D03*
X1796059Y104402D03*
X1801366Y151937D03*
X1811348Y143448D03*
X1800264Y143789D03*
X1800000Y132627D03*
X1820648Y155537D03*
X1816348D03*
X1777172Y179374D03*
X1778466Y198772D03*
X1783572Y179574D03*
X1802369Y179374D03*
X1808769Y179574D03*
X1815000Y179300D03*
X1789870Y179374D03*
X1796170Y179574D03*
X1795348Y172037D03*
X1797848D03*
X1792748Y171937D03*
X1821367Y179574D03*
X1827565Y179174D03*
X1833388Y179500D03*
X1791150Y209600D03*
X1794300Y209700D03*
X1794216Y198872D03*
X1791066Y198772D03*
X1819457Y198872D03*
X1828700Y198800D03*
X1820349Y209586D03*
X1828950Y209600D03*
X1832274Y209734D03*
X1816266Y198772D03*
X1804166Y198472D03*
X1807751Y209586D03*
X1803072Y209728D03*
X1806821Y198600D03*
X1815670Y209728D03*
X1781700Y209700D03*
X1778550Y209600D03*
X1781616Y198872D03*
X1816348Y163437D03*
X1818500Y159500D03*
X1820648Y163437D03*
X1782452Y237712D03*
X1820281Y250498D03*
X1809281D03*
X1801384D03*
X1790383D03*
X1791141Y232106D03*
X1828936Y249900D03*
X1819488Y232106D03*
X1810040D03*
X1800591D03*
X1781693D03*
X1775590Y448100D03*
X1778740D03*
X1828600Y450100D03*
X1825984Y448030D03*
X1816535Y448300D03*
X1813385Y447945D03*
X1804000Y447900D03*
X1800787Y447943D03*
X1791338Y448400D03*
X1788189Y448300D03*
X1779700Y472100D03*
X1784525Y491830D03*
X1781907Y467005D03*
X1785057D03*
X1779303Y497246D03*
X1832301Y467005D03*
X1835550Y466870D03*
X1789774Y476403D03*
X1801500Y471055D03*
X1795164Y476406D03*
X1789525Y491830D03*
X1801125D03*
X1796125D03*
X1817325Y481320D03*
X1806600Y471055D03*
X1812325Y481320D03*
X1806975Y491630D03*
X1830220Y479950D03*
X1824960Y473980D03*
X1824125Y491830D03*
X1822852Y467005D03*
X1819702D03*
X1819125Y491830D03*
X1807104Y467005D03*
X1810254D03*
X1811975Y491630D03*
X1797655Y467005D03*
X1794505D03*
X1810508Y515900D03*
X1804000Y498176D03*
X1834540Y519600D03*
X1796400Y498000D03*
X1781510Y546362D03*
X1786500Y562200D03*
X1783700Y579200D03*
X1828800Y546500D03*
X1828700Y540252D03*
X1828900Y552300D03*
X1834000Y534900D03*
X1811704Y554341D03*
X1807600Y552047D03*
X1806200Y549200D03*
X1786900Y552500D03*
X1801200Y529800D03*
X1806200Y582900D03*
X1810387Y571435D03*
X1794000Y568800D03*
X1793320Y557968D03*
X1828700Y569474D03*
X1836281Y589122D03*
X1828800Y575600D03*
X1828875Y563674D03*
X1828824Y557663D03*
X1810385Y568821D03*
X1807958Y565690D03*
X1812452Y538501D03*
Y533601D03*
X1807852D03*
X1807752Y538501D03*
X1779000Y598900D03*
X1787500Y597791D03*
X1825014Y593695D03*
X1811500Y603500D03*
X1808152Y591601D03*
X1812852Y596401D03*
X1808252D03*
X1812852Y591601D03*
X1893094Y-10142D03*
X1838100Y3900D03*
X1889218Y43530D03*
Y53530D03*
X1846800Y95400D03*
X1847000Y86500D03*
X1848000Y56500D03*
X1850500D03*
X1890803Y63189D03*
X1884500Y79300D03*
X1882000D03*
X1895330Y64390D03*
X1877270Y63473D03*
X1880230Y76820D03*
X1879500Y79300D03*
X1880986Y53299D03*
X1860995Y84509D03*
X1856873Y91200D03*
X1856778Y87397D03*
X1864208Y87724D03*
X1864195Y84509D03*
X1864153Y91241D03*
X1860815Y91184D03*
X1875100Y51300D03*
X1872340Y147236D03*
X1895800Y149200D03*
X1885400Y147000D03*
X1878550Y99470D03*
X1882550D03*
X1894834Y139286D03*
X1863908Y140992D03*
X1878950Y137400D03*
X1871855Y104188D03*
X1856700Y110167D03*
X1869000Y153900D03*
X1887830Y102227D03*
X1852600Y97500D03*
X1887300Y121500D03*
X1850700Y156000D03*
X1875700Y115700D03*
Y121500D03*
X1881500Y115700D03*
Y121500D03*
Y127300D03*
X1887300D03*
X1875700D03*
X1887300Y115700D03*
X1846663Y153748D03*
X1839500Y212700D03*
X1857044Y186292D03*
X1863750Y163750D03*
X1868375Y171900D03*
X1846163Y168448D03*
X1886800Y210600D03*
X1871708Y213442D03*
X1854663Y158248D03*
X1846663D03*
X1852300Y252000D03*
X1858400Y251200D03*
X1843700Y253400D03*
X1839400Y450440D03*
X1838768Y454120D03*
X1847185Y454368D03*
X1860158Y450322D03*
X1864300Y447900D03*
X1882677Y447930D03*
X1895275Y454422D03*
X1898425Y447930D03*
Y454422D03*
X1845330Y466870D03*
X1843000Y505000D03*
X1857480Y466800D03*
X1861300D03*
X1881285Y467049D03*
X1849795Y493379D03*
X1850290Y486610D03*
X1872908Y471338D03*
X1870138Y485732D03*
X1852340Y509140D03*
X1877518Y527560D03*
X1889800Y580200D03*
X1878000Y539000D03*
X1861080Y537090D03*
X1842500Y534500D03*
X1844100Y551000D03*
X1848900Y545500D03*
X1878450Y548650D03*
X1870250Y541950D03*
X1896500Y555300D03*
X1879800Y579000D03*
X1858000Y574000D03*
X1870892Y583245D03*
X1874825Y564125D03*
X1859167Y559350D03*
X1894299Y557790D03*
X1906438Y-15968D03*
X1909406Y76790D03*
X1907986Y82393D03*
X1907929Y84793D03*
X1907907Y87223D03*
X1918379Y84788D03*
X1905501Y79790D03*
X1902796Y79820D03*
X1900100Y145100D03*
X1921199Y140499D03*
X1929711Y155759D03*
X1904136Y140160D03*
X1937000Y150000D03*
X1906871Y106049D03*
X1911231Y137097D03*
X1908715Y104512D03*
X1912100Y142600D03*
X1915030Y147250D03*
X1911440Y128840D03*
X1952440Y98520D03*
X1942637Y100877D03*
X1914152Y115928D03*
X1950983Y147344D03*
X1928100Y136078D03*
X1953200Y195530D03*
X1937100Y206800D03*
X1908967Y201609D03*
X1909186Y211906D03*
X1944500Y183900D03*
X1903524Y208156D03*
X1905074Y198163D03*
X1943200Y214800D03*
X1928400Y212500D03*
X1926000Y212400D03*
X1933898Y216707D03*
X1945156Y160236D03*
X1950994Y173745D03*
X1939316Y173600D03*
X1900740Y178720D03*
X1900700Y172990D03*
Y167290D03*
X1906440Y178720D03*
X1906500Y173100D03*
X1906400Y167290D03*
X1912190Y178870D03*
X1912230Y167330D03*
Y173030D03*
X1946105Y230344D03*
X1902909Y223195D03*
X1943517Y223637D03*
X1943800Y241800D03*
X1943900Y238500D03*
X1934750Y242700D03*
Y240300D03*
X1925600Y242700D03*
X1929000Y445800D03*
X1910500Y435600D03*
X1927100Y436200D03*
X1930100D03*
X1904724Y454422D03*
X1901574Y447930D03*
X1907500Y435600D03*
X1911023Y448400D03*
X1907874Y454422D03*
Y448400D03*
X1933100Y436200D03*
X1957100Y502990D03*
X1955790Y499790D03*
X1947380Y482450D03*
X1915100Y480050D03*
X1905010Y479410D03*
X1939000Y479400D03*
X1952500Y508000D03*
X1959260Y506010D03*
X1938410Y490650D03*
X1929480Y472880D03*
X1905000Y533900D03*
X1906050Y569100D03*
X1923600Y554200D03*
X1955400Y530500D03*
X1923600Y572300D03*
X1908400Y556800D03*
X1915593Y576807D03*
X1953500Y551900D03*
X1943300Y535700D03*
X1921800Y586100D03*
X1936770Y607210D03*
X1906200Y607800D03*
X1916050Y604450D03*
X1924000Y611391D03*
X1968179Y77969D03*
X1965679D03*
Y75369D03*
X1968179D03*
X1965679Y82969D03*
Y80469D03*
X1968179D03*
X1966212Y72897D03*
X1970679Y75369D03*
Y80469D03*
Y77969D03*
X1962800Y143700D03*
X1971200Y152500D03*
X1965400Y149700D03*
X1961472Y165760D03*
X1967817Y201029D03*
X1965900Y184600D03*
X1965057Y176447D03*
X1966542Y179606D03*
X1965973Y166190D03*
X1970270Y474640D03*
X1968870Y481710D03*
X1970500Y502720D03*
X1963500Y521000D03*
X1961500Y561700D03*
Y582700D03*
X1972700Y552700D03*
G36*
G01X1956463Y209274D02*
G02X1954500Y205493I-1963J-1381D01*
G01X1950000D01*
G02X1947600Y207893I0J2400D01*
G01Y210293D01*
G02X1952400I2400J0D01*
G01X1954500D01*
G02X1954986Y210243I-1J-2400D01*
G03X1956463Y209274I1904J1292D01*
G37*
G54D22*
X1526871Y23968D03*
X1881595D03*
G54D13*
X-15748Y101221D03*
Y148465D03*
Y357362D03*
Y373110D03*
Y388858D03*
Y404606D03*
X12205Y156339D03*
X-4331D03*
X17323Y101221D03*
Y116969D03*
Y132717D03*
Y148465D03*
X787Y101221D03*
Y116969D03*
Y148465D03*
X33858Y101221D03*
Y116969D03*
Y132717D03*
Y148465D03*
X28740Y109095D03*
Y156339D03*
X12205Y109095D03*
Y140591D03*
X-4331Y109095D03*
Y124843D03*
Y140591D03*
X17323Y357362D03*
Y373110D03*
Y388858D03*
Y404606D03*
X787Y357362D03*
Y373110D03*
Y388858D03*
Y404606D03*
X33858Y357362D03*
Y373110D03*
Y388858D03*
Y404606D03*
X28740Y365236D03*
Y380984D03*
Y396732D03*
X12205Y365236D03*
Y380984D03*
Y396732D03*
X-4331Y365236D03*
Y380984D03*
Y396732D03*
X12205Y412480D03*
X-4331D03*
X28740D03*
G54D32*
X1952250Y240355D03*
G54D14*
X30500Y-42250D03*
Y-52250D03*
X12290Y264640D03*
X18450Y267010D03*
X22970Y244400D03*
X28720Y244450D03*
X17120Y244220D03*
X24200Y267060D03*
X50500Y-42250D03*
X70500D03*
X90500D03*
X110500D03*
X50500Y-52250D03*
X70500D03*
X90500D03*
X110500D03*
X130500Y-42250D03*
Y-52250D03*
X457246Y-52301D03*
Y-42301D03*
X477246Y-52301D03*
Y-42301D03*
X497246Y-52301D03*
Y-42301D03*
X517246Y-52301D03*
Y-42301D03*
X537246Y-52301D03*
Y-42301D03*
X557246Y-52301D03*
Y-42301D03*
X788984Y-52057D03*
Y-42057D03*
X808984Y-52057D03*
Y-42057D03*
X828984Y-52057D03*
Y-42057D03*
X848984Y-52057D03*
Y-42057D03*
X868984Y-52057D03*
Y-42057D03*
X888984Y-52057D03*
Y-42057D03*
X1125583Y-52285D03*
Y-42285D03*
X1145583Y-52285D03*
Y-42285D03*
X1382258Y-52257D03*
Y-42257D03*
X1402258Y-52257D03*
Y-42257D03*
X1422258Y-52257D03*
Y-42257D03*
X1442258Y-52257D03*
Y-42257D03*
G54D23*
X1647327Y-315D03*
G54D24*
X1613069Y302692D03*
G54D33*
X1969883Y207007D03*
Y242441D03*
G54D15*
X18228Y178386D03*
X-1969D03*
X44291D03*
G54D16*
X3937Y204370D03*
X-3937D03*
X-11811D03*
X35433D03*
X27559D03*
X19685D03*
X3937Y227992D03*
X-3937D03*
X-11811D03*
X35433D03*
X27559D03*
X19685D03*
X3937Y313504D03*
X-3937D03*
X-11811D03*
X3937Y337126D03*
X-3937D03*
X-11811D03*
X35433D03*
X27559D03*
X19685D03*
X35433Y313504D03*
X27559D03*
X19685D03*
G54D25*
X1643803Y585591D03*
X1640850Y582835D03*
X1631992D03*
X1623134D03*
X1640850Y567874D03*
X1631992D03*
X1623134D03*
X1646756Y595039D03*
X1623134Y612756D03*
X1640850Y597795D03*
X1631992D03*
X1623134D03*
X1640850Y612756D03*
X1631992D03*
X1691047Y585591D03*
X1688094Y582835D03*
X1679236D03*
X1670378D03*
X1688094Y567874D03*
X1679236D03*
X1670378D03*
X1694000Y595039D03*
X1688094Y612756D03*
X1679236D03*
X1670378D03*
X1688094Y597795D03*
X1679236D03*
X1670378D03*
G54D34*
G01X-9569Y-9569D02*
X0Y0D01*
G01D02*
X9569Y9569D01*
G01X-9569D02*
X0Y0D01*
G01D02*
X9569Y-9569D01*
G01X1602685Y292308D02*
X1613069Y302692D01*
G01D02*
X1623453Y313076D01*
G01X1602685D02*
X1613069Y302692D01*
G01D02*
X1623453Y292308D01*
X1961890Y211043D03*
Y238405D03*
G54D35*
G01X1684953Y534539D02*
X1687205Y536791D01*
G01D02*
X1689457Y539043D01*
G01X1684953D02*
X1687205Y536791D01*
G01D02*
X1689457Y534539D01*
G01X1699953D02*
X1702205Y536791D01*
G01D02*
X1704457Y539043D01*
G01X1699953D02*
X1702205Y536791D01*
G01D02*
X1704457Y534539D01*
G01X1747417Y534680D02*
X1749528Y536791D01*
G01D02*
X1751639Y538902D01*
G01X1747417D02*
X1749528Y536791D01*
G01D02*
X1751639Y534680D01*
G01X1751354D02*
X1753465Y536791D01*
G01D02*
X1755576Y538902D01*
G01X1751354D02*
X1753465Y536791D01*
G01D02*
X1755576Y534680D01*
G01X1714953Y534539D02*
X1717205Y536791D01*
G01D02*
X1719457Y539043D01*
G01X1714953D02*
X1717205Y536791D01*
G01D02*
X1719457Y534539D01*
G01X1893410Y19119D02*
X1895945Y21654D01*
G01X1893410Y24189D02*
X1895945Y21654D01*
G01X1897500Y579500D02*
X1900106Y576894D01*
G01X1898000Y589409D02*
X1900606Y586803D01*
G54D17*
X15512Y434094D03*
G54D26*
X1702205Y536791D03*
X1687205D03*
X1717205D03*
G54D36*
G01X548049Y-193422D02*
Y-210922D01*
G01X543027Y-193422D02*
X553071D01*
G01X565549Y-199256D02*
Y-210922D01*
G01Y-194589D02*
X565112Y-194297D01*
Y-193714D01*
X565549Y-193422D01*
X565986Y-193714D01*
Y-194297D01*
X565549Y-194589D01*
G01X583049Y-210922D02*
X581739Y-210630D01*
X580429Y-209464D01*
X579555Y-207422D01*
X579119Y-205089D01*
X579555Y-202755D01*
X580429Y-200714D01*
X581739Y-199547D01*
X583049Y-199256D01*
X584359Y-199547D01*
X585669Y-200714D01*
X586542Y-202755D01*
X586761Y-205089D01*
X586542Y-207422D01*
X585669Y-209464D01*
X584359Y-210630D01*
X583049Y-210922D01*
G01X597492Y-215297D02*
X599021Y-216464D01*
X600767Y-216755D01*
X602295Y-216464D01*
X603606Y-215006D01*
X604479Y-212964D01*
Y-199256D01*
G01Y-201589D02*
X603606Y-200422D01*
X602295Y-199547D01*
X600767Y-199256D01*
X599021Y-199839D01*
X597929Y-201005D01*
X597055Y-203047D01*
X596619Y-205089D01*
X596837Y-206839D01*
X597711Y-208881D01*
X599021Y-210339D01*
X600767Y-210922D01*
X602077Y-210630D01*
X603606Y-209464D01*
X604479Y-208298D01*
G01X621979Y-210922D02*
Y-199256D01*
G01Y-201297D02*
X621106Y-200131D01*
X619795Y-199547D01*
X618267Y-199256D01*
X616739Y-199839D01*
X615429Y-201005D01*
X614555Y-202755D01*
X614119Y-205089D01*
X614555Y-207422D01*
X615429Y-209172D01*
X616739Y-210339D01*
X618267Y-210922D01*
X619795Y-210630D01*
X621106Y-209756D01*
X621979Y-208589D01*
G01X648682Y-210922D02*
Y-193422D01*
X653922D01*
X655669Y-194297D01*
X656979Y-196339D01*
X657416Y-198672D01*
X656979Y-201005D01*
X655887Y-202755D01*
X653922Y-203631D01*
X648682D01*
G01X674479Y-210922D02*
Y-199256D01*
G01Y-201297D02*
X673606Y-200131D01*
X672295Y-199547D01*
X670767Y-199256D01*
X669239Y-199839D01*
X667929Y-201005D01*
X667055Y-202755D01*
X666619Y-205089D01*
X667055Y-207422D01*
X667929Y-209172D01*
X669239Y-210339D01*
X670767Y-210922D01*
X672295Y-210630D01*
X673606Y-209756D01*
X674479Y-208589D01*
G01X684774Y-208881D02*
X685866Y-210047D01*
X687394Y-210922D01*
X688704D01*
X690014Y-210339D01*
X690887Y-209464D01*
X691324Y-208298D01*
X691106Y-206547D01*
X690232Y-205672D01*
X686302Y-203922D01*
X685429Y-201880D01*
X685866Y-200422D01*
X686739Y-199547D01*
X688049Y-199256D01*
X689359Y-199547D01*
X690669Y-200422D01*
G01X702274Y-208881D02*
X703366Y-210047D01*
X704894Y-210922D01*
X706204D01*
X707514Y-210339D01*
X708387Y-209464D01*
X708824Y-208298D01*
X708606Y-206547D01*
X707732Y-205672D01*
X703802Y-203922D01*
X702929Y-201880D01*
X703366Y-200422D01*
X704239Y-199547D01*
X705549Y-199256D01*
X706859Y-199547D01*
X708169Y-200422D01*
G01X735746Y-210922D02*
Y-193422D01*
X740112D01*
X741859Y-194297D01*
X743169Y-195464D01*
X744261Y-197213D01*
X745134Y-199256D01*
X745352Y-202172D01*
X745134Y-205089D01*
X744261Y-207131D01*
X743169Y-208881D01*
X741859Y-210047D01*
X740112Y-210922D01*
X735746D01*
G01X752590Y-193422D02*
X758049Y-210922D01*
X763508Y-193422D01*
G01X775549D02*
Y-210922D01*
G01X770527Y-193422D02*
X780571D01*
G01X804872Y-210922D02*
Y-193422D01*
X810549Y-208005D01*
X816226Y-193422D01*
Y-210922D01*
G01X829795Y-201589D02*
X830669Y-200714D01*
X831324Y-199256D01*
X831761Y-197213D01*
X831324Y-195464D01*
X830451Y-194297D01*
X828922Y-193422D01*
X823027D01*
Y-210922D01*
X830232D01*
X831761Y-209756D01*
X832634Y-208005D01*
X833071Y-205964D01*
X832634Y-203922D01*
X831324Y-202172D01*
X829795Y-201589D01*
X823027D01*
G01X647372Y-165922D02*
Y-148422D01*
X653049Y-163005D01*
X658726Y-148422D01*
Y-165922D01*
G01X670549D02*
X669239Y-165630D01*
X667929Y-164464D01*
X667055Y-162422D01*
X666619Y-160089D01*
X667055Y-157755D01*
X667929Y-155714D01*
X669239Y-154547D01*
X670549Y-154256D01*
X671859Y-154547D01*
X673169Y-155714D01*
X674042Y-157755D01*
X674261Y-160089D01*
X674042Y-162422D01*
X673169Y-164464D01*
X671859Y-165630D01*
X670549Y-165922D01*
G01X691979Y-148422D02*
Y-165922D01*
G01Y-163298D02*
X691106Y-164756D01*
X689795Y-165630D01*
X688267Y-165922D01*
X686521Y-165339D01*
X685211Y-163881D01*
X684337Y-162131D01*
X684119Y-160089D01*
X684337Y-158047D01*
X685211Y-156297D01*
X686521Y-154839D01*
X688267Y-154256D01*
X689795Y-154547D01*
X690887Y-155131D01*
X691979Y-156297D01*
G01X702274Y-158047D02*
X709261D01*
X708606Y-156005D01*
X707514Y-154839D01*
X705986Y-154256D01*
X704457Y-154547D01*
X703147Y-155422D01*
X702274Y-157464D01*
X701837Y-159214D01*
Y-160964D01*
X702274Y-162714D01*
X703366Y-164464D01*
X704676Y-165630D01*
X706204Y-165922D01*
X707732Y-165339D01*
X709261Y-163589D01*
G01X723049Y-165922D02*
Y-148422D01*
G01X975549Y-210922D02*
Y-193422D01*
X972929Y-196922D01*
G01Y-210922D02*
X978169D01*
G01X988246Y-208298D02*
X989555Y-209756D01*
X991084Y-210630D01*
X993049Y-210922D01*
X995014Y-210339D01*
X996542Y-209172D01*
X997634Y-207131D01*
X997852Y-204797D01*
X997416Y-202464D01*
X996324Y-201005D01*
X994795Y-199839D01*
X993267Y-199547D01*
X991739Y-199839D01*
X989774Y-201005D01*
X990429Y-193422D01*
X996324D01*
G01X1010549Y-210922D02*
Y-193422D01*
X1007929Y-196922D01*
G01Y-210922D02*
X1013169D01*
G01X1023901Y-196339D02*
X1025211Y-194589D01*
X1026739Y-193714D01*
X1028486Y-193422D01*
X1030669Y-194005D01*
X1032197Y-195464D01*
X1032634Y-197213D01*
X1032416Y-198964D01*
X1031542Y-200422D01*
X1027176Y-203339D01*
X1025211Y-205380D01*
X1023901Y-208298D01*
X1023464Y-210922D01*
X1032634D01*
G01X1041401Y-203631D02*
X1042929Y-201589D01*
X1044239Y-200422D01*
X1045986Y-199839D01*
X1047514Y-200422D01*
X1048606Y-201589D01*
X1049479Y-203339D01*
X1049697Y-205380D01*
X1049479Y-207131D01*
X1048606Y-208881D01*
X1047295Y-210339D01*
X1045767Y-210922D01*
X1044021Y-210339D01*
X1042492Y-208589D01*
X1041619Y-205964D01*
X1041401Y-203047D01*
X1041837Y-199256D01*
X1042492Y-197213D01*
X1043584Y-195172D01*
X1045112Y-193714D01*
X1046641Y-193422D01*
X1048169Y-194005D01*
X1049261Y-195464D01*
G01X962432Y-165922D02*
Y-148422D01*
X967672D01*
X969419Y-149297D01*
X970729Y-151339D01*
X971166Y-153672D01*
X970729Y-156005D01*
X969637Y-157755D01*
X967672Y-158631D01*
X962432D01*
G01X989102Y-149881D02*
X987792Y-149005D01*
X986264Y-148422D01*
X984517D01*
X982552Y-149297D01*
X981024Y-150755D01*
X979932Y-152506D01*
X979059Y-155422D01*
X978840Y-158047D01*
X979277Y-160672D01*
X979932Y-162422D01*
X981242Y-164172D01*
X982771Y-165339D01*
X984299Y-165922D01*
X985827D01*
X987356Y-165339D01*
X988666Y-164464D01*
X989758Y-163298D01*
G01X1003545Y-156589D02*
X1004419Y-155714D01*
X1005074Y-154256D01*
X1005511Y-152213D01*
X1005074Y-150464D01*
X1004201Y-149297D01*
X1002672Y-148422D01*
X996777D01*
Y-165922D01*
X1003982D01*
X1005511Y-164756D01*
X1006384Y-163005D01*
X1006821Y-160964D01*
X1006384Y-158922D01*
X1005074Y-157172D01*
X1003545Y-156589D01*
X996777D01*
G01X1012749Y-171755D02*
X1025849D01*
G01X1031777Y-165922D02*
Y-148422D01*
X1041821Y-165922D01*
Y-148422D01*
G01X1054299Y-165922D02*
X1052552Y-165630D01*
X1051024Y-164464D01*
X1049714Y-162714D01*
X1048840Y-160672D01*
X1048404Y-158339D01*
Y-156005D01*
X1048840Y-153672D01*
X1049714Y-151630D01*
X1051024Y-149881D01*
X1052552Y-148714D01*
X1054299Y-148422D01*
X1056045Y-148714D01*
X1057574Y-149881D01*
X1058884Y-151630D01*
X1059758Y-153672D01*
X1060194Y-156005D01*
Y-158339D01*
X1059758Y-160672D01*
X1058884Y-162714D01*
X1057574Y-164464D01*
X1056045Y-165630D01*
X1054299Y-165922D01*
G01X1128099Y-210922D02*
Y-193422D01*
X1125479Y-196922D01*
G01Y-210922D02*
X1130719D01*
G01X1147345Y-201589D02*
X1148219Y-200714D01*
X1148874Y-199256D01*
X1149311Y-197213D01*
X1148874Y-195464D01*
X1148001Y-194297D01*
X1146472Y-193422D01*
X1140577D01*
Y-210922D01*
X1147782D01*
X1149311Y-209756D01*
X1150184Y-208005D01*
X1150621Y-205964D01*
X1150184Y-203922D01*
X1148874Y-202172D01*
X1147345Y-201589D01*
X1140577D01*
G01X1105140Y-148422D02*
X1110599Y-165922D01*
X1116058Y-148422D01*
G01X1132466Y-165922D02*
X1123732D01*
Y-148422D01*
X1132466D01*
G01X1128972Y-156880D02*
X1123732D01*
G01X1141232Y-165922D02*
Y-148422D01*
X1146691D01*
X1148437Y-149297D01*
X1149529Y-150464D01*
X1149966Y-152797D01*
X1149529Y-155131D01*
X1148219Y-156589D01*
X1146691Y-157464D01*
X1141232D01*
G01X1146691D02*
X1149966Y-165922D01*
G01X1163099Y-166505D02*
X1162662Y-166214D01*
Y-165630D01*
X1163099Y-165339D01*
X1163536Y-165630D01*
Y-166214D01*
X1163099Y-166505D01*
G01X1317416Y-193422D02*
Y-210922D01*
X1308682D01*
G01X1299261Y-208881D02*
X1297732Y-210339D01*
X1295986Y-210922D01*
X1294239Y-210339D01*
X1292711Y-208589D01*
X1291619Y-205964D01*
X1291182Y-203339D01*
Y-200131D01*
X1291619Y-197506D01*
X1292711Y-195172D01*
X1294021Y-194005D01*
X1295549Y-193422D01*
X1297296Y-194005D01*
X1298606Y-195172D01*
X1299479Y-196922D01*
X1299916Y-199256D01*
X1299479Y-201297D01*
X1298387Y-203339D01*
X1297077Y-204506D01*
X1295549Y-204797D01*
X1293803Y-204214D01*
X1292492Y-202755D01*
X1291182Y-200131D01*
G01X1276739Y-202172D02*
X1272372D01*
Y-207422D01*
X1273682Y-209172D01*
X1275211Y-210339D01*
X1277394Y-210922D01*
X1279577Y-210339D01*
X1281106Y-209172D01*
X1282416Y-207422D01*
X1283289Y-205380D01*
X1283726Y-203047D01*
Y-201005D01*
X1283289Y-199256D01*
X1282416Y-197213D01*
X1281106Y-195464D01*
X1279796Y-194297D01*
X1278049Y-193422D01*
X1276521D01*
X1274774Y-194005D01*
X1273464Y-195172D01*
G01X1265571Y-210922D02*
Y-193422D01*
X1255527Y-210922D01*
Y-193422D01*
G01X1247852Y-210922D02*
Y-193422D01*
X1243486D01*
X1241739Y-194297D01*
X1240429Y-195464D01*
X1239337Y-197213D01*
X1238464Y-199256D01*
X1238246Y-202172D01*
X1238464Y-205089D01*
X1239337Y-207131D01*
X1240429Y-208881D01*
X1241739Y-210047D01*
X1243486Y-210922D01*
X1247852D01*
G01X1238682Y-148422D02*
Y-165922D01*
X1247416D01*
G01X1264479D02*
Y-154256D01*
G01Y-156297D02*
X1263606Y-155131D01*
X1262295Y-154547D01*
X1260767Y-154256D01*
X1259239Y-154839D01*
X1257929Y-156005D01*
X1257055Y-157755D01*
X1256619Y-160089D01*
X1257055Y-162422D01*
X1257929Y-164172D01*
X1259239Y-165339D01*
X1260767Y-165922D01*
X1262295Y-165630D01*
X1263606Y-164756D01*
X1264479Y-163589D01*
G01X1273464Y-171172D02*
X1274774Y-171755D01*
X1276521Y-171172D01*
X1277612Y-170006D01*
X1278486Y-168547D01*
X1279795Y-163881D01*
X1282634Y-154256D01*
G01X1275647D02*
X1279795Y-163881D01*
G01X1292274Y-158047D02*
X1299261D01*
X1298606Y-156005D01*
X1297514Y-154839D01*
X1295986Y-154256D01*
X1294457Y-154547D01*
X1293147Y-155422D01*
X1292274Y-157464D01*
X1291837Y-159214D01*
Y-160964D01*
X1292274Y-162714D01*
X1293366Y-164464D01*
X1294676Y-165630D01*
X1296204Y-165922D01*
X1297732Y-165339D01*
X1299261Y-163589D01*
G01X1309992Y-165922D02*
Y-154256D01*
G01Y-156589D02*
X1311084Y-155422D01*
X1312176Y-154547D01*
X1313704Y-154256D01*
X1314795Y-154547D01*
X1316106Y-155422D01*
G01X1380796Y-165922D02*
Y-148422D01*
X1385162D01*
X1386909Y-149297D01*
X1388219Y-150464D01*
X1389311Y-152213D01*
X1390184Y-154256D01*
X1390402Y-157172D01*
X1390184Y-160089D01*
X1389311Y-162131D01*
X1388219Y-163881D01*
X1386909Y-165047D01*
X1385162Y-165922D01*
X1380796D01*
G01X1399824Y-158047D02*
X1406811D01*
X1406156Y-156005D01*
X1405064Y-154839D01*
X1403536Y-154256D01*
X1402007Y-154547D01*
X1400697Y-155422D01*
X1399824Y-157464D01*
X1399387Y-159214D01*
Y-160964D01*
X1399824Y-162714D01*
X1400916Y-164464D01*
X1402226Y-165630D01*
X1403754Y-165922D01*
X1405282Y-165339D01*
X1406811Y-163589D01*
G01X1417324Y-163881D02*
X1418416Y-165047D01*
X1419944Y-165922D01*
X1421254D01*
X1422564Y-165339D01*
X1423437Y-164464D01*
X1423874Y-163298D01*
X1423656Y-161547D01*
X1422782Y-160672D01*
X1418852Y-158922D01*
X1417979Y-156880D01*
X1418416Y-155422D01*
X1419289Y-154547D01*
X1420599Y-154256D01*
X1421909Y-154547D01*
X1423219Y-155422D01*
G01X1438099Y-154256D02*
Y-165922D01*
G01Y-149589D02*
X1437662Y-149297D01*
Y-148714D01*
X1438099Y-148422D01*
X1438536Y-148714D01*
Y-149297D01*
X1438099Y-149589D01*
G01X1452542Y-170297D02*
X1454071Y-171464D01*
X1455817Y-171755D01*
X1457345Y-171464D01*
X1458656Y-170006D01*
X1459529Y-167964D01*
Y-154256D01*
G01Y-156589D02*
X1458656Y-155422D01*
X1457345Y-154547D01*
X1455817Y-154256D01*
X1454071Y-154839D01*
X1452979Y-156005D01*
X1452105Y-158047D01*
X1451669Y-160089D01*
X1451887Y-161839D01*
X1452761Y-163881D01*
X1454071Y-165339D01*
X1455817Y-165922D01*
X1457127Y-165630D01*
X1458656Y-164464D01*
X1459529Y-163298D01*
G01X1469387Y-165922D02*
Y-154256D01*
G01Y-157172D02*
X1470261Y-155714D01*
X1471571Y-154547D01*
X1473317Y-154256D01*
X1474845Y-154547D01*
X1476156Y-155714D01*
X1476811Y-157755D01*
Y-165922D01*
G01X1487324Y-158047D02*
X1494311D01*
X1493656Y-156005D01*
X1492564Y-154839D01*
X1491036Y-154256D01*
X1489507Y-154547D01*
X1488197Y-155422D01*
X1487324Y-157464D01*
X1486887Y-159214D01*
Y-160964D01*
X1487324Y-162714D01*
X1488416Y-164464D01*
X1489726Y-165630D01*
X1491254Y-165922D01*
X1492782Y-165339D01*
X1494311Y-163589D01*
G01X1505042Y-165922D02*
Y-154256D01*
G01Y-156589D02*
X1506134Y-155422D01*
X1507226Y-154547D01*
X1508754Y-154256D01*
X1509845Y-154547D01*
X1511156Y-155422D01*
G01X1426729Y-193422D02*
X1431969D01*
G01X1429349D02*
Y-210922D01*
G01X1426729D02*
X1431969D01*
G01X1441390Y-193422D02*
X1446849Y-210922D01*
X1452308Y-193422D01*
G01X1464349Y-210922D02*
Y-203047D01*
X1459982Y-193422D01*
G01X1468716D02*
X1464349Y-203047D01*
G01X1551799Y-193422D02*
X1550052Y-194005D01*
X1548742Y-195464D01*
X1547869Y-197213D01*
X1547214Y-199547D01*
X1546996Y-202172D01*
X1547214Y-204797D01*
X1547869Y-207131D01*
X1548742Y-208881D01*
X1550052Y-210339D01*
X1551799Y-210922D01*
X1553545Y-210339D01*
X1554856Y-208881D01*
X1555729Y-207131D01*
X1556384Y-204797D01*
X1556602Y-202172D01*
X1556384Y-199547D01*
X1555729Y-197213D01*
X1554856Y-195464D01*
X1553545Y-194005D01*
X1551799Y-193422D01*
G01X1565151Y-196339D02*
X1566461Y-194589D01*
X1567989Y-193714D01*
X1569736Y-193422D01*
X1571919Y-194005D01*
X1573447Y-195464D01*
X1573884Y-197213D01*
X1573666Y-198964D01*
X1572792Y-200422D01*
X1568426Y-203339D01*
X1566461Y-205380D01*
X1565151Y-208298D01*
X1564714Y-210922D01*
X1573884D01*
G01X1582869Y-211505D02*
X1590729Y-193422D01*
G01X1604299Y-210922D02*
Y-193422D01*
X1601679Y-196922D01*
G01Y-210922D02*
X1606919D01*
G01X1621799Y-193422D02*
X1620052Y-194005D01*
X1618742Y-195464D01*
X1617869Y-197213D01*
X1617214Y-199547D01*
X1616996Y-202172D01*
X1617214Y-204797D01*
X1617869Y-207131D01*
X1618742Y-208881D01*
X1620052Y-210339D01*
X1621799Y-210922D01*
X1623545Y-210339D01*
X1624856Y-208881D01*
X1625729Y-207131D01*
X1626384Y-204797D01*
X1626602Y-202172D01*
X1626384Y-199547D01*
X1625729Y-197213D01*
X1624856Y-195464D01*
X1623545Y-194005D01*
X1621799Y-193422D01*
G01X1635369Y-211505D02*
X1643229Y-193422D01*
G01X1652651Y-196339D02*
X1653961Y-194589D01*
X1655489Y-193714D01*
X1657236Y-193422D01*
X1659419Y-194005D01*
X1660947Y-195464D01*
X1661384Y-197213D01*
X1661166Y-198964D01*
X1660292Y-200422D01*
X1655926Y-203339D01*
X1653961Y-205380D01*
X1652651Y-208298D01*
X1652214Y-210922D01*
X1661384D01*
G01X1674299Y-193422D02*
X1672552Y-194005D01*
X1671242Y-195464D01*
X1670369Y-197213D01*
X1669714Y-199547D01*
X1669496Y-202172D01*
X1669714Y-204797D01*
X1670369Y-207131D01*
X1671242Y-208881D01*
X1672552Y-210339D01*
X1674299Y-210922D01*
X1676045Y-210339D01*
X1677356Y-208881D01*
X1678229Y-207131D01*
X1678884Y-204797D01*
X1679102Y-202172D01*
X1678884Y-199547D01*
X1678229Y-197213D01*
X1677356Y-195464D01*
X1676045Y-194005D01*
X1674299Y-193422D01*
G01X1691799Y-210922D02*
Y-193422D01*
X1689179Y-196922D01*
G01Y-210922D02*
X1694419D01*
G01X1708862D02*
X1709299Y-207131D01*
X1709954Y-203922D01*
X1710827Y-201005D01*
X1711919Y-197797D01*
X1713666Y-193422D01*
X1704932D01*
G01X1599496Y-165922D02*
Y-148422D01*
X1603862D01*
X1605609Y-149297D01*
X1606919Y-150464D01*
X1608011Y-152213D01*
X1608884Y-154256D01*
X1609102Y-157172D01*
X1608884Y-160089D01*
X1608011Y-162131D01*
X1606919Y-163881D01*
X1605609Y-165047D01*
X1603862Y-165922D01*
X1599496D01*
G01X1625729D02*
Y-154256D01*
G01Y-156297D02*
X1624856Y-155131D01*
X1623545Y-154547D01*
X1622017Y-154256D01*
X1620489Y-154839D01*
X1619179Y-156005D01*
X1618305Y-157755D01*
X1617869Y-160089D01*
X1618305Y-162422D01*
X1619179Y-164172D01*
X1620489Y-165339D01*
X1622017Y-165922D01*
X1623545Y-165630D01*
X1624856Y-164756D01*
X1625729Y-163589D01*
G01X1639299Y-148422D02*
Y-165922D01*
G01X1636242Y-154256D02*
X1642356D01*
G01X1653524Y-158047D02*
X1660511D01*
X1659856Y-156005D01*
X1658764Y-154839D01*
X1657236Y-154256D01*
X1655707Y-154547D01*
X1654397Y-155422D01*
X1653524Y-157464D01*
X1653087Y-159214D01*
Y-160964D01*
X1653524Y-162714D01*
X1654616Y-164464D01*
X1655926Y-165630D01*
X1657454Y-165922D01*
X1658982Y-165339D01*
X1660511Y-163589D01*
G54D27*
X1753465Y536791D03*
X1749528D03*
G54D18*
X42724Y644684D03*
Y644656D03*
Y654684D03*
Y654656D03*
X67724Y644684D03*
Y644656D03*
Y654684D03*
Y654656D03*
X221656Y644656D03*
X196656D03*
X231446Y644756D03*
Y644784D03*
X221656Y644684D03*
X196656D03*
X221656Y654656D03*
X196656D03*
X231446Y654756D03*
Y654784D03*
X221656Y654684D03*
X196656D03*
X256446Y644756D03*
Y644784D03*
Y654756D03*
Y654784D03*
X409240Y644564D03*
X384240D03*
X418914Y644486D03*
Y644514D03*
X409240Y644536D03*
X384240D03*
X409240Y654564D03*
X384240D03*
X418914Y654486D03*
Y654514D03*
X409240Y654536D03*
X384240D03*
X443914Y644486D03*
Y644514D03*
Y654486D03*
Y654514D03*
X596707Y644293D03*
X571707D03*
X596708Y644266D03*
X571708D03*
X596707Y654293D03*
X571707D03*
X596708Y654266D03*
X571708D03*
X606462Y644245D03*
X631462D03*
X606462Y644217D03*
X631462D03*
X606462Y654245D03*
X631462D03*
X606462Y654217D03*
X631462D03*
X912351Y644245D03*
X887351D03*
X912351Y644273D03*
X887351D03*
X912351Y654245D03*
X887351D03*
X912351Y654273D03*
X887351D03*
X922116Y644206D03*
X947116D03*
X922116Y644234D03*
X947116D03*
X922116Y654206D03*
X947116D03*
X922116Y654234D03*
X947116D03*
X1200877Y644262D03*
Y644234D03*
Y654262D03*
Y654234D03*
X1225877Y644262D03*
X1235614Y644236D03*
X1260614D03*
X1235614Y644264D03*
X1260614D03*
X1225877Y644234D03*
Y654262D03*
X1235614Y654236D03*
X1260614D03*
X1235614Y654264D03*
X1260614D03*
X1225877Y654234D03*
X1514375Y644292D03*
Y644264D03*
Y654292D03*
Y654264D03*
X1539375Y644292D03*
Y644264D03*
Y654292D03*
Y654264D03*
G54D19*
X72074Y243282D03*
X65180Y243368D03*
X61800Y243400D03*
X68498Y243368D03*
X49560Y649770D03*
Y644670D03*
X54360D03*
X49560Y649570D03*
Y644670D03*
X54360D03*
X49560Y654670D03*
X54360D03*
X49560D03*
X54360D03*
X214820Y649570D03*
Y644670D03*
X210020D03*
X214820Y649770D03*
Y644670D03*
X210020D03*
X214820Y654670D03*
X210020D03*
X214820D03*
X210020D03*
X238282Y649670D03*
Y644770D03*
X243082D03*
X238282Y649870D03*
Y644770D03*
X243082D03*
X238282Y654770D03*
X243082D03*
X238282D03*
X243082D03*
X402404Y649650D03*
Y644550D03*
X397604D03*
X402404Y649450D03*
Y644550D03*
X397604D03*
X402404Y654550D03*
X397604D03*
X402404D03*
X397604D03*
X425750Y649400D03*
Y644500D03*
X430550D03*
X425750Y649600D03*
Y644500D03*
X430550D03*
X425750Y654500D03*
X430550D03*
X425750D03*
X430550D03*
X589871Y649379D03*
Y644279D03*
X585071D03*
X589872Y649180D03*
Y644280D03*
X585072D03*
X589871Y654279D03*
X585071D03*
X589872Y654280D03*
X585072D03*
X613298Y649331D03*
Y644231D03*
X618098D03*
X613298Y649131D03*
Y644231D03*
X618098D03*
X613298Y654231D03*
X618098D03*
X613298D03*
X618098D03*
X905515Y649159D03*
Y644259D03*
X900715D03*
X905515Y649359D03*
Y644259D03*
X900715D03*
X905515Y654259D03*
X900715D03*
X905515D03*
X900715D03*
X928952Y649120D03*
Y644220D03*
X933752D03*
X928952Y649320D03*
Y644220D03*
X933752D03*
X928952Y654220D03*
X933752D03*
X928952D03*
X933752D03*
X1219041Y649348D03*
Y644248D03*
X1214241D03*
X1219041Y649148D03*
Y644248D03*
X1214241D03*
X1219041Y654248D03*
X1214241D03*
X1219041D03*
X1214241D03*
X1242450Y649150D03*
Y644250D03*
X1247250D03*
X1242450Y649350D03*
Y644250D03*
X1247250D03*
X1242450Y654250D03*
X1247250D03*
X1242450D03*
X1247250D03*
X1527739Y644278D03*
D03*
Y654278D03*
D03*
X1532539Y649378D03*
Y644278D03*
Y649178D03*
Y644278D03*
Y654278D03*
D03*
G54D28*
X1895945Y21654D03*
G54D29*
X1952756Y-14960D03*
Y58268D03*
M02*
